G04 ================== begin FILE IDENTIFICATION RECORD ==================*
G04 Layout Name:  14545-sa.brd*
G04 Film Name:    14545-sa_X_Y*
G04 File Format:  Gerber RS274X*
G04 File Origin:  Cadence Allegro 16.5-S056*
G04 Origin Date:  Fri Aug 01 17:58:04 2014*
G04 *
G04 Layer:  BOARD GEOMETRY/PANEL_DRAWING*
G04 *
G04 Offset:    (0.00 0.00)*
G04 Mirror:    No*
G04 Mode:      Positive*
G04 Rotation:  0*
G04 FullContactRelief:  No*
G04 UndefLineWidth:     6.00*
G04 ================== end FILE IDENTIFICATION RECORD ====================*
%FSLAX35Y35*MOIN*%
%IR0*IPPOS*OFA0.00000B0.00000*MIA0B0*SFA1.00000B1.00000*%
%ADD10C,.006*%
G75*
%LPD*%
G75*
G36*
G01X-224329Y709D02*
X-224565D01*
X-224447Y0D01*
X-224329Y709D01*
G37*
G36*
G01X-224565Y1991417D02*
X-224329D01*
X-224447Y1992126D01*
X-224565Y1991417D01*
G37*
G36*
G01X-78032Y2034201D02*
Y2034437D01*
X-78741Y2034319D01*
X-78032Y2034201D01*
G37*
G36*
G01X275315Y1895715D02*
X282357Y1903401D01*
X279004Y1905465D01*
X275315Y1895715D01*
G37*
G36*
G01X1111495Y2034437D02*
Y2034201D01*
X1112204Y2034319D01*
X1111495Y2034437D01*
G37*
G54D10*
G01X-795028Y-57873D02*
Y2138820D01*
G01X2329578Y-57873D02*
X-795028D01*
G01X-776091Y-38936D02*
Y2119883D01*
G01X2310641Y-38936D02*
X-776091D01*
G01X-787920Y65605D02*
X-787207Y64464D01*
X-786352Y63704D01*
X-785353Y63324D01*
X-784212Y63704D01*
X-783357Y64464D01*
X-782501Y65605D01*
X-782216Y67126D01*
Y74731D01*
G01X-795028Y176946D02*
X-776091D01*
G01X-786779Y290613D02*
X-783357D01*
G01X-785068D02*
Y279206D01*
G01X-786779D02*
X-783357D01*
G01X-795028Y392828D02*
X-776091D01*
G01X-795028D02*
X-776091D01*
G01X-788063Y494898D02*
Y506305D01*
G01X-782073D02*
Y494898D01*
G01Y500601D02*
X-788063D01*
G01X-795028Y608710D02*
X-776091D01*
G01X-795028D02*
X-776091D01*
G01X-784212Y716483D02*
X-781360D01*
Y713061D01*
X-782216Y711920D01*
X-783214Y711160D01*
X-784640Y710780D01*
X-786066Y711160D01*
X-787064Y711920D01*
X-787920Y713061D01*
X-788491Y714392D01*
X-788776Y715913D01*
Y717244D01*
X-788491Y718384D01*
X-787920Y719716D01*
X-787064Y720856D01*
X-786209Y721616D01*
X-785068Y722187D01*
X-784070D01*
X-782929Y721807D01*
X-782073Y721046D01*
G01X-795028Y824592D02*
X-776091D01*
G01X-795028D02*
X-776091D01*
G01X-788156Y926852D02*
Y938259D01*
X-782738D01*
G01X-784734Y932746D02*
X-788156D01*
G01X-795028Y1040474D02*
X-776091D01*
G01X-795028D02*
X-776091D01*
G01X-795028D02*
X-776091D01*
G01X-782216Y1142923D02*
X-787920D01*
Y1154330D01*
X-782216D01*
G01X-784498Y1148817D02*
X-787920D01*
G01X-795028Y1256355D02*
X-776091D01*
G01X-795028D02*
X-776091D01*
G01X-788205Y1358615D02*
Y1370022D01*
X-785353D01*
X-784212Y1369451D01*
X-783357Y1368691D01*
X-782644Y1367551D01*
X-782073Y1366219D01*
X-781931Y1364318D01*
X-782073Y1362417D01*
X-782644Y1361086D01*
X-783357Y1359946D01*
X-784212Y1359185D01*
X-785353Y1358615D01*
X-788205D01*
G01X-795028Y1472237D02*
X-776091D01*
G01X-795028D02*
X-776091D01*
G01X-781931Y1585143D02*
X-782786Y1585714D01*
X-783784Y1586094D01*
X-784925D01*
X-786209Y1585523D01*
X-787207Y1584573D01*
X-787920Y1583432D01*
X-788491Y1581531D01*
X-788633Y1579820D01*
X-788348Y1578109D01*
X-787920Y1576968D01*
X-787064Y1575827D01*
X-786066Y1575067D01*
X-785068Y1574687D01*
X-784070D01*
X-783072Y1575067D01*
X-782216Y1575637D01*
X-781503Y1576398D01*
G01X-795028Y1688119D02*
X-776091D01*
G01X-795028D02*
X-776091D01*
G01X-783927Y1796463D02*
X-783357Y1797033D01*
X-782929Y1797983D01*
X-782644Y1799315D01*
X-782929Y1800455D01*
X-783499Y1801215D01*
X-784498Y1801786D01*
X-788348D01*
Y1790379D01*
X-783642D01*
X-782644Y1791139D01*
X-782073Y1792280D01*
X-781788Y1793611D01*
X-782073Y1794942D01*
X-782929Y1796082D01*
X-783927Y1796463D01*
X-788348D01*
G01X-795028Y1904001D02*
X-776091D01*
G01X-788633Y2006261D02*
X-785068Y2017668D01*
X-781503Y2006261D01*
G01X-782786Y2010253D02*
X-787350D01*
G01X-776091Y2119883D02*
X2310641D01*
G01X-795028Y2138820D02*
X2329578D01*
G01X-658191Y-54086D02*
Y-42679D01*
X-659902Y-44960D01*
G01Y-54086D02*
X-656480D01*
G01X-658191Y2123670D02*
Y2135077D01*
X-659902Y2132796D01*
G01Y2123670D02*
X-656480D01*
G01X-550740Y-38936D02*
Y-57873D01*
G01Y2138820D02*
Y2119883D01*
G01X-443124Y-44580D02*
X-442269Y-43440D01*
X-441271Y-42869D01*
X-440130Y-42679D01*
X-438704Y-43059D01*
X-437706Y-44010D01*
X-437420Y-45150D01*
X-437563Y-46291D01*
X-438133Y-47242D01*
X-440985Y-49143D01*
X-442269Y-50474D01*
X-443124Y-52375D01*
X-443410Y-54086D01*
X-437420D01*
G01X-443124Y2133176D02*
X-442269Y2134316D01*
X-441271Y2134887D01*
X-440130Y2135077D01*
X-438704Y2134697D01*
X-437706Y2133746D01*
X-437420Y2132606D01*
X-437563Y2131465D01*
X-438133Y2130514D01*
X-440985Y2128613D01*
X-442269Y2127282D01*
X-443124Y2125381D01*
X-443410Y2123670D01*
X-437420D01*
G01X-331070Y-38936D02*
Y-57873D01*
G01Y2138820D02*
Y2119883D01*
G01X-241364Y993323D02*
X-240766Y992658D01*
X-240067Y992259D01*
X-239169Y992126D01*
X-238270Y992392D01*
X-237572Y992924D01*
X-237072Y993856D01*
X-236973Y994921D01*
X-237172Y995985D01*
X-237671Y996651D01*
X-238370Y997183D01*
X-239069Y997316D01*
X-239767Y997183D01*
X-240666Y996651D01*
X-240366Y1000111D01*
X-237671D01*
G01X-231184D02*
X-231982Y999845D01*
X-232581Y999179D01*
X-232980Y998381D01*
X-233280Y997316D01*
X-233379Y996118D01*
X-233280Y994921D01*
X-232980Y993856D01*
X-232581Y993057D01*
X-231982Y992392D01*
X-231184Y992126D01*
X-230385Y992392D01*
X-229786Y993057D01*
X-229387Y993856D01*
X-229087Y994921D01*
X-228988Y996118D01*
X-229087Y997316D01*
X-229387Y998381D01*
X-229786Y999179D01*
X-230385Y999845D01*
X-231184Y1000111D01*
G01X-225095Y995453D02*
X-224396Y996385D01*
X-223797Y996917D01*
X-222999Y997183D01*
X-222300Y996917D01*
X-221801Y996385D01*
X-221402Y995586D01*
X-221302Y994655D01*
X-221402Y993856D01*
X-221801Y993057D01*
X-222400Y992392D01*
X-223099Y992126D01*
X-223897Y992392D01*
X-224596Y993190D01*
X-224995Y994388D01*
X-225095Y995719D01*
X-224895Y997449D01*
X-224596Y998381D01*
X-224097Y999312D01*
X-223398Y999978D01*
X-222699Y1000111D01*
X-222001Y999845D01*
X-221502Y999179D01*
G01X-215214Y991860D02*
X-215413Y991993D01*
Y992259D01*
X-215214Y992392D01*
X-215014Y992259D01*
Y991993D01*
X-215214Y991860D01*
G01X-207229Y1000111D02*
X-208027Y999845D01*
X-208626Y999179D01*
X-209025Y998381D01*
X-209325Y997316D01*
X-209424Y996118D01*
X-209325Y994921D01*
X-209025Y993856D01*
X-208626Y993057D01*
X-208027Y992392D01*
X-207229Y992126D01*
X-206430Y992392D01*
X-205831Y993057D01*
X-205432Y993856D01*
X-205132Y994921D01*
X-205033Y996118D01*
X-205132Y997316D01*
X-205432Y998381D01*
X-205831Y999179D01*
X-206430Y999845D01*
X-207229Y1000111D01*
G01X-199244D02*
X-200042Y999845D01*
X-200641Y999179D01*
X-201040Y998381D01*
X-201340Y997316D01*
X-201439Y996118D01*
X-201340Y994921D01*
X-201040Y993856D01*
X-200641Y993057D01*
X-200042Y992392D01*
X-199244Y992126D01*
X-198445Y992392D01*
X-197846Y993057D01*
X-197447Y993856D01*
X-197147Y994921D01*
X-197048Y996118D01*
X-197147Y997316D01*
X-197447Y998381D01*
X-197846Y999179D01*
X-198445Y999845D01*
X-199244Y1000111D01*
G01X-223883Y-51805D02*
X-223028Y-53136D01*
X-221887Y-53896D01*
X-220603Y-54086D01*
X-219462Y-53896D01*
X-218322Y-52946D01*
X-217609Y-51805D01*
X-217466Y-50664D01*
X-217751Y-49333D01*
X-218750Y-48383D01*
X-219748Y-48002D01*
X-221031D01*
G01X-219748D02*
X-218892Y-47432D01*
X-218179Y-46482D01*
X-217894Y-45341D01*
X-218179Y-44200D01*
X-218892Y-43250D01*
X-220176Y-42679D01*
X-221459Y-42869D01*
X-222742Y-43630D01*
G01X-224447Y991772D02*
Y709D01*
G01X321948Y0D02*
X-225156D01*
G01X-224447Y1991417D02*
Y1000354D01*
G01X279694Y1992126D02*
X-225156D01*
G01X-223883Y2125951D02*
X-223028Y2124620D01*
X-221887Y2123860D01*
X-220603Y2123670D01*
X-219462Y2123860D01*
X-218322Y2124810D01*
X-217609Y2125951D01*
X-217466Y2127092D01*
X-217751Y2128423D01*
X-218750Y2129373D01*
X-219748Y2129754D01*
X-221031D01*
G01X-219748D02*
X-218892Y2130324D01*
X-218179Y2131274D01*
X-217894Y2132415D01*
X-218179Y2133556D01*
X-218892Y2134506D01*
X-220176Y2135077D01*
X-221459Y2134887D01*
X-222742Y2134126D01*
G01X-111402Y-38936D02*
Y-57873D01*
G01X-78741Y15000D02*
G03X-63741Y0I15000J0D01*
G01X-78741Y15000D02*
Y120047D01*
G01X-63741Y135047D02*
G03X-78741Y120047I0J-15000D01*
G01Y298866D02*
G03X-63741Y283866I15000J0D01*
G01X-78741Y319646D02*
Y298866D01*
G01X-63741Y334646D02*
G03X-78741Y319646I0J-15000D01*
G01Y908315D02*
G03X-63741Y893315I15000J0D01*
G01X-78741Y908315D02*
Y1104299D01*
G01X-63741Y1119299D02*
G03X-78741Y1104299I0J-15000D01*
G01Y1283118D02*
G03X-63741Y1268118I15000J0D01*
G01X-78741Y1304285D02*
Y1283118D01*
G01X-63741Y1319285D02*
G03X-78741Y1304285I0J-15000D01*
G01Y1892953D02*
G03X-63741Y1877953I15000J0D01*
G01X-78741Y1935285D02*
Y2035027D01*
G01Y1892953D02*
Y1977126D01*
G01X-78032Y2034319D02*
X498004D01*
G01X-63741Y1992126D02*
G03X-78741Y1977126I0J-15000D01*
G01X-111402Y2138820D02*
Y2119883D01*
G01X634Y-54086D02*
Y-42679D01*
X-4642Y-50854D01*
X2488D01*
G01X-34761Y28743D02*
G03I-4292J0D01*
G01X-33266Y56622D02*
X-28266D01*
G01X-30766Y59122D02*
Y54122D01*
G01X-28266Y59122D02*
Y54122D01*
G01X-33266D02*
Y59122D01*
G01X-28266D02*
X-33266D01*
G01Y54122D02*
X-28266D01*
G01X-22766Y48622D02*
Y64622D01*
G01X-38766D02*
X-22766D01*
G01X-38766D02*
Y48622D01*
G01D02*
X-22766D01*
G01X1029527Y0D02*
X3936D01*
G01X-1Y3937D02*
G03X3936Y0I3937J0D01*
G01X-1Y3937D02*
Y140953D01*
G01X-7875Y0D02*
X-63741D01*
G01X-7875Y41772D02*
Y104969D01*
G01Y17252D02*
Y0D01*
G01Y41772D02*
G03X-1I3937J-1D01*
G01Y17213D02*
G03X-7875I-3937J0D01*
G01Y41772D02*
G03X-1I3937J-1D01*
G01Y17213D02*
G03X-7875I-3937J0D01*
G01X-1Y138985D02*
X26771D01*
G01X-9056Y140953D02*
X24802D01*
G01X-9056D02*
Y160244D01*
G01X-1Y140953D02*
Y160244D01*
G01Y140953D02*
Y211614D01*
G01X9842Y149221D02*
X-9056Y148433D01*
G01X14369Y153158D02*
G03I-4527J0D01*
G01X13779D02*
G03I-3937J0D01*
G01X-7875Y129516D02*
Y135047D01*
G01D02*
X-63741D01*
G01X-7875Y129516D02*
G03X-1I3937J0D01*
G01Y104958D02*
G03X-7875I-3937J0D01*
G01Y129516D02*
G03X-1I3937J0D01*
G01Y104958D02*
G03X-7875I-3937J0D01*
G01X-39607Y160244D02*
X-1D01*
G01X-39607Y163394D02*
X-27993D01*
G01X-39607Y258670D02*
Y160244D01*
G01X-33702Y164181D02*
X-39607D01*
G01Y168119D02*
X-9607D01*
G01X-35351Y171193D02*
X-10631Y170918D01*
G01X-36192Y171274D02*
X-35351Y171193D01*
G01X-36192Y175211D02*
X-35351Y175130D01*
G01X-36192Y179148D02*
X-35351Y179067D01*
G01X-36192Y183085D02*
X-35351Y183004D01*
G01X-36192Y172609D02*
X-35341Y172691D01*
G01X-36192Y176546D02*
X-35341Y176628D01*
G01X-36192Y180483D02*
X-35341Y180565D01*
G01X-35351Y172689D02*
X-10631Y172965D01*
G01X-35351Y176626D02*
X-10631Y176902D01*
G01X-35351Y180563D02*
X-10631Y180839D01*
G01X-39607Y170776D02*
X-24509D01*
G01X-35546Y170855D02*
X-1D01*
G01X-39607Y172843D02*
X-27993D01*
G01X-35546Y173059D02*
X-1D01*
G01X-24509Y173138D02*
X-39607D01*
G01Y174713D02*
X-24509D01*
G01X-35546Y174792D02*
X-1D01*
G01X-39607Y175993D02*
X-24844D01*
G01X-35546Y176996D02*
X-1D01*
G01X-24509Y177075D02*
X-39607D01*
G01Y178650D02*
X-24509D01*
G01X-35546Y178729D02*
X-1D01*
G01X-39607Y180717D02*
X-24844D01*
G01X-35546Y180933D02*
X-1D01*
G01X-24509Y181012D02*
X-39607D01*
G01Y182587D02*
X-24509D01*
G01X-35546Y182666D02*
X-1D01*
G01X-27993Y183867D02*
X-39607D01*
G01X-35351Y175130D02*
X-10631Y174855D01*
G01X-35351Y179067D02*
X-10631Y178792D01*
G01X-35351Y183004D02*
X-10631Y182729D01*
G01X-38426Y184949D02*
Y182587D01*
G01Y181012D02*
Y178650D01*
G01Y177075D02*
Y174713D01*
G01Y173138D02*
Y170776D01*
G01X-36812Y214642D02*
Y166572D01*
G01X-36192Y184420D02*
Y183085D01*
G01Y180483D02*
Y179148D01*
G01Y176546D02*
Y175211D01*
G01Y172609D02*
Y171274D01*
G01X-35595Y184477D02*
Y183028D01*
G01Y180540D02*
Y179091D01*
G01Y176603D02*
Y175154D01*
G01Y172666D02*
Y171217D01*
G01X-35546Y183023D02*
Y182587D01*
G01Y181012D02*
Y180545D01*
G01Y175149D02*
Y174713D01*
G01Y177075D02*
Y176608D01*
G01Y179086D02*
Y178650D01*
G01Y171212D02*
Y170776D01*
G01Y173138D02*
Y172671D01*
G01X-35331Y184502D02*
Y183004D01*
G01Y180565D02*
Y179067D01*
G01Y176628D02*
Y175130D01*
G01Y172691D02*
Y171193D01*
G01X-34607Y184870D02*
Y182666D01*
G01Y180933D02*
Y178729D01*
G01Y173059D02*
Y170855D01*
G01Y174792D02*
Y176996D01*
G01X-34136Y184514D02*
Y182991D01*
G01Y180577D02*
Y179054D01*
G01Y176640D02*
Y175117D01*
G01Y172703D02*
Y171180D01*
G01X-33702Y168119D02*
Y164181D01*
G01X-33153Y171169D02*
Y172714D01*
G01Y175106D02*
Y176651D01*
G01Y179043D02*
Y180588D01*
G01Y182980D02*
Y184525D01*
G01X-31995Y184538D02*
Y182967D01*
G01Y180601D02*
Y179030D01*
G01Y176664D02*
Y175093D01*
G01Y172727D02*
Y171156D01*
G01X-31725Y184541D02*
Y182964D01*
G01Y180604D02*
Y179027D01*
G01Y176667D02*
Y175090D01*
G01Y172730D02*
Y171153D01*
G01X-34603Y168119D02*
X-39607Y164615D01*
G01X-36192Y187022D02*
X-35351Y186941D01*
G01X-36192Y190959D02*
X-35351Y190878D01*
G01X-36192Y194896D02*
X-35351Y194815D01*
G01X-36192Y198833D02*
X-35351Y198752D01*
G01X-36192Y202770D02*
X-35351Y202689D01*
G01X-36192Y184420D02*
X-35341Y184502D01*
G01X-35351Y184500D02*
X-10631Y184776D01*
G01X-35351Y188437D02*
X-10631Y188713D01*
G01X-35351Y192374D02*
X-10631Y192650D01*
G01X-35351Y196311D02*
X-10631Y196587D01*
G01X-35351Y200248D02*
X-10631Y200524D01*
G01X-35546Y184870D02*
X-1D01*
G01X-24509Y184949D02*
X-39607D01*
G01Y186524D02*
X-24509D01*
G01X-35546Y186603D02*
X-1D01*
G01X-35546Y188807D02*
X-1D01*
G01X-24509Y188886D02*
X-39607D01*
G01Y190461D02*
X-24509D01*
G01X-35546Y190540D02*
X-1D01*
G01X-35546Y192744D02*
X-1D01*
G01X-24509Y192823D02*
X-39607D01*
G01Y193315D02*
X-27993D01*
G01X-39607Y194398D02*
X-24509D01*
G01X-35546Y194477D02*
X-1D01*
G01X-39607Y196465D02*
X-24844D01*
G01X-35546Y196681D02*
X-1D01*
G01X-24509Y196760D02*
X-39607D01*
G01Y198335D02*
X-24509D01*
G01X-35546Y198414D02*
X-1D01*
G01X-35546Y200619D02*
X-1D01*
G01X-24509Y200697D02*
X-39607D01*
G01Y201189D02*
X-24844D01*
G01X-39607Y202272D02*
X-24509D01*
G01X-35546Y202351D02*
X-1D01*
G01X-35351Y186941D02*
X-10631Y186666D01*
G01X-35351Y190878D02*
X-10631Y190603D01*
G01X-35351Y194815D02*
X-10631Y194540D01*
G01X-35351Y198752D02*
X-10631Y198477D01*
G01X-35351Y202689D02*
X-10631Y202414D01*
G01X-36192Y188357D02*
X-35341Y188439D01*
G01X-36192Y192294D02*
X-35341Y192376D01*
G01X-36192Y196231D02*
X-35341Y196313D01*
G01X-36192Y200168D02*
X-35341Y200250D01*
G01X-36192Y204105D02*
X-35341Y204187D01*
G01X-38426Y204634D02*
Y202272D01*
G01Y200697D02*
Y198335D01*
G01Y196760D02*
Y194398D01*
G01Y188886D02*
Y186524D01*
G01Y192823D02*
Y190461D01*
G01X-36192Y204105D02*
Y202770D01*
G01Y200168D02*
Y198833D01*
G01Y196231D02*
Y194896D01*
G01Y192294D02*
Y190959D01*
G01Y188357D02*
Y187022D01*
G01X-35595Y204162D02*
Y202713D01*
G01Y200225D02*
Y198776D01*
G01Y196288D02*
Y194839D01*
G01Y192351D02*
Y190902D01*
G01Y188414D02*
Y186965D01*
G01X-35546Y198771D02*
Y198335D01*
G01Y200697D02*
Y200230D01*
G01Y202708D02*
Y202272D01*
G01Y194834D02*
Y194398D01*
G01Y196760D02*
Y196293D01*
G01Y188886D02*
Y188419D01*
G01Y190897D02*
Y190461D01*
G01Y192823D02*
Y192356D01*
G01Y186960D02*
Y186524D01*
G01Y184949D02*
Y184482D01*
G01X-35331Y204187D02*
Y202689D01*
G01Y200250D02*
Y198752D01*
G01Y196313D02*
Y194815D01*
G01Y192376D02*
Y190878D01*
G01Y188439D02*
Y186941D01*
G01X-34607Y204556D02*
Y202351D01*
G01Y200619D02*
Y198414D01*
G01Y196681D02*
Y194477D01*
G01Y192744D02*
Y190540D01*
G01Y188807D02*
Y186603D01*
G01X-34136Y204199D02*
Y202676D01*
G01Y200262D02*
Y198739D01*
G01Y196325D02*
Y194802D01*
G01Y192388D02*
Y190865D01*
G01Y188451D02*
Y186928D01*
G01X-33153Y186917D02*
Y188462D01*
G01Y190854D02*
Y192399D01*
G01Y194791D02*
Y196336D01*
G01Y198728D02*
Y200273D01*
G01Y202665D02*
Y204210D01*
G01X-31995Y204223D02*
Y202652D01*
G01Y200286D02*
Y198715D01*
G01Y196349D02*
Y194778D01*
G01Y192412D02*
Y190841D01*
G01Y188475D02*
Y186904D01*
G01X-31725Y204226D02*
Y202649D01*
G01Y200289D02*
Y198712D01*
G01Y196352D02*
Y194775D01*
G01Y192415D02*
Y190838D01*
G01Y188478D02*
Y186901D01*
G01X-36561Y214467D02*
X-39020Y216188D01*
G01X-36192Y206707D02*
X-35351Y206626D01*
G01X-36192Y210644D02*
X-35351Y210563D01*
G01Y204185D02*
X-10631Y204461D01*
G01X-35351Y208122D02*
X-10631Y208398D01*
G01X-35351Y212059D02*
X-10631Y212335D01*
G01X-35351Y223870D02*
X-10631Y224146D01*
G01X-27993Y204339D02*
X-39607D01*
G01X-35546Y204556D02*
X-1D01*
G01X-24509Y204634D02*
X-39607D01*
G01Y206209D02*
X-24509D01*
G01X-35546Y206288D02*
X-1D01*
G01X-35546Y208493D02*
X-1D01*
G01X-24509Y208571D02*
X-39607D01*
G01Y210146D02*
X-24509D01*
G01X-35546Y210225D02*
X-1D01*
G01X-35546Y212430D02*
X-1D01*
G01X-24509Y212508D02*
X-39607D01*
G01Y213788D02*
X-27993D01*
G01X-9607Y213926D02*
X-34845D01*
G01X-1Y214733D02*
X-35434D01*
G01X-39607Y216937D02*
X-24844D01*
G01X-35434Y219733D02*
X-1D01*
G01X-34845Y220737D02*
X-9607D01*
G01X-39607Y221662D02*
X-24844D01*
G01X-39607Y221957D02*
X-24509D01*
G01X-35546Y222036D02*
X-1D01*
G01X-35351Y206626D02*
X-10631Y206351D01*
G01X-35351Y210563D02*
X-10631Y210288D01*
G01X-35351Y222374D02*
X-10631Y222099D01*
G01X-36192Y222456D02*
X-35351Y222374D01*
G01X-36192Y208042D02*
X-35341Y208124D01*
G01X-36192Y211979D02*
X-35341Y212061D01*
G01X-36192Y223790D02*
X-35341Y223872D01*
G01X-38426Y224319D02*
Y221957D01*
G01Y212508D02*
Y210146D01*
G01Y208571D02*
Y206209D01*
G01X-36812Y251571D02*
Y220020D01*
G01X-36192Y223790D02*
Y222456D01*
G01Y211979D02*
Y210644D01*
G01Y208042D02*
Y206707D01*
G01X-35595Y223847D02*
Y222398D01*
G01Y212036D02*
Y210587D01*
G01Y208099D02*
Y206650D01*
G01X-35546Y222393D02*
Y221957D01*
G01Y224319D02*
Y223852D01*
G01Y212508D02*
Y212041D01*
G01Y210582D02*
Y210146D01*
G01Y208571D02*
Y208104D01*
G01Y204634D02*
Y204167D01*
G01Y206645D02*
Y206209D01*
G01X-35434Y214733D02*
Y219733D01*
G01X-35331Y223872D02*
Y222374D01*
G01Y212061D02*
Y210563D01*
G01Y208124D02*
Y206626D01*
G01X-34607Y212430D02*
Y210225D01*
G01Y208493D02*
Y206288D01*
G01Y222036D02*
Y224241D01*
G01X-34136Y223884D02*
Y222361D01*
G01Y212073D02*
Y210550D01*
G01Y208136D02*
Y206613D01*
G01X-33153Y206602D02*
Y208147D01*
G01Y210539D02*
Y212084D01*
G01Y222350D02*
Y223895D01*
G01X-31995Y223908D02*
Y222337D01*
G01Y212097D02*
Y210526D01*
G01Y208160D02*
Y206589D01*
G01X-31725Y223911D02*
Y222334D01*
G01Y212100D02*
Y210523D01*
G01Y208163D02*
Y206586D01*
G01X-39020Y218474D02*
X-36561Y220195D01*
G01X-34845Y220737D02*
G03X-36561Y220195I1J-2992D01*
G01Y214467D02*
G03X-34845Y213926I1716J2451D01*
G01X-39020Y218474D02*
G03X-39607Y217345I791J-1128D01*
G01Y217317D02*
G03X-39020Y216188I1378J-1D01*
G01X-35351Y227807D02*
X-10631Y228083D01*
G01X-35351Y231744D02*
X-10631Y232020D01*
G01X-35546Y224241D02*
X-1D01*
G01X-24509Y224319D02*
X-39607D01*
G01X-27993Y224811D02*
X-39607D01*
G01Y225894D02*
X-24509D01*
G01X-35546Y225973D02*
X-1D01*
G01X-35546Y228178D02*
X-1D01*
G01X-24509Y228256D02*
X-39607D01*
G01Y229831D02*
X-24509D01*
G01X-35546Y229910D02*
X-1D01*
G01X-35546Y232115D02*
X-1D01*
G01X-24509Y232193D02*
X-39607D01*
G01X-35351Y226311D02*
X-10631Y226036D01*
G01X-35351Y230248D02*
X-10631Y229973D01*
G01X-36192Y226393D02*
X-35351Y226311D01*
G01X-36192Y230330D02*
X-35351Y230248D01*
G01X-36192Y227727D02*
X-35341Y227809D01*
G01X-36192Y231664D02*
X-35341Y231746D01*
G01X-38426Y232193D02*
Y229831D01*
G01Y228256D02*
Y225894D01*
G01X-36192Y231664D02*
Y230330D01*
G01Y227727D02*
Y226393D01*
G01X-35595Y231721D02*
Y230272D01*
G01Y227784D02*
Y226335D01*
G01X-35546Y232193D02*
Y231726D01*
G01Y228256D02*
Y227789D01*
G01Y230267D02*
Y229831D01*
G01Y226330D02*
Y225894D01*
G01X-35331Y231746D02*
Y230248D01*
G01Y227809D02*
Y226311D01*
G01X-34607Y228178D02*
Y225973D01*
G01Y232115D02*
Y229910D01*
G01X-34136Y231758D02*
Y230235D01*
G01Y227821D02*
Y226298D01*
G01X-33153Y226287D02*
Y227832D01*
G01Y230224D02*
Y231769D01*
G01X-31995Y231782D02*
Y230211D01*
G01Y227845D02*
Y226274D01*
G01X-31725Y231785D02*
Y230208D01*
G01Y227848D02*
Y226271D01*
G01X-27993Y175993D02*
Y160244D01*
G01X-24844D02*
Y175993D01*
G01X-12993Y170540D02*
X-1D01*
G01Y173374D02*
X-12993D01*
G01Y174477D02*
X-1D01*
G01Y177311D02*
X-12993D01*
G01Y178414D02*
X-1D01*
G01Y181248D02*
X-12993D01*
G01Y182351D02*
X-1D01*
G01X-27993Y180717D02*
Y196465D01*
G01X-27265Y184949D02*
Y182587D01*
G01Y181012D02*
Y178650D01*
G01Y177075D02*
Y174713D01*
G01Y173138D02*
Y170776D01*
G01X-26511Y184599D02*
Y182906D01*
G01Y180662D02*
Y178969D01*
G01Y176725D02*
Y175032D01*
G01Y172788D02*
Y171095D01*
G01X-26242Y171092D02*
Y172791D01*
G01Y175029D02*
Y176728D01*
G01Y178966D02*
Y180665D01*
G01Y182903D02*
Y184602D01*
G01X-24844Y180717D02*
Y196465D01*
G01X-24509Y184949D02*
Y182587D01*
G01Y177075D02*
Y174713D01*
G01Y181012D02*
Y178650D01*
G01Y173138D02*
Y170776D01*
G01X-23998Y184627D02*
Y182878D01*
G01Y180690D02*
Y178941D01*
G01Y176753D02*
Y175004D01*
G01Y172816D02*
Y171067D01*
G01X-23519Y171061D02*
Y172822D01*
G01Y174998D02*
Y176759D01*
G01Y178935D02*
Y180696D01*
G01Y182872D02*
Y184633D01*
G01X-12993Y181248D02*
Y180933D01*
G01Y182666D02*
Y182351D01*
G01Y177311D02*
Y176996D01*
G01Y174792D02*
Y174477D01*
G01Y178729D02*
Y178414D01*
G01Y173374D02*
Y173059D01*
G01Y170855D02*
Y170540D01*
G01X-12445Y170938D02*
Y172945D01*
G01Y174875D02*
Y176882D01*
G01Y178812D02*
Y180819D01*
G01Y182749D02*
Y184756D01*
G01X-11967Y184761D02*
Y182744D01*
G01Y180824D02*
Y178807D01*
G01Y176887D02*
Y174870D01*
G01Y172950D02*
Y170933D01*
G01X-1Y185185D02*
X-12993D01*
G01Y186288D02*
X-1D01*
G01Y189122D02*
X-12993D01*
G01Y190225D02*
X-1D01*
G01Y193059D02*
X-12993D01*
G01Y194162D02*
X-1D01*
G01Y196996D02*
X-12993D01*
G01Y198099D02*
X-1D01*
G01Y200933D02*
X-12993D01*
G01Y202036D02*
X-1D01*
G01X-27993Y201189D02*
Y216937D01*
G01X-27265Y204634D02*
Y202272D01*
G01Y200697D02*
Y198335D01*
G01Y196760D02*
Y194398D01*
G01Y188886D02*
Y186524D01*
G01Y192823D02*
Y190461D01*
G01X-26511Y204284D02*
Y202591D01*
G01Y200347D02*
Y198654D01*
G01Y196410D02*
Y194717D01*
G01Y192473D02*
Y190780D01*
G01Y188536D02*
Y186843D01*
G01X-26242Y186840D02*
Y188539D01*
G01Y190777D02*
Y192476D01*
G01Y194714D02*
Y196413D01*
G01Y198651D02*
Y200350D01*
G01Y202588D02*
Y204287D01*
G01X-24844Y201189D02*
Y216937D01*
G01X-24509Y204634D02*
Y202272D01*
G01Y200697D02*
Y198335D01*
G01Y196760D02*
Y194398D01*
G01Y192823D02*
Y190461D01*
G01Y188886D02*
Y186524D01*
G01X-23998Y204312D02*
Y202563D01*
G01Y200375D02*
Y198626D01*
G01Y196438D02*
Y194689D01*
G01Y192501D02*
Y190752D01*
G01Y188564D02*
Y186815D01*
G01X-23519Y186809D02*
Y188570D01*
G01Y190746D02*
Y192507D01*
G01Y194683D02*
Y196444D01*
G01Y198620D02*
Y200381D01*
G01Y202557D02*
Y204318D01*
G01X-12993Y202351D02*
Y202036D01*
G01Y198414D02*
Y198099D01*
G01Y200933D02*
Y200619D01*
G01Y194477D02*
Y194162D01*
G01Y196996D02*
Y196681D01*
G01Y189122D02*
Y188807D01*
G01Y190540D02*
Y190225D01*
G01Y193059D02*
Y192744D01*
G01Y185185D02*
Y184870D01*
G01Y186603D02*
Y186288D01*
G01X-12445Y186686D02*
Y188693D01*
G01Y190623D02*
Y192630D01*
G01Y194560D02*
Y196567D01*
G01Y198497D02*
Y200504D01*
G01Y202434D02*
Y204441D01*
G01X-11967Y204446D02*
Y202429D01*
G01Y200509D02*
Y198492D01*
G01Y196572D02*
Y194555D01*
G01Y188698D02*
Y186681D01*
G01Y192635D02*
Y190618D01*
G01X-1Y204870D02*
X-12993D01*
G01Y205973D02*
X-1D01*
G01Y208807D02*
X-12993D01*
G01Y209910D02*
X-1D01*
G01Y212744D02*
X-12993D01*
G01Y221721D02*
X-1D01*
G01X-27993Y221662D02*
Y237410D01*
G01X-27265Y224319D02*
Y221957D01*
G01Y212508D02*
Y210146D01*
G01Y208571D02*
Y206209D01*
G01X-26511Y223969D02*
Y222276D01*
G01Y212158D02*
Y210465D01*
G01Y208221D02*
Y206528D01*
G01X-26242Y206525D02*
Y208224D01*
G01Y210462D02*
Y212161D01*
G01Y222273D02*
Y223972D01*
G01X-24844Y221662D02*
Y237410D01*
G01X-24509Y224319D02*
Y221957D01*
G01Y212508D02*
Y210146D01*
G01Y208571D02*
Y206209D01*
G01X-23998Y223997D02*
Y222248D01*
G01Y212186D02*
Y210437D01*
G01Y208249D02*
Y206500D01*
G01X-23519Y206494D02*
Y208255D01*
G01Y210431D02*
Y212192D01*
G01Y222243D02*
Y224003D01*
G01X-12993Y222036D02*
Y221721D01*
G01Y212744D02*
Y212430D01*
G01Y210225D02*
Y209910D01*
G01Y208807D02*
Y208493D01*
G01Y206288D02*
Y205973D01*
G01Y204870D02*
Y204556D01*
G01X-12445Y206371D02*
Y208378D01*
G01Y210308D02*
Y212315D01*
G01Y222119D02*
Y224126D01*
G01X-11967Y208383D02*
Y206366D01*
G01Y224131D02*
Y222114D01*
G01Y212320D02*
Y210303D01*
G01X-1Y224556D02*
X-12993D01*
G01Y225658D02*
X-1D01*
G01Y228493D02*
X-12993D01*
G01Y229595D02*
X-1D01*
G01X-27265Y232193D02*
Y229831D01*
G01Y228256D02*
Y225894D01*
G01X-26511Y231843D02*
Y230150D01*
G01Y227906D02*
Y226213D01*
G01X-26242Y226210D02*
Y227909D01*
G01Y230147D02*
Y231846D01*
G01X-24509Y232193D02*
Y229831D01*
G01Y228256D02*
Y225894D01*
G01X-23998Y231871D02*
Y230122D01*
G01Y227934D02*
Y226185D01*
G01X-23519Y226180D02*
Y227940D01*
G01Y230117D02*
Y231877D01*
G01X-12993Y232430D02*
Y232115D01*
G01Y229910D02*
Y229595D01*
G01Y228493D02*
Y228178D01*
G01Y225973D02*
Y225658D01*
G01Y224556D02*
Y224241D01*
G01X-12445Y226056D02*
Y228063D01*
G01Y229993D02*
Y232000D01*
G01X-11967Y232006D02*
Y229988D01*
G01Y228069D02*
Y226051D01*
G01X-9056Y157882D02*
X9842Y157095D01*
G01X-1Y160244D02*
Y258670D01*
G01X-4259Y170721D02*
X-3582Y170540D01*
G01X-4259Y174658D02*
X-3582Y174477D01*
G01X-4259Y178595D02*
X-3582Y178414D01*
G01X-4259Y182532D02*
X-3582Y182351D01*
G01X-10631Y170918D02*
X-9844Y170563D01*
G01X-10631Y174855D02*
X-9844Y174500D01*
G01X-10631Y178792D02*
X-9844Y178437D01*
G01X-10631Y182729D02*
X-9844Y182374D01*
G01X8854Y172617D02*
X8385Y173011D01*
G01X24802Y166544D02*
X-1D01*
G01X-6545Y170540D02*
X-6694Y170563D01*
G01X-6545Y174477D02*
X-6694Y174500D01*
G01X-6545Y178414D02*
X-6694Y178437D01*
G01X-6545Y182351D02*
X-6694Y182374D01*
G01X-2197Y170878D02*
X-2001Y170540D01*
G01X-3151Y173004D02*
X-3364Y173374D01*
G01X-2197Y174815D02*
X-2001Y174477D01*
G01X-3151Y176941D02*
X-3364Y177311D01*
G01X-2197Y178752D02*
X-2001Y178414D01*
G01X-3151Y180878D02*
X-3364Y181248D01*
G01X-2197Y182689D02*
X-2001Y182351D01*
G01X11534Y169664D02*
X8385D01*
G01X8787Y170058D02*
X9725D01*
G01X-9844Y170563D02*
X-6694D01*
G01X-4725Y170721D02*
X-4259D01*
G01X-3151Y170878D02*
X-2197D01*
G01X-4725Y171154D02*
X-6694D01*
G01X9000Y171272D02*
X-1D01*
G01D02*
X-985D01*
G01X-1Y172611D02*
X9000D01*
G01X-985D02*
X-1D01*
G01X-4725Y172729D02*
X-6694D01*
G01X-3151Y173004D02*
X-2197D01*
G01X-4259Y173162D02*
X-4725D01*
G01X-6694Y173319D02*
X-9844D01*
G01X8385Y173404D02*
X11534D01*
G01X-9844Y174500D02*
X-6694D01*
G01X-4725Y174658D02*
X-4259D01*
G01X-3151Y174815D02*
X-2197D01*
G01X-4725Y175091D02*
X-6694D01*
G01X9000Y175209D02*
X-1D01*
G01D02*
X-985D01*
G01X-1Y176548D02*
X9000D01*
G01X-985D02*
X-1D01*
G01X-4725Y176666D02*
X-6694D01*
G01X-3151Y176941D02*
X-2197D01*
G01X-4259Y177099D02*
X-4725D01*
G01X-6694Y177256D02*
X-9844D01*
G01Y178437D02*
X-6694D01*
G01X-4725Y178595D02*
X-4259D01*
G01X-3151Y178752D02*
X-2197D01*
G01X-4725Y179028D02*
X-6694D01*
G01X9000Y179146D02*
X-1D01*
G01D02*
X-985D01*
G01X-1Y180485D02*
X9000D01*
G01X-985D02*
X-1D01*
G01X-4725Y180603D02*
X-6694D01*
G01X-3151Y180878D02*
X-2197D01*
G01X-4259Y181036D02*
X-4725D01*
G01X-6694Y181193D02*
X-9844D01*
G01Y182374D02*
X-6694D01*
G01X-4725Y182532D02*
X-4259D01*
G01X-3151Y182689D02*
X-2197D01*
G01X-4725Y182965D02*
X-6694D01*
G01X9000Y183083D02*
X-1D01*
G01D02*
X-985D01*
G01X-6351Y173374D02*
X-6694Y173319D01*
G01X-6351Y177311D02*
X-6694Y177256D01*
G01X-6351Y181248D02*
X-6694Y181193D01*
G01X-3467Y173374D02*
X-4259Y173162D01*
G01X-3467Y177311D02*
X-4259Y177099D01*
G01X-3467Y181248D02*
X-4259Y181036D01*
G01X-10531Y184821D02*
Y182684D01*
G01Y180884D02*
Y178747D01*
G01Y176947D02*
Y174810D01*
G01Y173010D02*
Y170873D01*
G01X-9607Y168119D02*
Y213926D01*
G01X-6694Y181193D02*
Y180603D01*
G01Y182965D02*
Y182374D01*
G01Y175091D02*
Y174500D01*
G01Y177256D02*
Y176666D01*
G01Y179028D02*
Y178437D01*
G01Y171154D02*
Y170563D01*
G01Y173319D02*
Y172729D01*
G01X-6038Y181248D02*
Y180933D01*
G01Y182666D02*
Y182351D01*
G01Y177311D02*
Y176996D01*
G01Y174792D02*
Y174477D01*
G01Y178729D02*
Y178414D01*
G01Y173374D02*
Y173059D01*
G01Y170855D02*
Y170540D01*
G01X-4725Y172729D02*
Y173374D01*
G01Y170540D02*
Y171154D01*
G01Y176666D02*
Y177311D01*
G01Y174477D02*
Y175091D01*
G01Y178414D02*
Y179028D01*
G01Y180603D02*
Y181248D01*
G01Y182351D02*
Y182965D01*
G01X-3757Y184870D02*
Y182666D01*
G01Y180933D02*
Y178729D01*
G01Y176996D02*
Y174792D01*
G01Y173059D02*
Y170855D01*
G01X-2521Y184870D02*
Y182666D01*
G01Y180933D02*
Y178729D01*
G01Y176996D02*
Y174792D01*
G01Y173059D02*
Y170855D01*
G01X-2251Y185185D02*
Y182351D01*
G01Y177311D02*
Y174477D01*
G01Y181248D02*
Y178414D01*
G01Y173374D02*
Y170540D01*
G01X-985Y184422D02*
Y183083D01*
G01Y180485D02*
Y179146D01*
G01Y176548D02*
Y175209D01*
G01Y172611D02*
Y171272D01*
G01X196Y184422D02*
Y183083D01*
G01Y180485D02*
Y179146D01*
G01Y176548D02*
Y175209D01*
G01Y172611D02*
Y171272D01*
G01X8385Y169664D02*
Y171239D01*
G01Y173011D02*
Y173404D01*
G01X8787Y171305D02*
Y170058D01*
G01X8385Y171239D02*
X8452Y171567D01*
G01X8854Y171502D02*
X8787Y171305D01*
G01X-3346Y182351D02*
X-3151Y182689D01*
G01X-1983Y181248D02*
X-2197Y180878D01*
G01X-3346Y178414D02*
X-3151Y178752D01*
G01X-1983Y177311D02*
X-2197Y176941D01*
G01X-3346Y174477D02*
X-3151Y174815D01*
G01X-1983Y173374D02*
X-2197Y173004D01*
G01X-3346Y170540D02*
X-3151Y170878D01*
G01X8452Y171567D02*
X8653Y171830D01*
G01D02*
X8921Y172026D01*
G01X-10631Y180839D02*
X-9844Y181193D01*
G01X-10631Y176902D02*
X-9844Y177256D01*
G01X-10631Y172965D02*
X-9844Y173319D01*
G01X-4259Y186469D02*
X-3582Y186288D01*
G01X-4259Y190406D02*
X-3582Y190225D01*
G01X-4259Y194343D02*
X-3582Y194162D01*
G01X-4259Y198280D02*
X-3582Y198099D01*
G01X-10631Y186666D02*
X-9844Y186311D01*
G01X-10631Y190603D02*
X-9844Y190248D01*
G01X-10631Y194540D02*
X-9844Y194185D01*
G01X-10631Y198477D02*
X-9844Y198122D01*
G01X-10631Y202414D02*
X-9844Y202059D01*
G01X-6545Y186288D02*
X-6694Y186311D01*
G01X-6545Y190225D02*
X-6694Y190248D01*
G01X-6545Y194162D02*
X-6694Y194185D01*
G01X-6545Y198099D02*
X-6694Y198122D01*
G01X-6545Y202036D02*
X-6694Y202059D01*
G01X-4259Y202217D02*
X-3582Y202036D01*
G01X-3151Y184815D02*
X-3364Y185185D01*
G01X-2197Y186626D02*
X-2001Y186288D01*
G01X-3151Y188752D02*
X-3364Y189122D01*
G01X-2197Y190563D02*
X-2001Y190225D01*
G01X-3151Y192689D02*
X-3364Y193059D01*
G01X-2197Y194500D02*
X-2001Y194162D01*
G01X-3151Y196626D02*
X-3364Y196996D01*
G01X-2197Y198437D02*
X-2001Y198099D01*
G01X-3151Y200563D02*
X-3364Y200933D01*
G01X-2197Y202374D02*
X-2001Y202036D01*
G01X-1Y184422D02*
X9000D01*
G01X-985D02*
X-1D01*
G01X-4725Y184540D02*
X-6694D01*
G01X-3151Y184815D02*
X-2197D01*
G01X-4259Y184973D02*
X-4725D01*
G01X-6694Y185130D02*
X-9844D01*
G01Y186311D02*
X-6694D01*
G01X-4725Y186469D02*
X-4259D01*
G01X-3151Y186626D02*
X-2197D01*
G01X-4725Y186902D02*
X-6694D01*
G01X9000Y187020D02*
X-1D01*
G01D02*
X-985D01*
G01X-1Y188359D02*
X9000D01*
G01X-985D02*
X-1D01*
G01X-4725Y188477D02*
X-6694D01*
G01X-3151Y188752D02*
X-2197D01*
G01X-4259Y188910D02*
X-4725D01*
G01X-6694Y189067D02*
X-9844D01*
G01Y190248D02*
X-6694D01*
G01X-4725Y190406D02*
X-4259D01*
G01X-3151Y190563D02*
X-2197D01*
G01X-4725Y190839D02*
X-6694D01*
G01X9000Y190957D02*
X-1D01*
G01D02*
X-985D01*
G01X-1Y192296D02*
X9000D01*
G01X-985D02*
X-1D01*
G01X-4725Y192414D02*
X-6694D01*
G01X-3151Y192689D02*
X-2197D01*
G01X-4259Y192847D02*
X-4725D01*
G01X-6694Y193004D02*
X-9844D01*
G01Y194185D02*
X-6694D01*
G01X-4725Y194343D02*
X-4259D01*
G01X-3151Y194500D02*
X-2197D01*
G01X-4725Y194776D02*
X-6694D01*
G01X9000Y194894D02*
X-1D01*
G01D02*
X-985D01*
G01X-1Y196233D02*
X9000D01*
G01X-985D02*
X-1D01*
G01X-4725Y196351D02*
X-6694D01*
G01X-3151Y196626D02*
X-2197D01*
G01X-4259Y196784D02*
X-4725D01*
G01X-6694Y196941D02*
X-9844D01*
G01Y198122D02*
X-6694D01*
G01X-4725Y198280D02*
X-4259D01*
G01X-3151Y198437D02*
X-2197D01*
G01X-4725Y198713D02*
X-6694D01*
G01X9000Y198831D02*
X-1D01*
G01D02*
X-985D01*
G01X-1Y200170D02*
X9000D01*
G01X-985D02*
X-1D01*
G01X-4725Y200288D02*
X-6694D01*
G01X-3151Y200563D02*
X-2197D01*
G01X-4259Y200721D02*
X-4725D01*
G01X-6694Y200878D02*
X-9844D01*
G01Y202059D02*
X-6694D01*
G01X-4725Y202217D02*
X-4259D01*
G01X-3151Y202374D02*
X-2197D01*
G01X-4725Y202650D02*
X-6694D01*
G01X9000Y202768D02*
X-1D01*
G01D02*
X-985D01*
G01X-1Y204107D02*
X9000D01*
G01X-985D02*
X-1D01*
G01X-6351Y185185D02*
X-6694Y185130D01*
G01X-6351Y189122D02*
X-6694Y189067D01*
G01X-6351Y193059D02*
X-6694Y193004D01*
G01X-6351Y196996D02*
X-6694Y196941D01*
G01X-6351Y200933D02*
X-6694Y200878D01*
G01X-3467Y185185D02*
X-4259Y184973D01*
G01X-3467Y189122D02*
X-4259Y188910D01*
G01X-3467Y193059D02*
X-4259Y192847D01*
G01X-3467Y196996D02*
X-4259Y196784D01*
G01X-3467Y200933D02*
X-4259Y200721D01*
G01X-10531Y204506D02*
Y202369D01*
G01Y200569D02*
Y198432D01*
G01Y196632D02*
Y194495D01*
G01Y188758D02*
Y186621D01*
G01Y192695D02*
Y190558D01*
G01X-6694Y202650D02*
Y202059D01*
G01Y200878D02*
Y200288D01*
G01Y198713D02*
Y198122D01*
G01Y196941D02*
Y196351D01*
G01Y194776D02*
Y194185D01*
G01Y189067D02*
Y188477D01*
G01Y193004D02*
Y192414D01*
G01Y190839D02*
Y190248D01*
G01Y185130D02*
Y184540D01*
G01Y186902D02*
Y186311D01*
G01X-6038Y198414D02*
Y198099D01*
G01Y202351D02*
Y202036D01*
G01Y200933D02*
Y200619D01*
G01Y194477D02*
Y194162D01*
G01Y196996D02*
Y196681D01*
G01Y189122D02*
Y188807D01*
G01Y190540D02*
Y190225D01*
G01Y193059D02*
Y192744D01*
G01Y185185D02*
Y184870D01*
G01Y186603D02*
Y186288D01*
G01X-4725Y184540D02*
Y185185D01*
G01Y186288D02*
Y186902D01*
G01Y188477D02*
Y189122D01*
G01Y190225D02*
Y190839D01*
G01Y192414D02*
Y193059D01*
G01Y194162D02*
Y194776D01*
G01Y196351D02*
Y196996D01*
G01Y198099D02*
Y198713D01*
G01Y202036D02*
Y202650D01*
G01Y200288D02*
Y200933D01*
G01X-3757Y204556D02*
Y202351D01*
G01Y200619D02*
Y198414D01*
G01Y196681D02*
Y194477D01*
G01Y188807D02*
Y186603D01*
G01Y192744D02*
Y190540D01*
G01X-2521Y204556D02*
Y202351D01*
G01Y200619D02*
Y198414D01*
G01Y196681D02*
Y194477D01*
G01Y192744D02*
Y190540D01*
G01Y188807D02*
Y186603D01*
G01X-2251Y204870D02*
Y202036D01*
G01Y200933D02*
Y198099D01*
G01Y196996D02*
Y194162D01*
G01Y193059D02*
Y190225D01*
G01Y189122D02*
Y186288D01*
G01X-985Y204107D02*
Y202768D01*
G01Y200170D02*
Y198831D01*
G01Y196233D02*
Y194894D01*
G01Y192296D02*
Y190957D01*
G01Y188359D02*
Y187020D01*
G01X196Y204107D02*
Y202768D01*
G01Y200170D02*
Y198831D01*
G01Y196233D02*
Y194894D01*
G01Y192296D02*
Y190957D01*
G01Y188359D02*
Y187020D01*
G01X-3346Y202036D02*
X-3151Y202374D01*
G01X-1983Y200933D02*
X-2197Y200563D01*
G01X-3346Y198099D02*
X-3151Y198437D01*
G01X-1983Y196996D02*
X-2197Y196626D01*
G01X-3346Y194162D02*
X-3151Y194500D01*
G01X-1983Y193059D02*
X-2197Y192689D01*
G01X-3346Y190225D02*
X-3151Y190563D01*
G01X-1983Y189122D02*
X-2197Y188752D01*
G01X-3346Y186288D02*
X-3151Y186626D01*
G01X-1983Y185185D02*
X-2197Y184815D01*
G01X-10631Y200524D02*
X-9844Y200878D01*
G01X-10631Y196587D02*
X-9844Y196941D01*
G01X-10631Y192650D02*
X-9844Y193004D01*
G01X-10631Y188713D02*
X-9844Y189067D01*
G01X-10631Y184776D02*
X-9844Y185130D01*
G01X-10631Y206351D02*
X-9844Y205996D01*
G01X-10631Y210288D02*
X-9844Y209933D01*
G01X-10631Y222099D02*
X-9844Y221744D01*
G01X387Y222644D02*
X-1Y223031D01*
G01X1968Y221063D02*
X387Y222644D01*
G01X-6545Y205973D02*
X-6694Y205996D01*
G01X-6545Y209910D02*
X-6694Y209933D01*
G01X-6545Y221721D02*
X-6694Y221744D01*
G01X-4259Y206154D02*
X-3582Y205973D01*
G01X-4259Y210091D02*
X-3582Y209910D01*
G01X-4259Y221902D02*
X-3582Y221721D01*
G01X-3151Y204500D02*
X-3364Y204870D01*
G01X-2197Y206311D02*
X-2001Y205973D01*
G01X-3151Y208437D02*
X-3364Y208807D01*
G01X-2197Y210248D02*
X-2001Y209910D01*
G01X-3151Y212374D02*
X-3364Y212744D01*
G01X-2197Y222059D02*
X-2001Y221721D01*
G01X-3151Y224185D02*
X-3364Y224556D01*
G01X-4725Y204225D02*
X-6694D01*
G01X-3151Y204500D02*
X-2197D01*
G01X-4259Y204658D02*
X-4725D01*
G01X-6694Y204815D02*
X-9844D01*
G01Y205996D02*
X-6694D01*
G01X-4725Y206154D02*
X-4259D01*
G01X-3151Y206311D02*
X-2197D01*
G01X-4725Y206587D02*
X-6694D01*
G01X9000Y206705D02*
X-1D01*
G01D02*
X-985D01*
G01X-1Y208044D02*
X9000D01*
G01X-985D02*
X-1D01*
G01X-4725Y208162D02*
X-6694D01*
G01X-3151Y208437D02*
X-2197D01*
G01X-4259Y208595D02*
X-4725D01*
G01X-6694Y208752D02*
X-9844D01*
G01Y209933D02*
X-6694D01*
G01X-4725Y210091D02*
X-4259D01*
G01X-3151Y210248D02*
X-2197D01*
G01X-4725Y210524D02*
X-6694D01*
G01X9000Y210642D02*
X-1D01*
G01D02*
X-985D01*
G01X-1Y211981D02*
X9000D01*
G01X-985D02*
X-1D01*
G01X-4725Y212099D02*
X-6694D01*
G01X-3151Y212374D02*
X-2197D01*
G01X-4259Y212532D02*
X-4725D01*
G01X-6694Y212689D02*
X-9844D01*
G01X1968Y213583D02*
X19881D01*
G01X-1Y213837D02*
X15550D01*
G01X-1Y220845D02*
X15550D01*
G01X19881Y221063D02*
X1968D01*
G01X-9844Y221744D02*
X-6694D01*
G01X-4725Y221902D02*
X-4259D01*
G01X-3151Y222059D02*
X-2197D01*
G01X-4725Y222335D02*
X-6694D01*
G01X9000Y222453D02*
X-1D01*
G01D02*
X-985D01*
G01X-1Y223792D02*
X9000D01*
G01X-985D02*
X-1D01*
G01X-4725Y223910D02*
X-6694D01*
G01X-3151Y224185D02*
X-2197D01*
G01X-6351Y204870D02*
X-6694Y204815D01*
G01X-6351Y208807D02*
X-6694Y208752D01*
G01X-6351Y212744D02*
X-6694Y212689D01*
G01X-3467Y204870D02*
X-4259Y204658D01*
G01X-3467Y208807D02*
X-4259Y208595D01*
G01X-3467Y212744D02*
X-4259Y212532D01*
G01X-10531Y224191D02*
Y222054D01*
G01Y212380D02*
Y210243D01*
G01Y208443D02*
Y206306D01*
G01X-9607Y220737D02*
Y250855D01*
G01X-6694Y224500D02*
Y223910D01*
G01Y222335D02*
Y221744D01*
G01Y212689D02*
Y212099D01*
G01Y210524D02*
Y209933D01*
G01Y208752D02*
Y208162D01*
G01Y206587D02*
Y205996D01*
G01Y204815D02*
Y204225D01*
G01X-6038Y222036D02*
Y221721D01*
G01Y212744D02*
Y212430D01*
G01Y210225D02*
Y209910D01*
G01Y208807D02*
Y208493D01*
G01Y206288D02*
Y205973D01*
G01Y204870D02*
Y204556D01*
G01X-4725Y205973D02*
Y206587D01*
G01Y204225D02*
Y204870D01*
G01Y209910D02*
Y210524D01*
G01Y208162D02*
Y208807D01*
G01Y212099D02*
Y212744D01*
G01Y221721D02*
Y222335D01*
G01Y223910D02*
Y224556D01*
G01X-3757Y224241D02*
Y222036D01*
G01Y212430D02*
Y210225D01*
G01Y208493D02*
Y206288D01*
G01X-2521Y224241D02*
Y222036D01*
G01Y212430D02*
Y210225D01*
G01Y208493D02*
Y206288D01*
G01X-2251Y224556D02*
Y221721D01*
G01Y212744D02*
Y209910D01*
G01Y208807D02*
Y205973D01*
G01X-985Y223792D02*
Y222453D01*
G01Y208044D02*
Y206705D01*
G01Y211981D02*
Y210642D01*
G01X-1Y223031D02*
Y277961D01*
G01X196Y223792D02*
Y222453D01*
G01Y211981D02*
Y210642D01*
G01Y208044D02*
Y206705D01*
G01X-1983Y224556D02*
X-2197Y224185D01*
G01X-3346Y221721D02*
X-3151Y222059D01*
G01X-1983Y212744D02*
X-2197Y212374D01*
G01X-3346Y209910D02*
X-3151Y210248D01*
G01X-1983Y208807D02*
X-2197Y208437D01*
G01X-3346Y205973D02*
X-3151Y206311D01*
G01X-1983Y204870D02*
X-2197Y204500D01*
G01X-1Y211614D02*
X281Y211896D01*
G01D02*
X1968Y213583D01*
G01X-10631Y224146D02*
X-9844Y224500D01*
G01X-10631Y212335D02*
X-9844Y212689D01*
G01X-10631Y208398D02*
X-9844Y208752D01*
G01X-10631Y204461D02*
X-9844Y204815D01*
G01X-10631Y226036D02*
X-9844Y225681D01*
G01X-10631Y229973D02*
X-9844Y229619D01*
G01X-6545Y225658D02*
X-6694Y225681D01*
G01X-6545Y229595D02*
X-6694Y229619D01*
G01X-4259Y225839D02*
X-3582Y225658D01*
G01X-4259Y229776D02*
X-3582Y229595D01*
G01X-2197Y225996D02*
X-2001Y225658D01*
G01X-3151Y228122D02*
X-3364Y228493D01*
G01X-2197Y229933D02*
X-2001Y229595D01*
G01X-3151Y232059D02*
X-3364Y232430D01*
G01X-4259Y224343D02*
X-4725D01*
G01X-6694Y224500D02*
X-9844D01*
G01Y225681D02*
X-6694D01*
G01X-4725Y225839D02*
X-4259D01*
G01X-3151Y225996D02*
X-2197D01*
G01X-4725Y226272D02*
X-6694D01*
G01X9000Y226390D02*
X-1D01*
G01D02*
X-985D01*
G01X-1Y227729D02*
X9000D01*
G01X-985D02*
X-1D01*
G01X-4725Y227847D02*
X-6694D01*
G01X-3151Y228122D02*
X-2197D01*
G01X-4259Y228280D02*
X-4725D01*
G01X-6694Y228437D02*
X-9844D01*
G01Y229619D02*
X-6694D01*
G01X-4725Y229776D02*
X-4259D01*
G01X-3151Y229933D02*
X-2197D01*
G01X-4725Y230209D02*
X-6694D01*
G01X9000Y230327D02*
X-1D01*
G01D02*
X-985D01*
G01X-1Y231666D02*
X9000D01*
G01X-985D02*
X-1D01*
G01X-4725Y231784D02*
X-6694D01*
G01X-3151Y232059D02*
X-2197D01*
G01X-4259Y232217D02*
X-4725D01*
G01X-6351Y224556D02*
X-6694Y224500D01*
G01X-3467Y224556D02*
X-4259Y224343D01*
G01X-3467Y228493D02*
X-4259Y228280D01*
G01X-3467Y232430D02*
X-4259Y232217D01*
G01X-6351Y228493D02*
X-6694Y228437D01*
G01X-10531Y232065D02*
Y229928D01*
G01Y228128D02*
Y225991D01*
G01X-6694Y232374D02*
Y231784D01*
G01Y230209D02*
Y229619D01*
G01Y228437D02*
Y227847D01*
G01Y226272D02*
Y225681D01*
G01X-6038Y232430D02*
Y232115D01*
G01Y229910D02*
Y229595D01*
G01Y228493D02*
Y228178D01*
G01Y225973D02*
Y225658D01*
G01Y224556D02*
Y224241D01*
G01X-4725Y225658D02*
Y226272D01*
G01Y229595D02*
Y230209D01*
G01Y227847D02*
Y228493D01*
G01Y231784D02*
Y232430D01*
G01X-3757Y232115D02*
Y229910D01*
G01Y228178D02*
Y225973D01*
G01X-2521Y232115D02*
Y229910D01*
G01Y228178D02*
Y225973D01*
G01X-2251Y232430D02*
Y229595D01*
G01Y228493D02*
Y225658D01*
G01X-985Y231666D02*
Y230327D01*
G01Y227729D02*
Y226390D01*
G01X196Y231666D02*
Y230327D01*
G01Y227729D02*
Y226390D01*
G01X-1983Y232430D02*
X-2197Y232059D01*
G01X-3346Y229595D02*
X-3151Y229933D01*
G01X-1983Y228493D02*
X-2197Y228122D01*
G01X-3346Y225658D02*
X-3151Y225996D01*
G01X-10631Y232020D02*
X-9844Y232374D01*
G01X-10631Y228083D02*
X-9844Y228437D01*
G01X9524Y171633D02*
X9323Y171698D01*
G01X9390Y172092D02*
X9591Y172026D01*
G01X10730Y171698D02*
X10931Y171633D01*
G01X10797Y172092D02*
X10999Y172026D01*
G01X9591D02*
X9859Y171830D01*
G01X10999Y172026D02*
X11267Y171830D01*
G01X8921Y173011D02*
X9390Y172617D01*
G01X9658Y171502D02*
X9524Y171633D01*
G01X10931D02*
X11066Y171502D01*
G01X11267Y171830D02*
X11468Y171567D01*
G01X9859Y171830D02*
X9926Y171698D01*
G01X11132Y170058D02*
X10127D01*
G01X12829Y171272D02*
X9000D01*
G01X9323Y171698D02*
X9189D01*
G01X10529D02*
X10730D01*
G01X9122Y172092D02*
X9390D01*
G01X10462D02*
X10797D01*
G01X9000Y172611D02*
X12829D01*
G01X9390Y172617D02*
X8854D01*
G01X11534Y173011D02*
X8921D01*
G01X12829Y175209D02*
X9000D01*
G01Y176548D02*
X12829D01*
G01Y179146D02*
X9000D01*
G01Y180485D02*
X12829D01*
G01Y183083D02*
X9000D01*
G01X9725Y171305D02*
X9658Y171502D01*
G01X11066D02*
X11132Y171305D01*
G01X11468Y171567D02*
X11534Y171239D01*
G01X9000Y184422D02*
Y183083D01*
G01Y180485D02*
Y179146D01*
G01Y176548D02*
Y175209D01*
G01Y172611D02*
Y171272D01*
G01X9725Y170058D02*
Y171305D01*
G01X10127Y170058D02*
Y171305D01*
G01X11132D02*
Y170058D01*
G01X11534Y171239D02*
Y169664D01*
G01Y173404D02*
Y173011D01*
G01X10127Y171305D02*
X10194Y171502D01*
G01X9926Y171698D02*
X9993Y171830D01*
G01X8988Y171633D02*
X8854Y171502D01*
G01X10194D02*
X10329Y171633D01*
G01X9993Y171830D02*
X10261Y172026D01*
G01X8921D02*
X9122Y172092D01*
G01X9189Y171698D02*
X8988Y171633D01*
G01X10261Y172026D02*
X10462Y172092D01*
G01X10329Y171633D02*
X10529Y171698D01*
G01X9000Y184422D02*
X12829D01*
G01Y187020D02*
X9000D01*
G01Y188359D02*
X12829D01*
G01Y190957D02*
X9000D01*
G01Y192296D02*
X12829D01*
G01Y194894D02*
X9000D01*
G01Y196233D02*
X12829D01*
G01Y198831D02*
X9000D01*
G01Y200170D02*
X12829D01*
G01Y202768D02*
X9000D01*
G01Y204107D02*
X12829D01*
G01X9000D02*
Y202768D01*
G01Y200170D02*
Y198831D01*
G01Y196233D02*
Y194894D01*
G01Y192296D02*
Y190957D01*
G01Y188359D02*
Y187020D01*
G01X12829Y206705D02*
X9000D01*
G01Y208044D02*
X12829D01*
G01Y210642D02*
X9000D01*
G01Y211981D02*
X12829D01*
G01Y222453D02*
X9000D01*
G01Y223792D02*
X12829D01*
G01X9000D02*
Y222453D01*
G01Y211981D02*
Y210642D01*
G01Y208044D02*
Y206705D01*
G01X12829Y226390D02*
X9000D01*
G01Y227729D02*
X12829D01*
G01Y230327D02*
X9000D01*
G01Y231666D02*
X12829D01*
G01X9000D02*
Y230327D01*
G01Y227729D02*
Y226390D01*
G01X-39036Y310479D02*
G03I-4292J0D01*
G01X-7875Y283866D02*
Y300383D01*
G01X-35351Y235681D02*
X-10631Y235957D01*
G01X-39607Y233768D02*
X-24509D01*
G01X-35546Y233847D02*
X-1D01*
G01X-39607Y234260D02*
X-27993D01*
G01X-35546Y236052D02*
X-1D01*
G01X-24509Y236130D02*
X-39607D01*
G01Y237410D02*
X-24844D01*
G01X-39607Y237705D02*
X-24509D01*
G01X-35546Y237784D02*
X-1D01*
G01X-35546Y239989D02*
X-1D01*
G01X-24509Y240067D02*
X-39607D01*
G01Y241642D02*
X-24509D01*
G01X-35546Y241721D02*
X-1D01*
G01X-39607Y242134D02*
X-24844D01*
G01X-35546Y243926D02*
X-1D01*
G01X-24509Y244004D02*
X-39607D01*
G01X-35351Y234185D02*
X-10631Y233910D01*
G01X-35351Y238122D02*
X-10631Y237847D01*
G01X-35351Y242059D02*
X-10631Y241784D01*
G01X-36192Y234267D02*
X-35351Y234185D01*
G01X-36192Y238204D02*
X-35351Y238122D01*
G01X-36192Y242141D02*
X-35351Y242059D01*
G01X-36192Y235601D02*
X-35341Y235683D01*
G01X-36192Y239538D02*
X-35341Y239620D01*
G01X-36192Y243475D02*
X-35341Y243557D01*
G01X-35351Y239619D02*
X-10631Y239894D01*
G01X-35351Y243556D02*
X-10631Y243831D01*
G01X-38426Y244004D02*
Y241642D01*
G01Y240067D02*
Y237705D01*
G01Y236130D02*
Y233768D01*
G01X-36192Y243475D02*
Y242141D01*
G01Y235601D02*
Y234267D01*
G01Y239538D02*
Y238204D01*
G01X-35595Y243532D02*
Y242083D01*
G01Y239595D02*
Y238146D01*
G01Y235658D02*
Y234209D01*
G01X-35546Y242078D02*
Y241642D01*
G01Y244004D02*
Y243537D01*
G01Y236130D02*
Y235663D01*
G01Y238141D02*
Y237705D01*
G01Y240067D02*
Y239600D01*
G01Y234204D02*
Y233768D01*
G01X-35331Y243557D02*
Y242059D01*
G01Y239620D02*
Y238122D01*
G01Y235683D02*
Y234185D01*
G01X-34607Y243926D02*
Y241721D01*
G01Y239989D02*
Y237784D01*
G01Y236052D02*
Y233847D01*
G01X-34136Y235695D02*
Y234172D01*
G01Y243569D02*
Y242046D01*
G01Y239632D02*
Y238109D01*
G01X-33153Y238098D02*
Y239643D01*
G01Y234161D02*
Y235706D01*
G01Y242035D02*
Y243580D01*
G01X-31995Y243593D02*
Y242022D01*
G01Y239656D02*
Y238085D01*
G01Y235719D02*
Y234148D01*
G01X-31725Y243596D02*
Y242019D01*
G01Y239659D02*
Y238082D01*
G01Y235722D02*
Y234145D01*
G01X-39607Y253529D02*
X-36561Y251396D01*
G01X-35351Y245996D02*
X-10631Y245721D01*
G01X-36192Y246078D02*
X-35351Y245996D01*
G01X-36192Y247412D02*
X-35341Y247494D01*
G01X-35351Y247493D02*
X-10631Y247768D01*
G01X-27993Y245284D02*
X-39607D01*
G01Y245579D02*
X-24509D01*
G01X-35546Y245658D02*
X-1D01*
G01X-35546Y247863D02*
X-1D01*
G01X-24509Y247941D02*
X-39607D01*
G01X-9607Y250855D02*
X-34845D01*
G01X-27993Y255520D02*
X-39607D01*
G01Y258670D02*
X-1D01*
G01X-38426Y247941D02*
Y245579D01*
G01X-36192Y247412D02*
Y246078D01*
G01X-35595Y247469D02*
Y246020D01*
G01X-35546Y246015D02*
Y245579D01*
G01Y247941D02*
Y247474D01*
G01X-35331Y247494D02*
Y245996D01*
G01X-34607Y247863D02*
Y245658D01*
G01X-34136Y247506D02*
Y245983D01*
G01X-33153Y245972D02*
Y247517D01*
G01X-31995Y247530D02*
Y245959D01*
G01X-31725Y247533D02*
Y245956D01*
G01X-36561Y251396D02*
G03X-34845Y250855I1716J2451D01*
G01X-1Y232430D02*
X-12993D01*
G01Y233532D02*
X-1D01*
G01Y236367D02*
X-12993D01*
G01Y237469D02*
X-1D01*
G01Y240304D02*
X-12993D01*
G01Y241406D02*
X-1D01*
G01Y244241D02*
X-12993D01*
G01X-27993Y242134D02*
Y258670D01*
G01X-27265Y244004D02*
Y241642D01*
G01Y240067D02*
Y237705D01*
G01Y236130D02*
Y233768D01*
G01X-26511Y243654D02*
Y241961D01*
G01Y235780D02*
Y234087D01*
G01Y239717D02*
Y238024D01*
G01X-26242Y238021D02*
Y239720D01*
G01Y234084D02*
Y235783D01*
G01Y241958D02*
Y243657D01*
G01X-24844Y242134D02*
Y258670D01*
G01X-24509Y244004D02*
Y241642D01*
G01Y240067D02*
Y237705D01*
G01Y236130D02*
Y233768D01*
G01X-23998Y243682D02*
Y241933D01*
G01Y239745D02*
Y237996D01*
G01Y235808D02*
Y234059D01*
G01X-23519Y234054D02*
Y235814D01*
G01Y237991D02*
Y239751D01*
G01Y241928D02*
Y243688D01*
G01X-12993Y241721D02*
Y241406D01*
G01Y244241D02*
Y243926D01*
G01Y240304D02*
Y239989D01*
G01Y237784D02*
Y237469D01*
G01Y236367D02*
Y236052D01*
G01Y233847D02*
Y233532D01*
G01X-12445Y237867D02*
Y239874D01*
G01Y233930D02*
Y235937D01*
G01Y241804D02*
Y243811D01*
G01X-11967Y243817D02*
Y241799D01*
G01Y235943D02*
Y233925D01*
G01Y239880D02*
Y237862D01*
G01X-12993Y245343D02*
X-1D01*
G01Y248178D02*
X-12993D01*
G01X-27265Y247941D02*
Y245579D01*
G01X-26511Y247591D02*
Y245898D01*
G01X-26242Y245895D02*
Y247594D01*
G01X-24509Y247941D02*
Y245579D01*
G01X-23998Y247619D02*
Y245870D01*
G01X-23519Y245865D02*
Y247625D01*
G01X-12993Y245658D02*
Y245343D01*
G01Y248178D02*
Y247863D01*
G01X-12445Y245741D02*
Y247748D01*
G01X-11967Y247754D02*
Y245736D01*
G01X-10631Y233910D02*
X-9844Y233556D01*
G01X-10631Y237847D02*
X-9844Y237493D01*
G01X-10631Y241784D02*
X-9844Y241430D01*
G01X-6545Y233532D02*
X-6694Y233556D01*
G01X-6545Y237469D02*
X-6694Y237493D01*
G01X-6545Y241406D02*
X-6694Y241430D01*
G01X-4259Y233713D02*
X-3582Y233532D01*
G01X-4259Y237650D02*
X-3582Y237469D01*
G01X-4259Y241587D02*
X-3582Y241406D01*
G01X-2197Y233870D02*
X-2001Y233532D01*
G01X-3151Y235996D02*
X-3364Y236367D01*
G01X-2197Y237807D02*
X-2001Y237469D01*
G01X-3151Y239933D02*
X-3364Y240304D01*
G01X-2197Y241744D02*
X-2001Y241406D01*
G01X-3151Y243870D02*
X-3364Y244241D01*
G01X-6694Y232374D02*
X-9844D01*
G01Y233556D02*
X-6694D01*
G01X-4725Y233713D02*
X-4259D01*
G01X-3151Y233870D02*
X-2197D01*
G01X-4725Y234146D02*
X-6694D01*
G01X9000Y234264D02*
X-1D01*
G01D02*
X-985D01*
G01X-1Y235603D02*
X9000D01*
G01X-985D02*
X-1D01*
G01X-4725Y235721D02*
X-6694D01*
G01X-3151Y235996D02*
X-2197D01*
G01X-4259Y236154D02*
X-4725D01*
G01X-6694Y236311D02*
X-9844D01*
G01Y237493D02*
X-6694D01*
G01X-4725Y237650D02*
X-4259D01*
G01X-3151Y237807D02*
X-2197D01*
G01X-4725Y238083D02*
X-6694D01*
G01X9000Y238201D02*
X-1D01*
G01D02*
X-985D01*
G01X-1Y239540D02*
X9000D01*
G01X-985D02*
X-1D01*
G01X-4725Y239658D02*
X-6694D01*
G01X-3151Y239933D02*
X-2197D01*
G01X-4259Y240091D02*
X-4725D01*
G01X-6694Y240248D02*
X-9844D01*
G01Y241430D02*
X-6694D01*
G01X-4725Y241587D02*
X-4259D01*
G01X-3151Y241744D02*
X-2197D01*
G01X-4725Y242020D02*
X-6694D01*
G01X9000Y242138D02*
X-1D01*
G01D02*
X-985D01*
G01X-1Y243477D02*
X9000D01*
G01X-985D02*
X-1D01*
G01X-4725Y243595D02*
X-6694D01*
G01X-3151Y243870D02*
X-2197D01*
G01X-4259Y244028D02*
X-4725D01*
G01X-6694Y244185D02*
X-9844D01*
G01X-6351Y232430D02*
X-6694Y232374D01*
G01X-6351Y236367D02*
X-6694Y236311D01*
G01X-6351Y240304D02*
X-6694Y240248D01*
G01X-6351Y244241D02*
X-6694Y244185D01*
G01X-10531Y243876D02*
Y241739D01*
G01Y239939D02*
Y237802D01*
G01Y236002D02*
Y233865D01*
G01X-6694Y244185D02*
Y243595D01*
G01Y242020D02*
Y241430D01*
G01Y240248D02*
Y239658D01*
G01Y238083D02*
Y237493D01*
G01Y236311D02*
Y235721D01*
G01Y234146D02*
Y233556D01*
G01X-6038Y241721D02*
Y241406D01*
G01Y244241D02*
Y243926D01*
G01Y240304D02*
Y239989D01*
G01Y237784D02*
Y237469D01*
G01Y236367D02*
Y236052D01*
G01Y233847D02*
Y233532D01*
G01X-4725D02*
Y234146D01*
G01Y237469D02*
Y238083D01*
G01Y235721D02*
Y236367D01*
G01Y241406D02*
Y242020D01*
G01Y243595D02*
Y244241D01*
G01Y239658D02*
Y240304D01*
G01X-3757Y243926D02*
Y241721D01*
G01Y236052D02*
Y233847D01*
G01Y239989D02*
Y237784D01*
G01X-3467Y236367D02*
X-4259Y236154D01*
G01X-3467Y240304D02*
X-4259Y240091D01*
G01X-3467Y244241D02*
X-4259Y244028D01*
G01X-2521Y243926D02*
Y241721D01*
G01Y236052D02*
Y233847D01*
G01Y239989D02*
Y237784D01*
G01X-2251Y244241D02*
Y241406D01*
G01Y240304D02*
Y237469D01*
G01Y236367D02*
Y233532D01*
G01X-985Y243477D02*
Y242138D01*
G01Y239540D02*
Y238201D01*
G01Y235603D02*
Y234264D01*
G01X196Y243477D02*
Y242138D01*
G01Y235603D02*
Y234264D01*
G01Y239540D02*
Y238201D01*
G01X-1983Y244241D02*
X-2197Y243870D01*
G01X-3346Y241406D02*
X-3151Y241744D01*
G01X-1983Y240304D02*
X-2197Y239933D01*
G01X-3346Y237469D02*
X-3151Y237807D01*
G01X-1983Y236367D02*
X-2197Y235996D01*
G01X-3346Y233532D02*
X-3151Y233870D01*
G01X-10631Y243831D02*
X-9844Y244185D01*
G01X-10631Y239894D02*
X-9844Y240248D01*
G01X-10631Y235957D02*
X-9844Y236311D01*
G01X-4259Y245524D02*
X-3582Y245343D01*
G01X-10631Y245721D02*
X-9844Y245367D01*
G01X-6545Y245343D02*
X-6694Y245367D01*
G01X-2197Y245681D02*
X-2001Y245343D01*
G01X-3151Y247807D02*
X-3364Y248178D01*
G01X9842Y261819D02*
X-9056Y261032D01*
G01X-6694Y245367D02*
X-9844D01*
G01X-4259Y245524D02*
X-4725D01*
G01X-3151Y245681D02*
X-2197D01*
G01X-4725Y245957D02*
X-6694D01*
G01X9000Y246075D02*
X-1D01*
G01D02*
X-985D01*
G01X-1Y247414D02*
X9000D01*
G01X-985D02*
X-1D01*
G01X-4725Y247532D02*
X-6694D01*
G01X-3151Y247807D02*
X-2197D01*
G01X-4725Y247965D02*
X-4259D01*
G01X-9844Y248122D02*
X-6694D01*
G01X24802Y252370D02*
X-1D01*
G01X-6694Y248122D02*
X-6351Y248178D01*
G01X-10531Y247813D02*
Y245676D01*
G01X-9056Y277961D02*
Y258670D01*
G01X-6694Y245957D02*
Y245367D01*
G01Y248122D02*
Y247532D01*
G01X-6038Y245658D02*
Y245343D01*
G01Y248178D02*
Y247863D01*
G01X-4725Y247532D02*
Y248178D01*
G01Y245343D02*
Y245957D01*
G01X-3757Y247863D02*
Y245658D01*
G01X-3467Y248178D02*
X-4259Y247965D01*
G01X-2521Y247863D02*
Y245658D01*
G01X-2251Y248178D02*
Y245343D01*
G01X-985Y247414D02*
Y246075D01*
G01X-1Y258670D02*
Y277961D01*
G01X196Y247414D02*
Y246075D01*
G01X-1983Y248178D02*
X-2197Y247807D01*
G01X-3346Y245343D02*
X-3151Y245681D01*
G01X-10631Y247768D02*
X-9844Y248122D01*
G01X14369Y265756D02*
G03I-4527J0D01*
G01X13779D02*
G03I-3937J0D01*
G01X24802Y277961D02*
X-9056D01*
G01X-1Y279930D02*
X26771D01*
G01X-9056Y270481D02*
X9842Y269693D01*
G01X-1Y277961D02*
Y340939D01*
G01X12829Y234264D02*
X9000D01*
G01Y235603D02*
X12829D01*
G01Y238201D02*
X9000D01*
G01Y239540D02*
X12829D01*
G01Y242138D02*
X9000D01*
G01Y243477D02*
X12829D01*
G01X9000D02*
Y242138D01*
G01Y235603D02*
Y234264D01*
G01Y239540D02*
Y238201D01*
G01X12829Y246075D02*
X9000D01*
G01Y247414D02*
X12829D01*
G01X9000D02*
Y246075D01*
G01X-19814Y283866D02*
X-63741D01*
G01X-7875D02*
X-19814D01*
G01X-1Y300383D02*
G03X-7875I-3937J0D01*
G01X-1D02*
G03X-7875I-3937J0D01*
G01Y331986D02*
Y324003D01*
G01X-24844Y360231D02*
X-39607D01*
G01Y360270D02*
X-24844D01*
G01X-33702Y362199D02*
X-39607D01*
G01Y363420D02*
X-27993D01*
G01X-39607Y360270D02*
Y710624D01*
G01X-33702Y366136D02*
Y362199D01*
G01X-39607Y364601D02*
X-34603Y368105D01*
G01X-35351Y372691D02*
X-10631Y372967D01*
G01X-35351Y376628D02*
X-10631Y376904D01*
G01X-35351Y380565D02*
X-10631Y380841D01*
G01X-35351Y384502D02*
X-10631Y384778D01*
G01X-39607Y366136D02*
X-33702D01*
G01X-34603Y368105D02*
X-8899D01*
G01X-39607Y370762D02*
X-24509D01*
G01X-35546Y370841D02*
X-1D01*
G01X-35546Y373046D02*
X-1D01*
G01X-24509Y373124D02*
X-39607D01*
G01Y374699D02*
X-24509D01*
G01X-35546Y374778D02*
X-1D01*
G01X-27993Y376766D02*
X-39607D01*
G01X-35546Y376983D02*
X-1D01*
G01X-24509Y377061D02*
X-39607D01*
G01Y378636D02*
X-24509D01*
G01X-35546Y378715D02*
X-1D01*
G01X-39607Y379916D02*
X-24844D01*
G01X-35546Y380920D02*
X-1D01*
G01X-24509Y380998D02*
X-39607D01*
G01Y382573D02*
X-24509D01*
G01X-35546Y382652D02*
X-1D01*
G01X-39607Y383892D02*
X-24844D01*
G01X-35546Y384857D02*
X-1D01*
G01X-24509Y384935D02*
X-39607D01*
G01X-10631Y370920D02*
X-35351Y371195D01*
G01X-10631Y374857D02*
X-35351Y375132D01*
G01X-10631Y378794D02*
X-35351Y379069D01*
G01X-10631Y382731D02*
X-35351Y383006D01*
G01X-38108Y371461D02*
X-35351Y371195D01*
G01X-38108Y375398D02*
X-35351Y375132D01*
G01X-38108Y379335D02*
X-35351Y379069D01*
G01X-38108Y383272D02*
X-35351Y383006D01*
G01X-38426Y384935D02*
Y382573D01*
G01Y377061D02*
Y374699D01*
G01Y380998D02*
Y378636D01*
G01Y373124D02*
Y370762D01*
G01X-38108Y384237D02*
Y383272D01*
G01Y376363D02*
Y375398D01*
G01Y380300D02*
Y379335D01*
G01Y372426D02*
Y371461D01*
G01X-37871Y384259D02*
Y383249D01*
G01Y376385D02*
Y375375D01*
G01Y380322D02*
Y379312D01*
G01Y372448D02*
Y371438D01*
G01X-36812Y414628D02*
Y366558D01*
G01X-35595Y384479D02*
Y383030D01*
G01Y376605D02*
Y375156D01*
G01Y380542D02*
Y379093D01*
G01Y372668D02*
Y371219D01*
G01X-35546Y384935D02*
Y382573D01*
G01Y380998D02*
Y378636D01*
G01Y377061D02*
Y374699D01*
G01Y373124D02*
Y370762D01*
G01X-35357Y384502D02*
Y383007D01*
G01Y380565D02*
Y379070D01*
G01Y376628D02*
Y375133D01*
G01Y372691D02*
Y371196D01*
G01X-34607Y384857D02*
Y382652D01*
G01Y376983D02*
Y374778D01*
G01Y380920D02*
Y378715D01*
G01Y373046D02*
Y370841D01*
G01X-34136Y380579D02*
Y379056D01*
G01Y384516D02*
Y382993D01*
G01Y376642D02*
Y375119D01*
G01Y372705D02*
Y371181D01*
G01X-33153Y384527D02*
Y382981D01*
G01Y376653D02*
Y375107D01*
G01Y380590D02*
Y379044D01*
G01Y372716D02*
Y371170D01*
G01X-32319Y380599D02*
Y379035D01*
G01Y384536D02*
Y382972D01*
G01Y376662D02*
Y375098D01*
G01Y372725D02*
Y371161D01*
G01X-31941Y380603D02*
Y379031D01*
G01Y384540D02*
Y382968D01*
G01Y376666D02*
Y375094D01*
G01Y372729D02*
Y371157D01*
G01X-35351Y372691D02*
X-38108Y372426D01*
G01X-35351Y376628D02*
X-38108Y376363D01*
G01X-35351Y380565D02*
X-38108Y380300D01*
G01X-35351Y384502D02*
X-38108Y384237D01*
G01X-35351Y388439D02*
X-10631Y388715D01*
G01X-39607Y386510D02*
X-24509D01*
G01X-35546Y386589D02*
X-1D01*
G01X-39607Y387042D02*
X-27993D01*
G01X-35546Y388794D02*
X-1D01*
G01X-24509Y388872D02*
X-39607D01*
G01Y390447D02*
X-24509D01*
G01X-35546Y390526D02*
X-1D01*
G01X-35546Y392731D02*
X-1D01*
G01X-24509Y392809D02*
X-39607D01*
G01Y394384D02*
X-24509D01*
G01X-35546Y394463D02*
X-1D01*
G01X-35546Y396668D02*
X-1D01*
G01X-24509Y396746D02*
X-39607D01*
G01X-10631Y386668D02*
X-35351Y386943D01*
G01X-10631Y390605D02*
X-35351Y390880D01*
G01X-10631Y394542D02*
X-35351Y394817D01*
G01X-38108Y387209D02*
X-35351Y386943D01*
G01X-38108Y391146D02*
X-35351Y390880D01*
G01X-38108Y395083D02*
X-35351Y394817D01*
G01X-38426Y396746D02*
Y394384D01*
G01Y392809D02*
Y390447D01*
G01Y388872D02*
Y386510D01*
G01X-38108Y396048D02*
Y395083D01*
G01Y392111D02*
Y391146D01*
G01Y388174D02*
Y387209D01*
G01X-37871Y396070D02*
Y395060D01*
G01Y392133D02*
Y391123D01*
G01Y388196D02*
Y387186D01*
G01X-35595Y396290D02*
Y394841D01*
G01Y392353D02*
Y390904D01*
G01Y388416D02*
Y386967D01*
G01X-35546Y392809D02*
Y390447D01*
G01Y396746D02*
Y394384D01*
G01Y388872D02*
Y386510D01*
G01X-35357Y396313D02*
Y394818D01*
G01Y392376D02*
Y390881D01*
G01Y388439D02*
Y386944D01*
G01X-34607Y396668D02*
Y394463D01*
G01Y392731D02*
Y390526D01*
G01Y388794D02*
Y386589D01*
G01X-34136Y396327D02*
Y394804D01*
G01Y392390D02*
Y390867D01*
G01Y388453D02*
Y386930D01*
G01X-33153Y396338D02*
Y394793D01*
G01Y392401D02*
Y390856D01*
G01Y388464D02*
Y386919D01*
G01X-32319Y396347D02*
Y394783D01*
G01Y392410D02*
Y390846D01*
G01Y388473D02*
Y386909D01*
G01X-31941Y396351D02*
Y394779D01*
G01Y392414D02*
Y390842D01*
G01Y388477D02*
Y386905D01*
G01X-35351Y388439D02*
X-38108Y388174D01*
G01X-35351Y392376D02*
X-38108Y392111D01*
G01X-35351Y396313D02*
X-38108Y396048D01*
G01X-35351Y392376D02*
X-10631Y392652D01*
G01X-35351Y396313D02*
X-10631Y396589D01*
G01X-1Y360231D02*
X-24844D01*
G01X-27993Y360270D02*
Y379916D01*
G01X-24844Y360270D02*
Y379916D01*
G01X-12993Y370526D02*
X-1D01*
G01Y373361D02*
X-12993D01*
G01Y374463D02*
X-1D01*
G01Y377298D02*
X-12993D01*
G01Y378400D02*
X-1D01*
G01Y381235D02*
X-12993D01*
G01Y382337D02*
X-1D01*
G01X-27993Y383892D02*
Y403538D01*
G01X-27265Y380998D02*
Y378636D01*
G01Y384935D02*
Y382573D01*
G01Y377061D02*
Y374699D01*
G01Y373124D02*
Y370762D01*
G01X-26943Y384596D02*
Y382912D01*
G01Y380659D02*
Y378975D01*
G01Y376722D02*
Y375038D01*
G01Y372785D02*
Y371101D01*
G01X-26566Y384600D02*
Y382908D01*
G01Y376726D02*
Y375034D01*
G01Y380663D02*
Y378971D01*
G01Y372789D02*
Y371097D01*
G01X-24844Y383892D02*
Y403538D01*
G01X-24509Y384935D02*
Y382573D01*
G01Y380998D02*
Y378636D01*
G01Y377061D02*
Y374699D01*
G01Y373124D02*
Y370762D01*
G01X-24122Y380690D02*
Y378944D01*
G01Y384627D02*
Y382881D01*
G01Y376753D02*
Y375007D01*
G01Y372816D02*
Y371070D01*
G01X-23684Y380695D02*
Y378939D01*
G01Y384632D02*
Y382876D01*
G01Y376758D02*
Y375002D01*
G01Y372821D02*
Y371065D01*
G01X-12993Y381235D02*
Y380920D01*
G01Y382652D02*
Y382337D01*
G01Y385172D02*
Y384857D01*
G01Y377298D02*
Y376983D01*
G01Y378715D02*
Y378400D01*
G01Y374778D02*
Y374463D01*
G01Y373361D02*
Y373046D01*
G01Y370841D02*
Y370526D01*
G01X-12280Y380822D02*
Y378812D01*
G01Y384759D02*
Y382749D01*
G01Y376885D02*
Y374875D01*
G01Y372948D02*
Y370938D01*
G01X-11843Y384764D02*
Y382744D01*
G01Y380827D02*
Y378807D01*
G01Y376890D02*
Y374870D01*
G01Y372953D02*
Y370933D01*
G01X-1Y385172D02*
X-12993D01*
G01Y386274D02*
X-1D01*
G01Y389109D02*
X-12993D01*
G01Y390211D02*
X-1D01*
G01Y393046D02*
X-12993D01*
G01Y394148D02*
X-1D01*
G01Y396983D02*
X-12993D01*
G01X-27265Y396746D02*
Y394384D01*
G01Y392809D02*
Y390447D01*
G01Y388872D02*
Y386510D01*
G01X-26943Y396407D02*
Y394723D01*
G01Y392470D02*
Y390786D01*
G01Y388533D02*
Y386849D01*
G01X-26566Y396411D02*
Y394719D01*
G01Y392474D02*
Y390782D01*
G01Y388537D02*
Y386845D01*
G01X-24509Y392809D02*
Y390447D01*
G01Y396746D02*
Y394384D01*
G01Y388872D02*
Y386510D01*
G01X-24122Y396438D02*
Y394692D01*
G01Y392501D02*
Y390755D01*
G01Y388564D02*
Y386818D01*
G01X-23684Y396443D02*
Y394687D01*
G01Y392506D02*
Y390750D01*
G01Y388569D02*
Y386813D01*
G01X-12993Y396983D02*
Y396668D01*
G01Y390526D02*
Y390211D01*
G01Y393046D02*
Y392731D01*
G01Y394463D02*
Y394148D01*
G01Y386589D02*
Y386274D01*
G01Y389109D02*
Y388794D01*
G01X-12280Y396570D02*
Y394560D01*
G01Y392633D02*
Y390623D01*
G01Y388696D02*
Y386686D01*
G01X-11843Y396575D02*
Y394555D01*
G01Y392638D02*
Y390618D01*
G01Y388701D02*
Y386681D01*
G01X-1Y338971D02*
X26771D01*
G01X-9056Y340939D02*
X24802D01*
G01X-9056Y360231D02*
Y340939D01*
G01X-1D02*
Y360231D01*
G01X9842Y349207D02*
X-9056Y348803D01*
G01Y358252D02*
X9842Y357081D01*
G01X-1Y360231D02*
Y710624D01*
G01X14369Y353144D02*
G03I-4527J0D01*
G01X13779D02*
G03I-3937J0D01*
G01X-10631Y370920D02*
X-9844Y370565D01*
G01X-10631Y374857D02*
X-9844Y374502D01*
G01X-10631Y378794D02*
X-9844Y378439D01*
G01X-10631Y382731D02*
X-9844Y382376D01*
G01X-2197Y370880D02*
X-1970Y370487D01*
G01X-3151Y373006D02*
X-3378Y373400D01*
G01X-2197Y374817D02*
X-1970Y374424D01*
G01X-3151Y376943D02*
X-3378Y377337D01*
G01X-2197Y378754D02*
X-1970Y378361D01*
G01X-3151Y380880D02*
X-3378Y381274D01*
G01X-2197Y382691D02*
X-1970Y382298D01*
G01X-3151Y384817D02*
X-3378Y385211D01*
G01X-4725Y370250D02*
X-6694Y370565D01*
G01X-4725Y374187D02*
X-6694Y374502D01*
G01X-4725Y378124D02*
X-6694Y378439D01*
G01X-4725Y382061D02*
X-6694Y382376D01*
G01X-4259Y370723D02*
X-3378Y370487D01*
G01X-4259Y374660D02*
X-3378Y374424D01*
G01X-4259Y378597D02*
X-3378Y378361D01*
G01X-4259Y382534D02*
X-3378Y382298D01*
G01X24802Y366530D02*
X-1D01*
G01Y370487D02*
X-1970D01*
G01X-6694Y370565D02*
X-9844D01*
G01X-4259Y370723D02*
X-4725D01*
G01X-2197Y370880D02*
X-3151D01*
G01X-4725Y371156D02*
X-6694D01*
G01X15077Y371274D02*
X8523D01*
G01D02*
X-1D01*
G01D02*
X-985D01*
G01Y372613D02*
X-1D01*
G01D02*
X8523D01*
G01D02*
X12600D01*
G01X-4725Y372731D02*
X-6694D01*
G01X-3151Y373006D02*
X-2197D01*
G01X-4725Y373164D02*
X-4259D01*
G01X-9844Y373321D02*
X-6694D01*
G01X-1970Y373400D02*
X-1D01*
G01Y374424D02*
X-1970D01*
G01X-6694Y374502D02*
X-9844D01*
G01X-4259Y374660D02*
X-4725D01*
G01X-2197Y374817D02*
X-3151D01*
G01X-4725Y375093D02*
X-6694D01*
G01X15077Y375211D02*
X8523D01*
G01D02*
X-1D01*
G01D02*
X-985D01*
G01Y376550D02*
X-1D01*
G01D02*
X8523D01*
G01D02*
X12600D01*
G01X-4725Y376668D02*
X-6694D01*
G01X-3151Y376943D02*
X-2197D01*
G01X-4725Y377101D02*
X-4259D01*
G01X-9844Y377258D02*
X-6694D01*
G01X-1970Y377337D02*
X-1D01*
G01Y378361D02*
X-1970D01*
G01X-6694Y378439D02*
X-9844D01*
G01X-4259Y378597D02*
X-4725D01*
G01X-2197Y378754D02*
X-3151D01*
G01X-4725Y379030D02*
X-6694D01*
G01X15077Y379148D02*
X8523D01*
G01D02*
X-1D01*
G01D02*
X-985D01*
G01Y380487D02*
X-1D01*
G01D02*
X8523D01*
G01D02*
X12600D01*
G01X-4725Y380605D02*
X-6694D01*
G01X-3151Y380880D02*
X-2197D01*
G01X-4725Y381038D02*
X-4259D01*
G01X-9844Y381195D02*
X-6694D01*
G01X-1970Y381274D02*
X-1D01*
G01Y382298D02*
X-1970D01*
G01X-6694Y382376D02*
X-9844D01*
G01X-4259Y382534D02*
X-4725D01*
G01X-2197Y382691D02*
X-3151D01*
G01X-4725Y382967D02*
X-6694D01*
G01X15077Y383085D02*
X8523D01*
G01D02*
X-1D01*
G01D02*
X-985D01*
G01Y384424D02*
X-1D01*
G01D02*
X8523D01*
G01D02*
X12600D01*
G01X-4725Y384542D02*
X-6694D01*
G01X-3151Y384817D02*
X-2197D01*
G01X-10531Y380886D02*
Y378748D01*
G01Y384823D02*
Y382685D01*
G01Y376949D02*
Y374811D01*
G01Y373012D02*
Y370874D01*
G01X-8899Y368105D02*
Y413912D01*
G01X-6694Y385132D02*
Y384542D01*
G01Y382967D02*
Y382376D01*
G01Y381195D02*
Y380605D01*
G01Y379030D02*
Y378439D01*
G01Y377258D02*
Y376668D01*
G01Y375093D02*
Y374502D01*
G01Y373321D02*
Y372731D01*
G01Y371156D02*
Y370565D01*
G01X-4725Y385447D02*
Y384542D01*
G01Y381510D02*
Y380605D01*
G01Y382967D02*
Y382061D01*
G01Y377573D02*
Y376668D01*
G01Y379030D02*
Y378124D01*
G01Y375093D02*
Y374187D01*
G01Y373636D02*
Y372731D01*
G01Y371156D02*
Y370250D01*
G01X-3757Y380920D02*
Y378715D01*
G01Y384857D02*
Y382652D01*
G01Y376983D02*
Y374778D01*
G01Y373046D02*
Y370841D01*
G01X-6694Y373321D02*
X-4725Y373636D01*
G01X-6694Y377258D02*
X-4725Y377573D01*
G01X-6694Y381195D02*
X-4725Y381510D01*
G01X-2521Y380920D02*
Y378715D01*
G01Y384857D02*
Y382652D01*
G01Y376983D02*
Y374778D01*
G01Y373046D02*
Y370841D01*
G01X-2251Y381235D02*
Y378400D01*
G01Y385172D02*
Y382337D01*
G01Y377298D02*
Y374463D01*
G01Y373361D02*
Y370526D01*
G01X-985Y384424D02*
Y383085D01*
G01Y376550D02*
Y375211D01*
G01Y380487D02*
Y379148D01*
G01Y372613D02*
Y371274D01*
G01X8523Y384424D02*
Y383085D01*
G01Y380487D02*
Y379148D01*
G01Y376550D02*
Y375211D01*
G01Y372613D02*
Y371274D01*
G01X-3378Y373400D02*
X-4259Y373164D01*
G01X-3378Y377337D02*
X-4259Y377101D01*
G01X-3378Y381274D02*
X-4259Y381038D01*
G01X-1970Y385211D02*
X-2197Y384817D01*
G01X-3378Y382298D02*
X-3151Y382691D01*
G01X-1970Y381274D02*
X-2197Y380880D01*
G01X-3378Y378361D02*
X-3151Y378754D01*
G01X-1970Y377337D02*
X-2197Y376943D01*
G01X-3378Y374424D02*
X-3151Y374817D01*
G01X-1970Y373400D02*
X-2197Y373006D01*
G01X-3378Y370487D02*
X-3151Y370880D01*
G01X-9844Y385132D02*
X-10631Y384778D01*
G01X-9844Y381195D02*
X-10631Y380841D01*
G01X-9844Y377258D02*
X-10631Y376904D01*
G01X-9844Y373321D02*
X-10631Y372967D01*
G01Y386668D02*
X-9844Y386313D01*
G01X-10631Y390605D02*
X-9844Y390250D01*
G01X-10631Y394542D02*
X-9844Y394187D01*
G01X-2197Y386628D02*
X-1970Y386235D01*
G01X-3151Y388754D02*
X-3378Y389148D01*
G01X-2197Y390565D02*
X-1970Y390172D01*
G01X-3151Y392691D02*
X-3378Y393085D01*
G01X-2197Y394502D02*
X-1970Y394109D01*
G01X-3151Y396628D02*
X-3378Y397022D01*
G01X-4725Y385998D02*
X-6694Y386313D01*
G01X-4725Y389935D02*
X-6694Y390250D01*
G01X-4725Y393872D02*
X-6694Y394187D01*
G01X-4259Y386471D02*
X-3378Y386235D01*
G01X-4259Y390408D02*
X-3378Y390172D01*
G01X-4259Y394345D02*
X-3378Y394109D01*
G01X-4725Y384975D02*
X-4259D01*
G01X-9844Y385132D02*
X-6694D01*
G01X-1970Y385211D02*
X-1D01*
G01Y386235D02*
X-1970D01*
G01X-6694Y386313D02*
X-9844D01*
G01X-4259Y386471D02*
X-4725D01*
G01X-2197Y386628D02*
X-3151D01*
G01X-4725Y386904D02*
X-6694D01*
G01X15077Y387022D02*
X8523D01*
G01D02*
X-1D01*
G01D02*
X-985D01*
G01Y388361D02*
X-1D01*
G01D02*
X8523D01*
G01D02*
X12600D01*
G01X-4725Y388479D02*
X-6694D01*
G01X-3151Y388754D02*
X-2197D01*
G01X-4725Y388912D02*
X-4259D01*
G01X-9844Y389069D02*
X-6694D01*
G01X-1970Y389148D02*
X-1D01*
G01Y390172D02*
X-1970D01*
G01X-6694Y390250D02*
X-9844D01*
G01X-4259Y390408D02*
X-4725D01*
G01X-2197Y390565D02*
X-3151D01*
G01X-4725Y390841D02*
X-6694D01*
G01X15077Y390959D02*
X8523D01*
G01D02*
X-1D01*
G01D02*
X-985D01*
G01Y392298D02*
X-1D01*
G01D02*
X8523D01*
G01D02*
X12600D01*
G01X-4725Y392416D02*
X-6694D01*
G01X-3151Y392691D02*
X-2197D01*
G01X-4725Y392849D02*
X-4259D01*
G01X-9844Y393006D02*
X-6694D01*
G01X-1970Y393085D02*
X-1D01*
G01Y394109D02*
X-1970D01*
G01X-6694Y394187D02*
X-9844D01*
G01X-4259Y394345D02*
X-4725D01*
G01X-2197Y394502D02*
X-3151D01*
G01X-4725Y394778D02*
X-6694D01*
G01X15077Y394896D02*
X8523D01*
G01D02*
X-1D01*
G01D02*
X-985D01*
G01Y396235D02*
X-1D01*
G01D02*
X8523D01*
G01D02*
X12600D01*
G01X-4725Y396353D02*
X-6694D01*
G01X-3151Y396628D02*
X-2197D01*
G01X-4725Y396786D02*
X-4259D01*
G01X-9844Y396943D02*
X-6694D01*
G01X-10531Y396634D02*
Y394496D01*
G01Y392697D02*
Y390559D01*
G01Y388760D02*
Y386622D01*
G01X-6694Y396943D02*
Y396353D01*
G01Y394778D02*
Y394187D01*
G01Y393006D02*
Y392416D01*
G01Y390841D02*
Y390250D01*
G01Y389069D02*
Y388479D01*
G01Y386904D02*
Y386313D01*
G01X-4725Y397258D02*
Y396353D01*
G01Y393321D02*
Y392416D01*
G01Y390841D02*
Y389935D01*
G01Y394778D02*
Y393872D01*
G01Y389384D02*
Y388479D01*
G01Y386904D02*
Y385998D01*
G01X-3757Y396668D02*
Y394463D01*
G01Y392731D02*
Y390526D01*
G01Y388794D02*
Y386589D01*
G01X-1970Y397022D02*
X-1D01*
G01X-2521Y396668D02*
Y394463D01*
G01Y392731D02*
Y390526D01*
G01Y388794D02*
Y386589D01*
G01X-2251Y396983D02*
Y394148D01*
G01Y393046D02*
Y390211D01*
G01Y389109D02*
Y386274D01*
G01X-985Y396235D02*
Y394896D01*
G01Y392298D02*
Y390959D01*
G01Y388361D02*
Y387022D01*
G01X8523Y396235D02*
Y394896D01*
G01Y392298D02*
Y390959D01*
G01Y388361D02*
Y387022D01*
G01X-3378Y385211D02*
X-4259Y384975D01*
G01X-3378Y389148D02*
X-4259Y388912D01*
G01X-3378Y393085D02*
X-4259Y392849D01*
G01X-6694Y385132D02*
X-4725Y385447D01*
G01X-6694Y389069D02*
X-4725Y389384D01*
G01X-6694Y393006D02*
X-4725Y393321D01*
G01X-6694Y396943D02*
X-4725Y397258D01*
G01X-3378Y397022D02*
X-4259Y396786D01*
G01X-1970Y397022D02*
X-2197Y396628D01*
G01X-3378Y394109D02*
X-3151Y394502D01*
G01X-1970Y393085D02*
X-2197Y392691D01*
G01X-3378Y390172D02*
X-3151Y390565D01*
G01X-1970Y389148D02*
X-2197Y388754D01*
G01X-3378Y386235D02*
X-3151Y386628D01*
G01X-9844Y396943D02*
X-10631Y396589D01*
G01X-9844Y393006D02*
X-10631Y392652D01*
G01X-9844Y389069D02*
X-10631Y388715D01*
G01X10508Y371884D02*
X10307Y371950D01*
G01X10575Y372278D02*
X10843Y372081D01*
G01X11983Y372278D02*
X12251Y372081D01*
G01X9838Y372869D02*
X9369Y373262D01*
G01X9905D02*
X10375Y372869D01*
G01X10642Y371753D02*
X10508Y371884D01*
G01X11916D02*
X12050Y371753D01*
G01X10375Y372343D02*
X10575Y372278D01*
G01X11715Y371950D02*
X11916Y371884D01*
G01X11782Y372343D02*
X11983Y372278D01*
G01X10843Y372081D02*
X10910Y371950D01*
G01X10710Y371556D02*
X10642Y371753D01*
G01X12519Y369916D02*
X9369D01*
G01X12117Y370309D02*
X11112D01*
G01X9771D02*
X10710D01*
G01X10307Y371950D02*
X10173D01*
G01X11514D02*
X11715D01*
G01X10106Y372343D02*
X10375D01*
G01X11447D02*
X11782D01*
G01X10375Y372869D02*
X9838D01*
G01X12519Y373262D02*
X9905D01*
G01X9369Y373656D02*
X12519D01*
G01X9369Y369916D02*
Y371491D01*
G01Y373262D02*
Y373656D01*
G01X9771Y371556D02*
Y370309D01*
G01X10710D02*
Y371556D01*
G01X11112Y370309D02*
Y371556D01*
G01X9369Y371491D02*
X9436Y371819D01*
G01X9838Y371753D02*
X9771Y371556D01*
G01X11112D02*
X11179Y371753D01*
G01X10910Y371950D02*
X10977Y372081D01*
G01X9436Y371819D02*
X9637Y372081D01*
G01X9972Y371884D02*
X9838Y371753D01*
G01X11179D02*
X11313Y371884D01*
G01X9637Y372081D02*
X9905Y372278D01*
G01X10977Y372081D02*
X11245Y372278D01*
G01X9905D02*
X10106Y372343D01*
G01X10173Y371950D02*
X9972Y371884D01*
G01X11245Y372278D02*
X11447Y372343D01*
G01X11313Y371884D02*
X11514Y371950D01*
G01X-7875Y331986D02*
Y334646D01*
G01D02*
X-63741D01*
G01X-7875Y324003D02*
G03X-1I3937J0D01*
G01X-7875D02*
G03X-1I3937J0D01*
G01X-10631Y398479D02*
X-35351Y398754D01*
G01X-10631Y402416D02*
X-35351Y402691D01*
G01X-38108Y399020D02*
X-35351Y398754D01*
G01X-38108Y402957D02*
X-35351Y402691D01*
G01X-38426Y400683D02*
Y398321D01*
G01Y404620D02*
Y402258D01*
G01X-38108Y399985D02*
Y399020D01*
G01Y403922D02*
Y402957D01*
G01X-37871Y403944D02*
Y402934D01*
G01Y400007D02*
Y398997D01*
G01X-35595Y400227D02*
Y398778D01*
G01Y404164D02*
Y402715D01*
G01X-35546Y404620D02*
Y402258D01*
G01Y400683D02*
Y398321D01*
G01X-35357Y404187D02*
Y402692D01*
G01Y400250D02*
Y398755D01*
G01X-34607Y400605D02*
Y398400D01*
G01Y404542D02*
Y402337D01*
G01X-34136Y404201D02*
Y402678D01*
G01Y400264D02*
Y398741D01*
G01X-33153Y400275D02*
Y398730D01*
G01Y404212D02*
Y402667D01*
G01X-32319Y404221D02*
Y402657D01*
G01Y400284D02*
Y398720D01*
G01X-31941Y404225D02*
Y402653D01*
G01Y400288D02*
Y398716D01*
G01X-35351Y400250D02*
X-38108Y399985D01*
G01X-35351Y404187D02*
X-38108Y403922D01*
G01X-35351Y400250D02*
X-10631Y400526D01*
G01X-35351Y404187D02*
X-10631Y404463D01*
G01X-39607Y398321D02*
X-24509D01*
G01X-35546Y398400D02*
X-1D01*
G01X-27993Y400388D02*
X-39607D01*
G01X-35546Y400605D02*
X-1D01*
G01X-24509Y400683D02*
X-39607D01*
G01Y402258D02*
X-24509D01*
G01X-35546Y402337D02*
X-1D01*
G01X-39607Y403538D02*
X-24844D01*
G01X-35546Y404542D02*
X-1D01*
G01X-24509Y404620D02*
X-39607D01*
G01X-36561Y414453D02*
X-39020Y416174D01*
G01X-38108Y406894D02*
X-35351Y406628D01*
G01X-38108Y410831D02*
X-35351Y410565D01*
G01X-38108Y422642D02*
X-35351Y422376D01*
G01X-38426Y424306D02*
Y421943D01*
G01Y412494D02*
Y410132D01*
G01Y408557D02*
Y406195D01*
G01X-38108Y423607D02*
Y422642D01*
G01Y411796D02*
Y410831D01*
G01Y407859D02*
Y406894D01*
G01X-37871Y423630D02*
Y422619D01*
G01Y411819D02*
Y410808D01*
G01Y407881D02*
Y406871D01*
G01X-36812Y703664D02*
Y420006D01*
G01X-35595Y423849D02*
Y422400D01*
G01Y412038D02*
Y410589D01*
G01Y408101D02*
Y406652D01*
G01X-35546Y424306D02*
Y421943D01*
G01Y412494D02*
Y410132D01*
G01Y408557D02*
Y406195D01*
G01X-35434Y419719D02*
Y414719D01*
G01X-35357Y423872D02*
Y422377D01*
G01Y412061D02*
Y410566D01*
G01Y408124D02*
Y406629D01*
G01X-34607Y408479D02*
Y406274D01*
G01Y410211D02*
Y412416D01*
G01Y422022D02*
Y424227D01*
G01X-34136Y423886D02*
Y422363D01*
G01Y412075D02*
Y410552D01*
G01Y408138D02*
Y406615D01*
G01X-33153Y423897D02*
Y422352D01*
G01Y412086D02*
Y410541D01*
G01Y408149D02*
Y406604D01*
G01X-32319Y423906D02*
Y422343D01*
G01Y412095D02*
Y410531D01*
G01Y408158D02*
Y406594D01*
G01X-31941Y423910D02*
Y422338D01*
G01Y412099D02*
Y410527D01*
G01Y408162D02*
Y406590D01*
G01X-35351Y408124D02*
X-38108Y407859D01*
G01X-35351Y412061D02*
X-38108Y411796D01*
G01X-35351Y408124D02*
X-10631Y408400D01*
G01X-35351Y412061D02*
X-10631Y412337D01*
G01X-35351Y423872D02*
X-10631Y424148D01*
G01X-39607Y406195D02*
X-24509D01*
G01X-35546Y406274D02*
X-1D01*
G01X-39607Y407514D02*
X-24844D01*
G01X-35546Y408479D02*
X-1D01*
G01X-24509Y408557D02*
X-39607D01*
G01Y410132D02*
X-24509D01*
G01X-35546Y410211D02*
X-1D01*
G01X-39607Y410664D02*
X-27993D01*
G01X-35546Y412416D02*
X-1D01*
G01X-24509Y412494D02*
X-39607D01*
G01X-8899Y413912D02*
X-34845D01*
G01X-35434Y414719D02*
X-1D01*
G01Y419719D02*
X-35434D01*
G01X-34845Y420723D02*
X-8899D01*
G01X-39607Y421943D02*
X-24509D01*
G01X-35546Y422022D02*
X-1D01*
G01X-27993Y424010D02*
X-39607D01*
G01X-35546Y424227D02*
X-1D01*
G01X-24509Y424306D02*
X-39607D01*
G01X-10631Y406353D02*
X-35351Y406628D01*
G01X-10631Y410290D02*
X-35351Y410565D01*
G01X-10631Y422101D02*
X-35351Y422376D01*
G01Y423872D02*
X-38108Y423607D01*
G01X-39020Y418460D02*
X-36561Y420181D01*
G01Y414453D02*
G03X-34845Y413912I1716J2451D01*
G01Y420723D02*
G03X-36561Y420181I1J-2992D01*
G01X-39020Y418432D02*
G03Y416174I791J-1129D01*
G01X-38108Y426579D02*
X-35351Y426313D01*
G01X-38108Y430516D02*
X-35351Y430250D01*
G01X-38108Y434453D02*
X-35351Y434187D01*
G01X-38108Y438390D02*
X-35351Y438124D01*
G01X-38108Y442327D02*
X-35351Y442061D01*
G01X-38426Y443991D02*
Y441628D01*
G01Y440054D02*
Y437691D01*
G01Y436117D02*
Y433754D01*
G01Y432180D02*
Y429817D01*
G01Y428243D02*
Y425880D01*
G01X-38108Y443292D02*
Y442327D01*
G01Y439355D02*
Y438390D01*
G01Y435418D02*
Y434453D01*
G01Y431481D02*
Y430516D01*
G01Y427544D02*
Y426579D01*
G01X-37871Y443315D02*
Y442304D01*
G01Y439378D02*
Y438367D01*
G01Y435441D02*
Y434430D01*
G01Y427567D02*
Y426556D01*
G01Y431504D02*
Y430493D01*
G01X-35595Y443534D02*
Y442085D01*
G01Y439597D02*
Y438148D01*
G01Y435660D02*
Y434211D01*
G01Y431723D02*
Y430274D01*
G01Y427786D02*
Y426337D01*
G01X-35546Y443991D02*
Y441628D01*
G01Y440054D02*
Y437691D01*
G01Y436117D02*
Y433754D01*
G01Y432180D02*
Y429817D01*
G01Y428243D02*
Y425880D01*
G01X-35357Y443557D02*
Y442062D01*
G01Y439620D02*
Y438125D01*
G01Y435683D02*
Y434188D01*
G01Y431746D02*
Y430251D01*
G01Y427809D02*
Y426314D01*
G01X-34607Y443912D02*
Y441707D01*
G01Y439975D02*
Y437770D01*
G01Y436038D02*
Y433833D01*
G01Y432101D02*
Y429896D01*
G01Y428164D02*
Y425959D01*
G01X-34136Y443571D02*
Y442048D01*
G01Y439634D02*
Y438111D01*
G01Y435697D02*
Y434174D01*
G01Y427823D02*
Y426300D01*
G01Y431760D02*
Y430237D01*
G01X-33153Y443582D02*
Y442037D01*
G01Y439645D02*
Y438100D01*
G01Y435708D02*
Y434163D01*
G01Y431771D02*
Y430226D01*
G01Y427834D02*
Y426289D01*
G01X-32319Y443591D02*
Y442028D01*
G01Y439654D02*
Y438091D01*
G01Y435717D02*
Y434154D01*
G01Y427843D02*
Y426280D01*
G01Y431780D02*
Y430217D01*
G01X-31941Y443595D02*
Y442023D01*
G01Y439658D02*
Y438086D01*
G01Y435721D02*
Y434149D01*
G01Y427847D02*
Y426275D01*
G01Y431784D02*
Y430212D01*
G01X-35351Y427809D02*
X-10631Y428085D01*
G01X-35351Y431746D02*
X-10631Y432022D01*
G01X-35351Y435683D02*
X-10631Y435959D01*
G01X-35351Y439620D02*
X-10631Y439896D01*
G01X-35351Y443557D02*
X-10631Y443833D01*
G01X-39607Y425880D02*
X-24509D01*
G01X-35546Y425959D02*
X-1D01*
G01X-39607Y427160D02*
X-24844D01*
G01X-35546Y428164D02*
X-1D01*
G01X-24509Y428243D02*
X-39607D01*
G01Y429817D02*
X-24509D01*
G01X-35546Y429896D02*
X-1D01*
G01X-39607Y431136D02*
X-24844D01*
G01X-35546Y432101D02*
X-1D01*
G01X-24509Y432180D02*
X-39607D01*
G01Y433754D02*
X-24509D01*
G01X-35546Y433833D02*
X-1D01*
G01X-39607Y434286D02*
X-27993D01*
G01X-35546Y436038D02*
X-1D01*
G01X-24509Y436117D02*
X-39607D01*
G01Y437691D02*
X-24509D01*
G01X-35546Y437770D02*
X-1D01*
G01X-35546Y439975D02*
X-1D01*
G01X-24509Y440054D02*
X-39607D01*
G01Y441628D02*
X-24509D01*
G01X-35546Y441707D02*
X-1D01*
G01X-35546Y443912D02*
X-1D01*
G01X-24509Y443991D02*
X-39607D01*
G01X-10631Y426038D02*
X-35351Y426313D01*
G01X-10631Y429975D02*
X-35351Y430250D01*
G01X-10631Y433912D02*
X-35351Y434187D01*
G01X-10631Y437849D02*
X-35351Y438124D01*
G01X-10631Y441786D02*
X-35351Y442061D01*
G01Y427809D02*
X-38108Y427544D01*
G01X-35351Y431746D02*
X-38108Y431481D01*
G01X-35351Y435683D02*
X-38108Y435418D01*
G01X-35351Y439620D02*
X-38108Y439355D01*
G01X-35351Y443557D02*
X-38108Y443292D01*
G01Y446264D02*
X-35351Y445998D01*
G01X-38426Y467613D02*
Y465250D01*
G01Y463676D02*
Y461313D01*
G01Y459739D02*
Y457376D01*
G01Y451865D02*
Y449502D01*
G01Y455802D02*
Y453439D01*
G01Y447928D02*
Y445565D01*
G01X-38108Y462977D02*
Y462012D01*
G01Y459040D02*
Y458075D01*
G01Y455103D02*
Y454138D01*
G01Y451166D02*
Y450201D01*
G01Y447229D02*
Y446264D01*
G01X-37871Y463000D02*
Y461989D01*
G01Y459063D02*
Y458052D01*
G01Y451189D02*
Y450178D01*
G01Y455126D02*
Y454115D01*
G01Y447252D02*
Y446241D01*
G01X-35595Y463219D02*
Y461770D01*
G01Y459282D02*
Y457833D01*
G01Y455345D02*
Y453896D01*
G01Y451408D02*
Y449959D01*
G01Y447471D02*
Y446022D01*
G01X-35546Y467613D02*
Y465250D01*
G01Y463676D02*
Y461313D01*
G01Y459739D02*
Y457376D01*
G01Y455802D02*
Y453439D01*
G01Y451865D02*
Y449502D01*
G01Y447928D02*
Y445565D01*
G01X-35357Y463242D02*
Y461747D01*
G01Y459305D02*
Y457810D01*
G01Y455368D02*
Y453873D01*
G01Y451431D02*
Y449936D01*
G01Y447494D02*
Y445999D01*
G01X-34607Y463597D02*
Y461392D01*
G01Y459660D02*
Y457455D01*
G01Y451786D02*
Y449581D01*
G01Y455723D02*
Y453518D01*
G01Y447849D02*
Y445644D01*
G01X-34136Y463256D02*
Y461733D01*
G01Y459319D02*
Y457796D01*
G01Y451445D02*
Y449922D01*
G01Y455382D02*
Y453859D01*
G01Y447508D02*
Y445985D01*
G01X-33153Y463267D02*
Y461722D01*
G01Y459330D02*
Y457785D01*
G01Y455393D02*
Y453848D01*
G01Y451456D02*
Y449911D01*
G01Y447519D02*
Y445974D01*
G01X-32319Y463276D02*
Y461713D01*
G01Y459339D02*
Y457776D01*
G01Y451465D02*
Y449902D01*
G01Y455402D02*
Y453839D01*
G01Y447528D02*
Y445965D01*
G01X-31941Y463280D02*
Y461708D01*
G01Y459343D02*
Y457771D01*
G01Y451469D02*
Y449897D01*
G01Y455406D02*
Y453834D01*
G01Y447532D02*
Y445960D01*
G01X-35351Y447494D02*
X-10631Y447770D01*
G01X-35351Y451431D02*
X-10631Y451707D01*
G01X-35351Y455369D02*
X-10631Y455644D01*
G01X-35351Y459306D02*
X-10631Y459581D01*
G01X-35351Y463243D02*
X-10631Y463518D01*
G01X-39607Y445565D02*
X-24509D01*
G01X-35546Y445644D02*
X-1D01*
G01X-27993Y447632D02*
X-39607D01*
G01X-35546Y447849D02*
X-1D01*
G01X-24509Y447928D02*
X-39607D01*
G01Y449502D02*
X-24509D01*
G01X-35546Y449581D02*
X-1D01*
G01X-39607Y450782D02*
X-24844D01*
G01X-35546Y451786D02*
X-1D01*
G01X-24509Y451865D02*
X-39607D01*
G01Y453439D02*
X-24509D01*
G01X-35546Y453518D02*
X-1D01*
G01X-39607Y454758D02*
X-24844D01*
G01X-35546Y455723D02*
X-1D01*
G01X-24509Y455802D02*
X-39607D01*
G01Y457376D02*
X-24509D01*
G01X-35546Y457455D02*
X-1D01*
G01X-39607Y457908D02*
X-27993D01*
G01X-35546Y459660D02*
X-1D01*
G01X-24509Y459739D02*
X-39607D01*
G01Y461313D02*
X-24509D01*
G01X-35546Y461392D02*
X-1D01*
G01X-35546Y463597D02*
X-1D01*
G01X-24509Y463676D02*
X-39607D01*
G01Y465250D02*
X-24509D01*
G01X-10631Y445723D02*
X-35351Y445998D01*
G01X-10631Y449660D02*
X-35351Y449935D01*
G01X-10631Y453597D02*
X-35351Y453872D01*
G01X-10631Y457534D02*
X-35351Y457809D01*
G01X-10631Y461471D02*
X-35351Y461746D01*
G01X-38108Y450201D02*
X-35351Y449935D01*
G01X-38108Y454138D02*
X-35351Y453872D01*
G01X-38108Y458075D02*
X-35351Y457809D01*
G01X-38108Y462012D02*
X-35351Y461746D01*
G01Y447494D02*
X-38108Y447229D01*
G01X-35351Y451431D02*
X-38108Y451166D01*
G01X-35351Y455369D02*
X-38108Y455103D01*
G01X-35351Y459306D02*
X-38108Y459040D01*
G01X-35351Y463243D02*
X-38108Y462977D01*
G01X-38426Y475487D02*
Y473124D01*
G01Y479424D02*
Y477061D01*
G01Y471550D02*
Y469187D01*
G01X-38108Y478725D02*
Y477760D01*
G01Y474788D02*
Y473823D01*
G01Y470851D02*
Y469886D01*
G01Y466914D02*
Y465949D01*
G01X-37871Y474811D02*
Y473800D01*
G01Y478748D02*
Y477737D01*
G01Y470874D02*
Y469863D01*
G01Y466937D02*
Y465926D01*
G01X-35595Y478967D02*
Y477518D01*
G01Y475030D02*
Y473581D01*
G01Y471093D02*
Y469644D01*
G01Y467156D02*
Y465707D01*
G01X-35546Y479424D02*
Y477061D01*
G01Y475487D02*
Y473124D01*
G01Y471550D02*
Y469187D01*
G01X-35357Y478990D02*
Y477495D01*
G01Y475053D02*
Y473558D01*
G01Y471116D02*
Y469621D01*
G01Y467179D02*
Y465684D01*
G01X-34607Y475408D02*
Y473203D01*
G01Y479345D02*
Y477140D01*
G01Y471471D02*
Y469266D01*
G01Y467534D02*
Y465329D01*
G01X-34136Y479004D02*
Y477481D01*
G01Y475067D02*
Y473544D01*
G01Y471130D02*
Y469607D01*
G01Y467193D02*
Y465670D01*
G01X-33153Y479015D02*
Y477470D01*
G01Y475078D02*
Y473533D01*
G01Y471141D02*
Y469596D01*
G01Y467204D02*
Y465659D01*
G01X-32319Y479024D02*
Y477461D01*
G01Y475087D02*
Y473524D01*
G01Y471150D02*
Y469587D01*
G01Y467213D02*
Y465650D01*
G01X-31941Y479028D02*
Y477456D01*
G01Y475091D02*
Y473519D01*
G01Y471154D02*
Y469582D01*
G01Y467217D02*
Y465645D01*
G01X-35546Y465329D02*
X-1D01*
G01X-35546Y467534D02*
X-1D01*
G01X-24509Y467613D02*
X-39607D01*
G01Y469187D02*
X-24509D01*
G01X-35546Y469266D02*
X-1D01*
G01X-27993Y471254D02*
X-39607D01*
G01X-35546Y471471D02*
X-1D01*
G01X-24509Y471550D02*
X-39607D01*
G01Y473124D02*
X-24509D01*
G01X-10631Y465408D02*
X-35351Y465683D01*
G01X-10631Y469345D02*
X-35351Y469620D01*
G01X-10631Y473282D02*
X-35351Y473557D01*
G01X-10631Y477219D02*
X-35351Y477494D01*
G01X-38108Y465949D02*
X-35351Y465683D01*
G01X-38108Y469886D02*
X-35351Y469620D01*
G01X-38108Y473823D02*
X-35351Y473557D01*
G01X-38108Y477760D02*
X-35351Y477494D01*
G01Y467180D02*
X-38108Y466914D01*
G01X-35351Y471117D02*
X-38108Y470851D01*
G01X-35351Y475054D02*
X-38108Y474788D01*
G01X-35351Y478991D02*
X-38108Y478725D01*
G01X-35351Y467180D02*
X-10631Y467455D01*
G01X-35351Y471117D02*
X-10631Y471392D01*
G01X-35351Y475054D02*
X-10631Y475329D01*
G01X-35351Y478991D02*
X-10631Y479266D01*
G01X-35546Y473203D02*
X-1D01*
G01X-39607Y474404D02*
X-24844D01*
G01X-35546Y475408D02*
X-1D01*
G01X-24509Y475487D02*
X-39607D01*
G01Y477061D02*
X-24509D01*
G01X-35546Y477140D02*
X-1D01*
G01X-39607Y478380D02*
X-24844D01*
G01X-35546Y479345D02*
X-1D01*
G01X-24509Y479424D02*
X-39607D01*
G01X-27265Y404620D02*
Y402258D01*
G01Y400683D02*
Y398321D01*
G01X-26943Y404281D02*
Y402597D01*
G01Y400344D02*
Y398660D01*
G01X-26566Y400348D02*
Y398656D01*
G01Y404285D02*
Y402593D01*
G01X-24509Y404620D02*
Y402258D01*
G01Y400683D02*
Y398321D01*
G01X-24122Y404312D02*
Y402566D01*
G01Y400375D02*
Y398629D01*
G01X-23684Y404317D02*
Y402561D01*
G01Y400380D02*
Y398624D01*
G01X-12993Y404857D02*
Y404542D01*
G01Y400920D02*
Y400605D01*
G01Y402337D02*
Y402022D01*
G01Y398400D02*
Y398085D01*
G01X-12280Y404444D02*
Y402434D01*
G01Y400507D02*
Y398497D01*
G01X-11843Y404449D02*
Y402429D01*
G01Y400512D02*
Y398492D01*
G01X-12993Y398085D02*
X-1D01*
G01Y400920D02*
X-12993D01*
G01Y402022D02*
X-1D01*
G01Y404857D02*
X-12993D01*
G01X-27993Y407514D02*
Y427160D01*
G01X-27265Y424306D02*
Y421943D01*
G01Y412494D02*
Y410132D01*
G01Y408557D02*
Y406195D01*
G01X-26943Y423966D02*
Y422282D01*
G01Y412155D02*
Y410471D01*
G01Y408218D02*
Y406534D01*
G01X-26566Y423970D02*
Y422278D01*
G01Y412159D02*
Y410467D01*
G01Y408222D02*
Y406530D01*
G01X-24844Y407514D02*
Y427160D01*
G01X-24509Y424306D02*
Y421943D01*
G01Y412494D02*
Y410132D01*
G01Y408557D02*
Y406195D01*
G01X-24122Y423997D02*
Y422251D01*
G01Y412186D02*
Y410440D01*
G01Y408249D02*
Y406503D01*
G01X-23684Y424002D02*
Y422246D01*
G01Y412191D02*
Y410435D01*
G01Y408254D02*
Y406498D01*
G01X-12993Y424542D02*
Y424227D01*
G01Y422022D02*
Y421707D01*
G01Y408794D02*
Y408479D01*
G01Y410211D02*
Y409896D01*
G01Y412731D02*
Y412416D01*
G01Y406274D02*
Y405959D01*
G01X-12280Y424130D02*
Y422119D01*
G01Y412319D02*
Y410308D01*
G01Y408381D02*
Y406371D01*
G01X-11843Y424134D02*
Y422114D01*
G01Y412323D02*
Y410303D01*
G01Y408386D02*
Y406366D01*
G01X-12993Y405959D02*
X-1D01*
G01Y408794D02*
X-12993D01*
G01Y409896D02*
X-1D01*
G01Y412731D02*
X-12993D01*
G01Y421707D02*
X-1D01*
G01Y424542D02*
X-12993D01*
G01X-27993Y431136D02*
Y450782D01*
G01X-27265Y443991D02*
Y441628D01*
G01Y440054D02*
Y437691D01*
G01Y436117D02*
Y433754D01*
G01Y432180D02*
Y429817D01*
G01Y428243D02*
Y425880D01*
G01X-26943Y443651D02*
Y441967D01*
G01Y439714D02*
Y438030D01*
G01Y435777D02*
Y434093D01*
G01Y431840D02*
Y430156D01*
G01Y427903D02*
Y426219D01*
G01X-26566Y443655D02*
Y441963D01*
G01Y439718D02*
Y438026D01*
G01Y435781D02*
Y434089D01*
G01Y431844D02*
Y430152D01*
G01Y427907D02*
Y426215D01*
G01X-24844Y431136D02*
Y450782D01*
G01X-24509Y443991D02*
Y441628D01*
G01Y440054D02*
Y437691D01*
G01Y436117D02*
Y433754D01*
G01Y432180D02*
Y429817D01*
G01Y428243D02*
Y425880D01*
G01X-24122Y443682D02*
Y441936D01*
G01Y439745D02*
Y437999D01*
G01Y435808D02*
Y434062D01*
G01Y427934D02*
Y426188D01*
G01Y431871D02*
Y430125D01*
G01X-23684Y443687D02*
Y441931D01*
G01Y439750D02*
Y437994D01*
G01Y435813D02*
Y434057D01*
G01Y427939D02*
Y426183D01*
G01Y431876D02*
Y430120D01*
G01X-12993Y441707D02*
Y441392D01*
G01Y444227D02*
Y443912D01*
G01Y437770D02*
Y437455D01*
G01Y440290D02*
Y439975D01*
G01Y433833D02*
Y433518D01*
G01Y436353D02*
Y436038D01*
G01Y432416D02*
Y432101D01*
G01Y429896D02*
Y429581D01*
G01Y428479D02*
Y428164D01*
G01Y425959D02*
Y425644D01*
G01X-12280Y443815D02*
Y441804D01*
G01Y439878D02*
Y437867D01*
G01Y435941D02*
Y433930D01*
G01Y428067D02*
Y426056D01*
G01Y432004D02*
Y429993D01*
G01X-11843Y443819D02*
Y441799D01*
G01Y439882D02*
Y437862D01*
G01Y435945D02*
Y433925D01*
G01Y432008D02*
Y429988D01*
G01Y428071D02*
Y426051D01*
G01X-12993Y425644D02*
X-1D01*
G01Y428479D02*
X-12993D01*
G01Y429581D02*
X-1D01*
G01Y432416D02*
X-12993D01*
G01Y433518D02*
X-1D01*
G01Y436353D02*
X-12993D01*
G01Y437455D02*
X-1D01*
G01Y440290D02*
X-12993D01*
G01Y441392D02*
X-1D01*
G01Y444227D02*
X-12993D01*
G01X-27993Y454758D02*
Y474404D01*
G01X-27265Y467613D02*
Y465250D01*
G01Y463676D02*
Y461313D01*
G01Y459739D02*
Y457376D01*
G01Y455802D02*
Y453439D01*
G01Y451865D02*
Y449502D01*
G01Y447928D02*
Y445565D01*
G01X-26943Y463336D02*
Y461652D01*
G01Y459399D02*
Y457715D01*
G01Y455462D02*
Y453778D01*
G01Y451525D02*
Y449841D01*
G01Y447588D02*
Y445904D01*
G01X-26566Y463340D02*
Y461648D01*
G01Y459403D02*
Y457711D01*
G01Y455466D02*
Y453774D01*
G01Y451529D02*
Y449837D01*
G01Y447592D02*
Y445900D01*
G01X-24844Y454758D02*
Y474404D01*
G01X-24509Y467613D02*
Y465250D01*
G01Y463676D02*
Y461313D01*
G01Y459739D02*
Y457376D01*
G01Y455802D02*
Y453439D01*
G01Y451865D02*
Y449502D01*
G01Y447928D02*
Y445565D01*
G01X-24122Y463367D02*
Y461621D01*
G01Y455493D02*
Y453747D01*
G01Y459430D02*
Y457684D01*
G01Y451556D02*
Y449810D01*
G01Y447619D02*
Y445873D01*
G01X-23684Y463372D02*
Y461616D01*
G01Y455498D02*
Y453742D01*
G01Y459435D02*
Y457679D01*
G01Y451561D02*
Y449805D01*
G01Y447624D02*
Y445868D01*
G01X-12993Y465329D02*
Y465014D01*
G01Y461392D02*
Y461077D01*
G01Y463912D02*
Y463597D01*
G01Y457455D02*
Y457140D01*
G01Y459975D02*
Y459660D01*
G01Y456038D02*
Y455723D01*
G01Y453518D02*
Y453203D01*
G01Y452101D02*
Y451786D01*
G01Y449581D02*
Y449266D01*
G01Y448164D02*
Y447849D01*
G01Y445644D02*
Y445329D01*
G01X-12280Y463500D02*
Y461489D01*
G01Y459563D02*
Y457552D01*
G01Y455626D02*
Y453615D01*
G01Y451689D02*
Y449678D01*
G01Y447752D02*
Y445741D01*
G01X-11843Y463504D02*
Y461484D01*
G01Y459567D02*
Y457547D01*
G01Y455630D02*
Y453610D01*
G01Y451693D02*
Y449673D01*
G01Y447756D02*
Y445736D01*
G01X-12993Y445329D02*
X-1D01*
G01Y448164D02*
X-12993D01*
G01Y449266D02*
X-1D01*
G01Y452101D02*
X-12993D01*
G01Y453203D02*
X-1D01*
G01Y456038D02*
X-12993D01*
G01Y457140D02*
X-1D01*
G01Y459975D02*
X-12993D01*
G01Y461077D02*
X-1D01*
G01Y463912D02*
X-12993D01*
G01Y465014D02*
X-1D01*
G01X-27993Y478380D02*
Y498026D01*
G01X-27265Y479424D02*
Y477061D01*
G01Y475487D02*
Y473124D01*
G01Y471550D02*
Y469187D01*
G01X-26943Y479084D02*
Y477400D01*
G01Y475147D02*
Y473463D01*
G01Y471210D02*
Y469526D01*
G01Y467273D02*
Y465589D01*
G01X-26566Y479088D02*
Y477396D01*
G01Y475151D02*
Y473459D01*
G01Y471214D02*
Y469522D01*
G01Y467277D02*
Y465585D01*
G01X-24844Y478380D02*
Y498026D01*
G01X-24509Y479424D02*
Y477061D01*
G01Y475487D02*
Y473124D01*
G01Y471550D02*
Y469187D01*
G01X-24122Y479115D02*
Y477369D01*
G01Y475178D02*
Y473432D01*
G01Y471241D02*
Y469495D01*
G01Y467304D02*
Y465558D01*
G01X-23684Y479120D02*
Y477364D01*
G01Y475183D02*
Y473427D01*
G01Y471246D02*
Y469490D01*
G01Y467309D02*
Y465553D01*
G01X-12993Y479660D02*
Y479345D01*
G01Y477140D02*
Y476825D01*
G01Y475723D02*
Y475408D01*
G01Y473203D02*
Y472888D01*
G01Y471786D02*
Y471471D01*
G01Y469266D02*
Y468951D01*
G01Y467849D02*
Y467534D01*
G01X-12280Y479248D02*
Y477237D01*
G01Y475311D02*
Y473300D01*
G01Y471374D02*
Y469363D01*
G01Y467437D02*
Y465426D01*
G01X-11843Y479252D02*
Y477232D01*
G01Y475315D02*
Y473295D01*
G01Y471378D02*
Y469358D01*
G01Y467441D02*
Y465421D01*
G01X-1Y467849D02*
X-12993D01*
G01Y468951D02*
X-1D01*
G01Y471786D02*
X-12993D01*
G01Y472888D02*
X-1D01*
G01Y475723D02*
X-12993D01*
G01Y476825D02*
X-1D01*
G01Y479660D02*
X-12993D01*
G01X-10631Y398479D02*
X-9844Y398124D01*
G01X-10631Y402416D02*
X-9844Y402061D01*
G01X-4259Y398282D02*
X-3378Y398046D01*
G01X-4259Y402219D02*
X-3378Y401983D01*
G01X-2197Y398439D02*
X-1970Y398046D01*
G01X-3151Y400565D02*
X-3378Y400959D01*
G01X-2197Y402376D02*
X-1970Y401983D01*
G01X-3151Y404502D02*
X-3378Y404896D01*
G01X-4725Y397809D02*
X-6694Y398124D01*
G01X-4725Y401746D02*
X-6694Y402061D01*
G01X-10531Y404508D02*
Y402370D01*
G01Y400571D02*
Y398433D01*
G01X-6694Y404817D02*
Y404227D01*
G01Y400880D02*
Y400290D01*
G01Y402652D02*
Y402061D01*
G01Y398715D02*
Y398124D01*
G01X-4725Y405132D02*
Y404227D01*
G01Y401195D02*
Y400290D01*
G01Y402652D02*
Y401746D01*
G01Y398715D02*
Y397809D01*
G01X-3757Y404542D02*
Y402337D01*
G01Y400605D02*
Y398400D01*
G01X-1Y398046D02*
X-1970D01*
G01X-6694Y398124D02*
X-9844D01*
G01X-4259Y398282D02*
X-4725D01*
G01X-2197Y398439D02*
X-3151D01*
G01X-4725Y398715D02*
X-6694D01*
G01X15077Y398833D02*
X8523D01*
G01D02*
X-1D01*
G01D02*
X-985D01*
G01Y400172D02*
X-1D01*
G01D02*
X8523D01*
G01D02*
X12600D01*
G01X-4725Y400290D02*
X-6694D01*
G01X-3151Y400565D02*
X-2197D01*
G01X-4725Y400723D02*
X-4259D01*
G01X-9844Y400880D02*
X-6694D01*
G01X-1970Y400959D02*
X-1D01*
G01Y401983D02*
X-1970D01*
G01X-6694Y402061D02*
X-9844D01*
G01X-4259Y402219D02*
X-4725D01*
G01X-2197Y402376D02*
X-3151D01*
G01X-4725Y402652D02*
X-6694D01*
G01X15077Y402770D02*
X8523D01*
G01D02*
X-1D01*
G01D02*
X-985D01*
G01Y404109D02*
X-1D01*
G01D02*
X8523D01*
G01D02*
X12600D01*
G01X-4725Y404227D02*
X-6694D01*
G01X-3151Y404502D02*
X-2197D01*
G01X-4725Y404660D02*
X-4259D01*
G01X-9844Y404817D02*
X-6694D01*
G01X-1970Y404896D02*
X-1D01*
G01X-2521Y404542D02*
Y402337D01*
G01Y400605D02*
Y398400D01*
G01X-2251Y404857D02*
Y402022D01*
G01Y400920D02*
Y398085D01*
G01X-985Y404109D02*
Y402770D01*
G01Y400172D02*
Y398833D01*
G01X8523Y404109D02*
Y402770D01*
G01Y400172D02*
Y398833D01*
G01X-6694Y400880D02*
X-4725Y401195D01*
G01X-6694Y404817D02*
X-4725Y405132D01*
G01X-3378Y400959D02*
X-4259Y400723D01*
G01X-3378Y404896D02*
X-4259Y404660D01*
G01X-1970Y404896D02*
X-2197Y404502D01*
G01X-3378Y401983D02*
X-3151Y402376D01*
G01X-1970Y400959D02*
X-2197Y400565D01*
G01X-3378Y398046D02*
X-3151Y398439D01*
G01X-9844Y404817D02*
X-10631Y404463D01*
G01X-9844Y400880D02*
X-10631Y400526D01*
G01Y406353D02*
X-9844Y405998D01*
G01X-10631Y410290D02*
X-9844Y409935D01*
G01X576Y422455D02*
X1968Y421063D01*
G01X576Y422455D02*
X-1Y423031D01*
G01X-4259Y406156D02*
X-3378Y405920D01*
G01X-4259Y410093D02*
X-3378Y409857D01*
G01X-4259Y421904D02*
X-3378Y421668D01*
G01X-10631Y422101D02*
X-9844Y421746D01*
G01X-2197Y406313D02*
X-1970Y405920D01*
G01X-3151Y408439D02*
X-3378Y408833D01*
G01X-2197Y410250D02*
X-1970Y409857D01*
G01X-3151Y412376D02*
X-3378Y412770D01*
G01X-2197Y422061D02*
X-1970Y421668D01*
G01X-3151Y424187D02*
X-3378Y424581D01*
G01X-4725Y405683D02*
X-6694Y405998D01*
G01X-4725Y409620D02*
X-6694Y409935D01*
G01X-4725Y421431D02*
X-6694Y421746D01*
G01X-10531Y424193D02*
Y422056D01*
G01Y412382D02*
Y410244D01*
G01Y408445D02*
Y406307D01*
G01X-8899Y420723D02*
Y702947D01*
G01X-6694Y424502D02*
Y423912D01*
G01Y422337D02*
Y421746D01*
G01Y412691D02*
Y412101D01*
G01Y410526D02*
Y409935D01*
G01Y408754D02*
Y408164D01*
G01Y406589D02*
Y405998D01*
G01X-4725Y424817D02*
Y423912D01*
G01Y422337D02*
Y421431D01*
G01Y413006D02*
Y412101D01*
G01Y410526D02*
Y409620D01*
G01Y409069D02*
Y408164D01*
G01Y406589D02*
Y405683D01*
G01X-3757Y424227D02*
Y422022D01*
G01Y412416D02*
Y410211D01*
G01Y408479D02*
Y406274D01*
G01X-1Y405920D02*
X-1970D01*
G01X-6694Y405998D02*
X-9844D01*
G01X-4259Y406156D02*
X-4725D01*
G01X-2197Y406313D02*
X-3151D01*
G01X-4725Y406589D02*
X-6694D01*
G01X15077Y406707D02*
X8523D01*
G01D02*
X-1D01*
G01D02*
X-985D01*
G01Y408046D02*
X-1D01*
G01D02*
X8523D01*
G01D02*
X12600D01*
G01X-4725Y408164D02*
X-6694D01*
G01X-3151Y408439D02*
X-2197D01*
G01X-4725Y408597D02*
X-4259D01*
G01X-9844Y408754D02*
X-6694D01*
G01X-1970Y408833D02*
X-1D01*
G01Y409857D02*
X-1970D01*
G01X-6694Y409935D02*
X-9844D01*
G01X-4259Y410093D02*
X-4725D01*
G01X-2197Y410250D02*
X-3151D01*
G01X-4725Y410526D02*
X-6694D01*
G01X15077Y410644D02*
X8523D01*
G01D02*
X-1D01*
G01D02*
X-985D01*
G01Y411983D02*
X-1D01*
G01D02*
X8523D01*
G01D02*
X12600D01*
G01X-4725Y412101D02*
X-6694D01*
G01X-3151Y412376D02*
X-2197D01*
G01X-4725Y412534D02*
X-4259D01*
G01X-9844Y412691D02*
X-6694D01*
G01X-1970Y412770D02*
X-1D01*
G01X1968Y413583D02*
X19881D01*
G01X15550Y413695D02*
X1968D01*
G01D02*
X-1D01*
G01Y420703D02*
X15550D01*
G01X1968Y421063D02*
X19881D01*
G01X-1Y421668D02*
X-1970D01*
G01X-6694Y421746D02*
X-9844D01*
G01X-4259Y421904D02*
X-4725D01*
G01X-2197Y422061D02*
X-3151D01*
G01X-4725Y422337D02*
X-6694D01*
G01X15077Y422455D02*
X8523D01*
G01D02*
X-1D01*
G01D02*
X-985D01*
G01Y423794D02*
X-1D01*
G01D02*
X8523D01*
G01D02*
X12600D01*
G01X-4725Y423912D02*
X-6694D01*
G01X-3151Y424187D02*
X-2197D01*
G01X-4725Y424345D02*
X-4259D01*
G01X-9844Y424502D02*
X-6694D01*
G01X-1970Y424581D02*
X-1D01*
G01X-2521Y424227D02*
Y422022D01*
G01Y412416D02*
Y410211D01*
G01Y408479D02*
Y406274D01*
G01X-2251Y424542D02*
Y421707D01*
G01Y408794D02*
Y405959D01*
G01Y412731D02*
Y409896D01*
G01X-985Y423794D02*
Y422455D01*
G01Y411983D02*
Y410644D01*
G01Y408046D02*
Y406707D01*
G01X8523Y423794D02*
Y422455D01*
G01Y411983D02*
Y410644D01*
G01Y408046D02*
Y406707D01*
G01X-6694Y408754D02*
X-4725Y409069D01*
G01X-6694Y412691D02*
X-4725Y413006D01*
G01X-6694Y424502D02*
X-4725Y424817D01*
G01X-3378Y408833D02*
X-4259Y408597D01*
G01X-3378Y412770D02*
X-4259Y412534D01*
G01X-3378Y424581D02*
X-4259Y424345D01*
G01X-1970Y424581D02*
X-2197Y424187D01*
G01X-3378Y421668D02*
X-3151Y422061D01*
G01X-1970Y412770D02*
X-2197Y412376D01*
G01X-3378Y409857D02*
X-3151Y410250D01*
G01X-1970Y408833D02*
X-2197Y408439D01*
G01X-3378Y405920D02*
X-3151Y406313D01*
G01X1968Y413583D02*
X368Y411983D01*
G01X-1Y411614D02*
X368Y411983D01*
G01X-9844Y424502D02*
X-10631Y424148D01*
G01X-9844Y412691D02*
X-10631Y412337D01*
G01X-9844Y408754D02*
X-10631Y408400D01*
G01X-4259Y425841D02*
X-3378Y425605D01*
G01X-4259Y429778D02*
X-3378Y429542D01*
G01X-4259Y433715D02*
X-3378Y433479D01*
G01X-10631Y426038D02*
X-9844Y425683D01*
G01X-10631Y429975D02*
X-9844Y429620D01*
G01X-10631Y433912D02*
X-9844Y433557D01*
G01X-10631Y437849D02*
X-9844Y437494D01*
G01X-10631Y441786D02*
X-9844Y441431D01*
G01X-2197Y425998D02*
X-1970Y425605D01*
G01X-3151Y428124D02*
X-3378Y428518D01*
G01X-2197Y429935D02*
X-1970Y429542D01*
G01X-3151Y432061D02*
X-3378Y432455D01*
G01X-2197Y433872D02*
X-1970Y433479D01*
G01X-3151Y435998D02*
X-3378Y436392D01*
G01X-2197Y437809D02*
X-1970Y437416D01*
G01X-3151Y439935D02*
X-3378Y440329D01*
G01X-2197Y441746D02*
X-1970Y441353D01*
G01X-3151Y443872D02*
X-3378Y444266D01*
G01X-4725Y425369D02*
X-6694Y425683D01*
G01X-4725Y429306D02*
X-6694Y429620D01*
G01X-4725Y433243D02*
X-6694Y433557D01*
G01X-4725Y437180D02*
X-6694Y437494D01*
G01X-4725Y441117D02*
X-6694Y441431D01*
G01X-4725Y445054D02*
X-6694Y445369D01*
G01X-4259Y437652D02*
X-3378Y437416D01*
G01X-4259Y441589D02*
X-3378Y441353D01*
G01X-10531Y443878D02*
Y441741D01*
G01Y439941D02*
Y437804D01*
G01Y432067D02*
Y429930D01*
G01Y436004D02*
Y433867D01*
G01Y428130D02*
Y425993D01*
G01X-6694Y444187D02*
Y443597D01*
G01Y442022D02*
Y441431D01*
G01Y440250D02*
Y439660D01*
G01Y438085D02*
Y437494D01*
G01Y436313D02*
Y435723D01*
G01Y434148D02*
Y433557D01*
G01Y432376D02*
Y431786D01*
G01Y430211D02*
Y429620D01*
G01Y428439D02*
Y427849D01*
G01Y426274D02*
Y425683D01*
G01X-4725Y444502D02*
Y443597D01*
G01Y442022D02*
Y441117D01*
G01Y445959D02*
Y445054D01*
G01Y440565D02*
Y439660D01*
G01Y438085D02*
Y437180D01*
G01Y432691D02*
Y431786D01*
G01Y436628D02*
Y435723D01*
G01Y434148D02*
Y433243D01*
G01Y428754D02*
Y427849D01*
G01Y430211D02*
Y429306D01*
G01Y426274D02*
Y425369D01*
G01X-3757Y443912D02*
Y441707D01*
G01Y439975D02*
Y437770D01*
G01Y432101D02*
Y429896D01*
G01Y436038D02*
Y433833D01*
G01Y428164D02*
Y425959D01*
G01X-1Y425605D02*
X-1970D01*
G01X-6694Y425683D02*
X-9844D01*
G01X-4259Y425841D02*
X-4725D01*
G01X-2197Y425998D02*
X-3151D01*
G01X-4725Y426274D02*
X-6694D01*
G01X15077Y426392D02*
X8523D01*
G01D02*
X-1D01*
G01D02*
X-985D01*
G01Y427731D02*
X-1D01*
G01D02*
X8523D01*
G01D02*
X12600D01*
G01X-4725Y427849D02*
X-6694D01*
G01X-3151Y428124D02*
X-2197D01*
G01X-4725Y428282D02*
X-4259D01*
G01X-9844Y428439D02*
X-6694D01*
G01X-1970Y428518D02*
X-1D01*
G01Y429542D02*
X-1970D01*
G01X-6694Y429620D02*
X-9844D01*
G01X-4259Y429778D02*
X-4725D01*
G01X-2197Y429935D02*
X-3151D01*
G01X-4725Y430211D02*
X-6694D01*
G01X15077Y430329D02*
X8523D01*
G01D02*
X-1D01*
G01D02*
X-985D01*
G01Y431668D02*
X-1D01*
G01D02*
X8523D01*
G01D02*
X12600D01*
G01X-4725Y431786D02*
X-6694D01*
G01X-3151Y432061D02*
X-2197D01*
G01X-4725Y432219D02*
X-4259D01*
G01X-9844Y432376D02*
X-6694D01*
G01X-1970Y432455D02*
X-1D01*
G01Y433479D02*
X-1970D01*
G01X-6694Y433557D02*
X-9844D01*
G01X-4259Y433715D02*
X-4725D01*
G01X-2197Y433872D02*
X-3151D01*
G01X-4725Y434148D02*
X-6694D01*
G01X15077Y434266D02*
X8523D01*
G01D02*
X-1D01*
G01D02*
X-985D01*
G01Y435605D02*
X-1D01*
G01D02*
X8523D01*
G01D02*
X12600D01*
G01X-4725Y435723D02*
X-6694D01*
G01X-3151Y435998D02*
X-2197D01*
G01X-4725Y436156D02*
X-4259D01*
G01X-9844Y436313D02*
X-6694D01*
G01X-1970Y436392D02*
X-1D01*
G01Y437416D02*
X-1970D01*
G01X-6694Y437494D02*
X-9844D01*
G01X-4259Y437652D02*
X-4725D01*
G01X-2197Y437809D02*
X-3151D01*
G01X-4725Y438085D02*
X-6694D01*
G01X15077Y438203D02*
X8523D01*
G01D02*
X-1D01*
G01D02*
X-985D01*
G01Y439542D02*
X-1D01*
G01D02*
X8523D01*
G01D02*
X12600D01*
G01X-4725Y439660D02*
X-6694D01*
G01X-3151Y439935D02*
X-2197D01*
G01X-4725Y440093D02*
X-4259D01*
G01X-9844Y440250D02*
X-6694D01*
G01X-1970Y440329D02*
X-1D01*
G01Y441353D02*
X-1970D01*
G01X-6694Y441431D02*
X-9844D01*
G01X-4259Y441589D02*
X-4725D01*
G01X-2197Y441746D02*
X-3151D01*
G01X-4725Y442022D02*
X-6694D01*
G01X15077Y442140D02*
X8523D01*
G01D02*
X-1D01*
G01D02*
X-985D01*
G01Y443479D02*
X-1D01*
G01D02*
X8523D01*
G01D02*
X12600D01*
G01X-4725Y443597D02*
X-6694D01*
G01X-3151Y443872D02*
X-2197D01*
G01X-4725Y444030D02*
X-4259D01*
G01X-9844Y444187D02*
X-6694D01*
G01X-1970Y444266D02*
X-1D01*
G01X-2521Y443912D02*
Y441707D01*
G01Y439975D02*
Y437770D01*
G01Y432101D02*
Y429896D01*
G01Y436038D02*
Y433833D01*
G01Y428164D02*
Y425959D01*
G01X-2251Y444227D02*
Y441392D01*
G01Y440290D02*
Y437455D01*
G01Y436353D02*
Y433518D01*
G01Y432416D02*
Y429581D01*
G01Y428479D02*
Y425644D01*
G01X-985Y443479D02*
Y442140D01*
G01Y439542D02*
Y438203D01*
G01Y435605D02*
Y434266D01*
G01Y427731D02*
Y426392D01*
G01Y431668D02*
Y430329D01*
G01X8523Y443479D02*
Y442140D01*
G01Y439542D02*
Y438203D01*
G01Y435605D02*
Y434266D01*
G01Y431668D02*
Y430329D01*
G01Y427731D02*
Y426392D01*
G01X-6694Y428439D02*
X-4725Y428754D01*
G01X-6694Y432376D02*
X-4725Y432691D01*
G01X-6694Y436313D02*
X-4725Y436628D01*
G01X-6694Y440250D02*
X-4725Y440565D01*
G01X-6694Y444187D02*
X-4725Y444502D01*
G01X-3378Y428518D02*
X-4259Y428282D01*
G01X-3378Y432455D02*
X-4259Y432219D01*
G01X-3378Y436392D02*
X-4259Y436156D01*
G01X-3378Y440329D02*
X-4259Y440093D01*
G01X-3378Y444266D02*
X-4259Y444030D01*
G01X-1970Y444266D02*
X-2197Y443872D01*
G01X-3378Y441353D02*
X-3151Y441746D01*
G01X-1970Y440329D02*
X-2197Y439935D01*
G01X-3378Y437416D02*
X-3151Y437809D01*
G01X-1970Y436392D02*
X-2197Y435998D01*
G01X-3378Y433479D02*
X-3151Y433872D01*
G01X-1970Y432455D02*
X-2197Y432061D01*
G01X-3378Y429542D02*
X-3151Y429935D01*
G01X-1970Y428518D02*
X-2197Y428124D01*
G01X-3378Y425605D02*
X-3151Y425998D01*
G01X-9844Y444187D02*
X-10631Y443833D01*
G01X-9844Y440250D02*
X-10631Y439896D01*
G01X-9844Y436313D02*
X-10631Y435959D01*
G01X-9844Y432376D02*
X-10631Y432022D01*
G01X-9844Y428439D02*
X-10631Y428085D01*
G01Y445723D02*
X-9844Y445369D01*
G01X-10631Y449660D02*
X-9844Y449306D01*
G01X-10631Y453597D02*
X-9844Y453243D01*
G01X-10631Y457534D02*
X-9844Y457180D01*
G01X-10631Y461471D02*
X-9844Y461117D01*
G01X-10631Y465408D02*
X-9844Y465054D01*
G01X-2197Y445683D02*
X-1970Y445290D01*
G01X-3151Y447809D02*
X-3378Y448203D01*
G01X-2197Y449620D02*
X-1970Y449227D01*
G01X-3151Y451746D02*
X-3378Y452140D01*
G01X-2197Y453557D02*
X-1970Y453164D01*
G01X-3151Y455683D02*
X-3378Y456077D01*
G01X-2197Y457494D02*
X-1970Y457101D01*
G01X-3151Y459620D02*
X-3378Y460014D01*
G01X-2197Y461431D02*
X-1970Y461038D01*
G01X-3151Y463557D02*
X-3378Y463951D01*
G01X-2197Y465369D02*
X-1970Y464975D01*
G01X-4725Y448991D02*
X-6694Y449306D01*
G01X-4725Y452928D02*
X-6694Y453243D01*
G01X-4725Y456865D02*
X-6694Y457180D01*
G01X-4725Y460802D02*
X-6694Y461117D01*
G01X-4725Y464739D02*
X-6694Y465054D01*
G01X-4259Y445526D02*
X-3378Y445290D01*
G01X-4259Y449463D02*
X-3378Y449227D01*
G01X-4259Y453400D02*
X-3378Y453164D01*
G01X-4259Y457337D02*
X-3378Y457101D01*
G01X-4259Y461274D02*
X-3378Y461038D01*
G01X-4259Y465211D02*
X-3378Y464975D01*
G01X-10531Y463563D02*
Y461426D01*
G01Y455689D02*
Y453552D01*
G01Y459626D02*
Y457489D01*
G01Y451752D02*
Y449615D01*
G01Y447815D02*
Y445678D01*
G01X-6694Y465644D02*
Y465054D01*
G01Y463872D02*
Y463282D01*
G01Y461707D02*
Y461117D01*
G01Y459935D02*
Y459345D01*
G01Y457770D02*
Y457180D01*
G01Y455998D02*
Y455408D01*
G01Y453833D02*
Y453243D01*
G01Y452061D02*
Y451471D01*
G01Y449896D02*
Y449306D01*
G01Y448124D02*
Y447534D01*
G01Y445959D02*
Y445369D01*
G01X-4725Y465644D02*
Y464739D01*
G01Y464187D02*
Y463282D01*
G01Y461707D02*
Y460802D01*
G01Y460250D02*
Y459345D01*
G01Y457770D02*
Y456865D01*
G01Y456313D02*
Y455408D01*
G01Y453833D02*
Y452928D01*
G01Y452376D02*
Y451471D01*
G01Y448439D02*
Y447534D01*
G01Y449896D02*
Y448991D01*
G01X-3757Y463597D02*
Y461392D01*
G01Y455723D02*
Y453518D01*
G01Y459660D02*
Y457455D01*
G01Y451786D02*
Y449581D01*
G01Y447849D02*
Y445644D01*
G01X-1Y445290D02*
X-1970D01*
G01X-6694Y445369D02*
X-9844D01*
G01X-4259Y445526D02*
X-4725D01*
G01X-2197Y445683D02*
X-3151D01*
G01X-4725Y445959D02*
X-6694D01*
G01X15077Y446077D02*
X8523D01*
G01D02*
X-1D01*
G01D02*
X-985D01*
G01Y447416D02*
X-1D01*
G01D02*
X8523D01*
G01D02*
X12600D01*
G01X-4725Y447534D02*
X-6694D01*
G01X-3151Y447809D02*
X-2197D01*
G01X-4725Y447967D02*
X-4259D01*
G01X-9844Y448124D02*
X-6694D01*
G01X-1970Y448203D02*
X-1D01*
G01Y449227D02*
X-1970D01*
G01X-6694Y449306D02*
X-9844D01*
G01X-4259Y449463D02*
X-4725D01*
G01X-2197Y449620D02*
X-3151D01*
G01X-4725Y449896D02*
X-6694D01*
G01X15077Y450014D02*
X8523D01*
G01D02*
X-1D01*
G01D02*
X-985D01*
G01Y451353D02*
X-1D01*
G01D02*
X8523D01*
G01D02*
X12600D01*
G01X-4725Y451471D02*
X-6694D01*
G01X-3151Y451746D02*
X-2197D01*
G01X-4725Y451904D02*
X-4259D01*
G01X-9844Y452061D02*
X-6694D01*
G01X-1970Y452140D02*
X-1D01*
G01Y453164D02*
X-1970D01*
G01X-6694Y453243D02*
X-9844D01*
G01X-4259Y453400D02*
X-4725D01*
G01X-2197Y453557D02*
X-3151D01*
G01X-4725Y453833D02*
X-6694D01*
G01X15077Y453951D02*
X8523D01*
G01D02*
X-1D01*
G01D02*
X-985D01*
G01Y455290D02*
X-1D01*
G01D02*
X8523D01*
G01D02*
X12600D01*
G01X-4725Y455408D02*
X-6694D01*
G01X-3151Y455683D02*
X-2197D01*
G01X-4725Y455841D02*
X-4259D01*
G01X-9844Y455998D02*
X-6694D01*
G01X-1970Y456077D02*
X-1D01*
G01Y457101D02*
X-1970D01*
G01X-6694Y457180D02*
X-9844D01*
G01X-4259Y457337D02*
X-4725D01*
G01X-2197Y457494D02*
X-3151D01*
G01X-4725Y457770D02*
X-6694D01*
G01X15077Y457888D02*
X8523D01*
G01D02*
X-1D01*
G01D02*
X-985D01*
G01Y459227D02*
X-1D01*
G01D02*
X8523D01*
G01D02*
X12600D01*
G01X-4725Y459345D02*
X-6694D01*
G01X-3151Y459620D02*
X-2197D01*
G01X-4725Y459778D02*
X-4259D01*
G01X-9844Y459935D02*
X-6694D01*
G01X-1970Y460014D02*
X-1D01*
G01Y461038D02*
X-1970D01*
G01X-6694Y461117D02*
X-9844D01*
G01X-4259Y461274D02*
X-4725D01*
G01X-2197Y461431D02*
X-3151D01*
G01X-4725Y461707D02*
X-6694D01*
G01X15077Y461825D02*
X8523D01*
G01D02*
X-1D01*
G01D02*
X-985D01*
G01Y463164D02*
X-1D01*
G01D02*
X8523D01*
G01D02*
X12600D01*
G01X-4725Y463282D02*
X-6694D01*
G01X-3151Y463557D02*
X-2197D01*
G01X-4725Y463715D02*
X-4259D01*
G01X-9844Y463872D02*
X-6694D01*
G01X-1970Y463951D02*
X-1D01*
G01Y464975D02*
X-1970D01*
G01X-6694Y465054D02*
X-9844D01*
G01X-4259Y465211D02*
X-4725D01*
G01X-2521Y463597D02*
Y461392D01*
G01Y455723D02*
Y453518D01*
G01Y459660D02*
Y457455D01*
G01Y451786D02*
Y449581D01*
G01Y447849D02*
Y445644D01*
G01X-2251Y467849D02*
Y465014D01*
G01Y463912D02*
Y461077D01*
G01Y459975D02*
Y457140D01*
G01Y456038D02*
Y453203D01*
G01Y452101D02*
Y449266D01*
G01Y448164D02*
Y445329D01*
G01X-985Y463164D02*
Y461825D01*
G01Y459227D02*
Y457888D01*
G01Y451353D02*
Y450014D01*
G01Y455290D02*
Y453951D01*
G01Y447416D02*
Y446077D01*
G01X8523Y463164D02*
Y461825D01*
G01Y459227D02*
Y457888D01*
G01Y455290D02*
Y453951D01*
G01Y451353D02*
Y450014D01*
G01Y447416D02*
Y446077D01*
G01X-6694Y448124D02*
X-4725Y448439D01*
G01X-6694Y452061D02*
X-4725Y452376D01*
G01X-6694Y455998D02*
X-4725Y456313D01*
G01X-3378Y448203D02*
X-4259Y447967D01*
G01X-3378Y452140D02*
X-4259Y451904D01*
G01X-3378Y456077D02*
X-4259Y455841D01*
G01X-3378Y460014D02*
X-4259Y459778D01*
G01X-3378Y463951D02*
X-4259Y463715D01*
G01X-6694Y459935D02*
X-4725Y460250D01*
G01X-6694Y463872D02*
X-4725Y464187D01*
G01X-3378Y464975D02*
X-3151Y465369D01*
G01X-1970Y463951D02*
X-2197Y463557D01*
G01X-3378Y461038D02*
X-3151Y461431D01*
G01X-1970Y460014D02*
X-2197Y459620D01*
G01X-3378Y457101D02*
X-3151Y457494D01*
G01X-1970Y456077D02*
X-2197Y455683D01*
G01X-3378Y453164D02*
X-3151Y453557D01*
G01X-1970Y452140D02*
X-2197Y451746D01*
G01X-3378Y449227D02*
X-3151Y449620D01*
G01X-1970Y448203D02*
X-2197Y447809D01*
G01X-3378Y445290D02*
X-3151Y445683D01*
G01X-9844Y463872D02*
X-10631Y463518D01*
G01X-9844Y459935D02*
X-10631Y459581D01*
G01X-9844Y455998D02*
X-10631Y455644D01*
G01X-9844Y452061D02*
X-10631Y451707D01*
G01X-9844Y448124D02*
X-10631Y447770D01*
G01Y469345D02*
X-9844Y468991D01*
G01X-10631Y473282D02*
X-9844Y472928D01*
G01X-10631Y477219D02*
X-9844Y476865D01*
G01X-3151Y467494D02*
X-3378Y467888D01*
G01X-2197Y469306D02*
X-1970Y468912D01*
G01X-3151Y471431D02*
X-3378Y471825D01*
G01X-2197Y473243D02*
X-1970Y472849D01*
G01X-3151Y475369D02*
X-3378Y475762D01*
G01X-2197Y477180D02*
X-1970Y476786D01*
G01X-3151Y479306D02*
X-3378Y479699D01*
G01X-4725Y468676D02*
X-6694Y468991D01*
G01X-4725Y472613D02*
X-6694Y472928D01*
G01X-4259Y469148D02*
X-3378Y468912D01*
G01X-4259Y473085D02*
X-3378Y472849D01*
G01X-4259Y477022D02*
X-3378Y476786D01*
G01X-10531Y479311D02*
Y477174D01*
G01Y475374D02*
Y473237D01*
G01Y471437D02*
Y469300D01*
G01Y467500D02*
Y465363D01*
G01X-6694Y479620D02*
Y479030D01*
G01Y477455D02*
Y476865D01*
G01Y475683D02*
Y475093D01*
G01Y473518D02*
Y472928D01*
G01Y471746D02*
Y471156D01*
G01Y469581D02*
Y468991D01*
G01Y467809D02*
Y467219D01*
G01X-4725Y481392D02*
Y480487D01*
G01Y479935D02*
Y479030D01*
G01Y477455D02*
Y476550D01*
G01Y475998D02*
Y475093D01*
G01Y473518D02*
Y472613D01*
G01Y472061D02*
Y471156D01*
G01Y469581D02*
Y468676D01*
G01Y468124D02*
Y467219D01*
G01X-3757Y479345D02*
Y477140D01*
G01Y475408D02*
Y473203D01*
G01Y471471D02*
Y469266D01*
G01Y467534D02*
Y465329D01*
G01X-2197Y465369D02*
X-3151D01*
G01X-4725Y465644D02*
X-6694D01*
G01X15077Y465762D02*
X8523D01*
G01D02*
X-1D01*
G01D02*
X-985D01*
G01Y467101D02*
X-1D01*
G01D02*
X8523D01*
G01D02*
X12600D01*
G01X-4725Y467219D02*
X-6694D01*
G01X-3151Y467494D02*
X-2197D01*
G01X-4725Y467652D02*
X-4259D01*
G01X-9844Y467809D02*
X-6694D01*
G01X-1970Y467888D02*
X-1D01*
G01Y468912D02*
X-1970D01*
G01X-6694Y468991D02*
X-9844D01*
G01X-4259Y469148D02*
X-4725D01*
G01X-2197Y469306D02*
X-3151D01*
G01X-4725Y469581D02*
X-6694D01*
G01X15077Y469699D02*
X8523D01*
G01D02*
X-1D01*
G01D02*
X-985D01*
G01Y471038D02*
X-1D01*
G01D02*
X8523D01*
G01D02*
X12600D01*
G01X-4725Y471156D02*
X-6694D01*
G01X-3151Y471431D02*
X-2197D01*
G01X-4725Y471589D02*
X-4259D01*
G01X-9844Y471746D02*
X-6694D01*
G01X-1970Y471825D02*
X-1D01*
G01Y472849D02*
X-1970D01*
G01X-6694Y472928D02*
X-9844D01*
G01X-4259Y473085D02*
X-4725D01*
G01Y476550D02*
X-6694Y476865D01*
G01X-4725Y480487D02*
X-6694Y480802D01*
G01X-2521Y479345D02*
Y477140D01*
G01Y475408D02*
Y473203D01*
G01Y471471D02*
Y469266D01*
G01Y467534D02*
Y465329D01*
G01X-2251Y479660D02*
Y476825D01*
G01Y475723D02*
Y472888D01*
G01Y471786D02*
Y468951D01*
G01X-985Y478912D02*
Y477573D01*
G01Y474975D02*
Y473636D01*
G01Y471038D02*
Y469699D01*
G01Y467101D02*
Y465762D01*
G01X8523Y478912D02*
Y477573D01*
G01Y474975D02*
Y473636D01*
G01Y471038D02*
Y469699D01*
G01Y467101D02*
Y465762D01*
G01X-2197Y473243D02*
X-3151D01*
G01X-4725Y473518D02*
X-6694D01*
G01X15077Y473636D02*
X8523D01*
G01D02*
X-1D01*
G01D02*
X-985D01*
G01Y474975D02*
X-1D01*
G01D02*
X8523D01*
G01D02*
X12600D01*
G01X-4725Y475093D02*
X-6694D01*
G01X-3151Y475369D02*
X-2197D01*
G01X-4725Y475526D02*
X-4259D01*
G01X-9844Y475683D02*
X-6694D01*
G01X-1970Y475762D02*
X-1D01*
G01Y476786D02*
X-1970D01*
G01X-6694Y476865D02*
X-9844D01*
G01X-4259Y477022D02*
X-4725D01*
G01X-2197Y477180D02*
X-3151D01*
G01X-4725Y477455D02*
X-6694D01*
G01X15077Y477573D02*
X8523D01*
G01D02*
X-1D01*
G01D02*
X-985D01*
G01Y478912D02*
X-1D01*
G01D02*
X8523D01*
G01D02*
X12600D01*
G01X-4725Y479030D02*
X-6694D01*
G01X-3151Y479306D02*
X-2197D01*
G01X-4725Y479463D02*
X-4259D01*
G01X-9844Y479620D02*
X-6694D01*
G01X-1970Y479699D02*
X-1D01*
G01X-3378Y467888D02*
X-4259Y467652D01*
G01X-3378Y471825D02*
X-4259Y471589D01*
G01X-6694Y467809D02*
X-4725Y468124D01*
G01X-6694Y471746D02*
X-4725Y472061D01*
G01X-6694Y475683D02*
X-4725Y475998D01*
G01X-6694Y479620D02*
X-4725Y479935D01*
G01X-3378Y475762D02*
X-4259Y475526D01*
G01X-3378Y479699D02*
X-4259Y479463D01*
G01X-1970Y479699D02*
X-2197Y479306D01*
G01X-3378Y476786D02*
X-3151Y477180D01*
G01X-1970Y475762D02*
X-2197Y475369D01*
G01X-3378Y472849D02*
X-3151Y473243D01*
G01X-1970Y471825D02*
X-2197Y471431D01*
G01X-3378Y468912D02*
X-3151Y469306D01*
G01X-1970Y467888D02*
X-2197Y467494D01*
G01X-9844Y479620D02*
X-10631Y479266D01*
G01X-9844Y475683D02*
X-10631Y475329D01*
G01X-9844Y471746D02*
X-10631Y471392D01*
G01X-9844Y467809D02*
X-10631Y467455D01*
G01X-38426Y487298D02*
Y484935D01*
G01Y483361D02*
Y480998D01*
G01X-38108Y482662D02*
Y481697D01*
G01X-37871Y482685D02*
Y481674D01*
G01X-35595Y486841D02*
Y485392D01*
G01Y482904D02*
Y481455D01*
G01X-35546Y487298D02*
Y484935D01*
G01Y483361D02*
Y480998D01*
G01X-35357Y486864D02*
Y485369D01*
G01Y482927D02*
Y481432D01*
G01X-34607Y487219D02*
Y485014D01*
G01Y483282D02*
Y481077D01*
G01X-34136Y486878D02*
Y485355D01*
G01Y482941D02*
Y481418D01*
G01X-33153Y486889D02*
Y485344D01*
G01Y482952D02*
Y481407D01*
G01X-32319Y486898D02*
Y485335D01*
G01Y482961D02*
Y481398D01*
G01X-31941Y486902D02*
Y485330D01*
G01Y482965D02*
Y481393D01*
G01X-38108Y481697D02*
X-35351Y481431D01*
G01X-38108Y485634D02*
X-35351Y485369D01*
G01Y482928D02*
X-38108Y482662D01*
G01X-35351Y482928D02*
X-10631Y483203D01*
G01X-39607Y480998D02*
X-24509D01*
G01X-35546Y481077D02*
X-1D01*
G01X-39607Y481530D02*
X-27993D01*
G01X-35546Y483282D02*
X-1D01*
G01X-24509Y483361D02*
X-39607D01*
G01Y484935D02*
X-24509D01*
G01X-35546Y485014D02*
X-1D01*
G01X-10631Y481156D02*
X-35351Y481431D01*
G01X-10631Y485093D02*
X-35351Y485369D01*
G01X-38426Y506983D02*
Y504620D01*
G01Y499109D02*
Y496746D01*
G01Y503046D02*
Y500683D01*
G01Y495172D02*
Y492809D01*
G01Y491235D02*
Y488872D01*
G01X-38108Y506284D02*
Y505319D01*
G01Y498410D02*
Y497445D01*
G01Y502347D02*
Y501382D01*
G01Y494473D02*
Y493508D01*
G01Y490536D02*
Y489571D01*
G01Y486599D02*
Y485634D01*
G01X-37871Y502370D02*
Y501359D01*
G01Y506307D02*
Y505296D01*
G01Y498433D02*
Y497422D01*
G01Y494496D02*
Y493485D01*
G01Y490559D02*
Y489548D01*
G01Y486622D02*
Y485611D01*
G01X-35595Y506526D02*
Y505077D01*
G01Y498652D02*
Y497203D01*
G01Y502589D02*
Y501140D01*
G01Y494715D02*
Y493266D01*
G01Y490778D02*
Y489329D01*
G01X-35546Y506983D02*
Y504620D01*
G01Y503046D02*
Y500683D01*
G01Y499109D02*
Y496746D01*
G01Y495172D02*
Y492809D01*
G01Y491235D02*
Y488872D01*
G01X-35357Y506549D02*
Y505054D01*
G01Y502612D02*
Y501117D01*
G01Y498675D02*
Y497180D01*
G01Y494738D02*
Y493243D01*
G01Y490801D02*
Y489306D01*
G01X-34607Y506904D02*
Y504699D01*
G01Y499030D02*
Y496825D01*
G01Y502967D02*
Y500762D01*
G01Y495093D02*
Y492888D01*
G01Y491156D02*
Y488951D01*
G01X-34136Y502626D02*
Y501103D01*
G01Y506563D02*
Y505040D01*
G01Y498689D02*
Y497166D01*
G01Y494752D02*
Y493229D01*
G01Y490815D02*
Y489292D01*
G01X-33153Y506574D02*
Y505029D01*
G01Y498700D02*
Y497155D01*
G01Y502637D02*
Y501092D01*
G01Y494763D02*
Y493218D01*
G01Y490826D02*
Y489281D01*
G01X-32319Y502646D02*
Y501083D01*
G01Y506583D02*
Y505020D01*
G01Y498709D02*
Y497146D01*
G01Y494772D02*
Y493209D01*
G01Y490835D02*
Y489272D01*
G01X-31941Y502650D02*
Y501078D01*
G01Y506587D02*
Y505015D01*
G01Y498713D02*
Y497141D01*
G01Y494776D02*
Y493204D01*
G01Y490839D02*
Y489267D01*
G01X-38108Y489571D02*
X-35351Y489306D01*
G01X-38108Y493508D02*
X-35351Y493243D01*
G01X-38108Y497445D02*
X-35351Y497180D01*
G01X-38108Y501382D02*
X-35351Y501117D01*
G01X-38108Y505319D02*
X-35351Y505054D01*
G01Y486865D02*
X-38108Y486599D01*
G01X-35351Y490802D02*
X-38108Y490536D01*
G01X-35351Y486865D02*
X-10631Y487140D01*
G01X-35351Y490802D02*
X-10631Y491077D01*
G01X-35351Y494739D02*
X-10631Y495014D01*
G01X-35351Y498676D02*
X-10631Y498951D01*
G01X-35351Y502613D02*
X-10631Y502888D01*
G01X-35546Y487219D02*
X-1D01*
G01X-24509Y487298D02*
X-39607D01*
G01Y488872D02*
X-24509D01*
G01X-35546Y488951D02*
X-1D01*
G01X-35546Y491156D02*
X-1D01*
G01X-24509Y491235D02*
X-39607D01*
G01Y492809D02*
X-24509D01*
G01X-35546Y492888D02*
X-1D01*
G01X-27993Y494876D02*
X-39607D01*
G01X-35546Y495093D02*
X-1D01*
G01X-24509Y495172D02*
X-39607D01*
G01Y496746D02*
X-24509D01*
G01X-35546Y496825D02*
X-1D01*
G01X-39607Y498026D02*
X-24844D01*
G01X-35546Y499030D02*
X-1D01*
G01X-24509Y499109D02*
X-39607D01*
G01Y500683D02*
X-24509D01*
G01X-35546Y500762D02*
X-1D01*
G01X-39607Y502002D02*
X-24844D01*
G01X-35546Y502967D02*
X-1D01*
G01X-24509Y503046D02*
X-39607D01*
G01Y504620D02*
X-24509D01*
G01X-35546Y504699D02*
X-1D01*
G01X-39607Y505152D02*
X-27993D01*
G01X-10631Y489030D02*
X-35351Y489306D01*
G01X-10631Y492967D02*
X-35351Y493243D01*
G01X-10631Y496904D02*
X-35351Y497180D01*
G01X-10631Y500841D02*
X-35351Y501117D01*
G01X-10631Y504778D02*
X-35351Y505054D01*
G01Y494739D02*
X-38108Y494473D01*
G01X-35351Y498676D02*
X-38108Y498410D01*
G01X-35351Y502613D02*
X-38108Y502347D01*
G01X-38426Y522731D02*
Y520369D01*
G01Y526668D02*
Y524306D01*
G01Y518794D02*
Y516431D01*
G01Y514857D02*
Y512494D01*
G01Y510920D02*
Y508557D01*
G01X-38108Y522032D02*
Y521067D01*
G01Y525969D02*
Y525004D01*
G01Y518095D02*
Y517130D01*
G01Y514158D02*
Y513193D01*
G01Y510221D02*
Y509256D01*
G01X-37871Y525992D02*
Y524981D01*
G01Y522055D02*
Y521044D01*
G01Y518118D02*
Y517107D01*
G01Y514181D02*
Y513170D01*
G01Y510244D02*
Y509233D01*
G01X-35595Y522274D02*
Y520825D01*
G01Y526211D02*
Y524762D01*
G01Y518337D02*
Y516888D01*
G01Y514400D02*
Y512951D01*
G01Y510463D02*
Y509014D01*
G01X-35546Y526668D02*
Y524306D01*
G01Y522731D02*
Y520369D01*
G01Y518794D02*
Y516431D01*
G01Y514857D02*
Y512494D01*
G01Y510920D02*
Y508557D01*
G01X-35357Y526234D02*
Y524739D01*
G01Y522297D02*
Y520802D01*
G01Y518360D02*
Y516865D01*
G01Y514423D02*
Y512928D01*
G01Y510486D02*
Y508991D01*
G01X-34607Y522652D02*
Y520447D01*
G01Y526589D02*
Y524384D01*
G01Y518715D02*
Y516510D01*
G01Y514778D02*
Y512573D01*
G01Y510841D02*
Y508636D01*
G01X-34136Y526248D02*
Y524725D01*
G01Y522311D02*
Y520788D01*
G01Y518374D02*
Y516851D01*
G01Y514437D02*
Y512914D01*
G01Y510500D02*
Y508977D01*
G01X-33153Y522322D02*
Y520777D01*
G01Y526259D02*
Y524714D01*
G01Y518385D02*
Y516840D01*
G01Y514448D02*
Y512903D01*
G01Y510511D02*
Y508966D01*
G01X-32319Y526268D02*
Y524705D01*
G01Y522331D02*
Y520768D01*
G01Y518394D02*
Y516831D01*
G01Y514457D02*
Y512894D01*
G01Y510520D02*
Y508957D01*
G01X-31941Y526272D02*
Y524700D01*
G01Y522335D02*
Y520763D01*
G01Y518398D02*
Y516826D01*
G01Y514461D02*
Y512889D01*
G01Y510524D02*
Y508952D01*
G01X-38108Y509256D02*
X-35351Y508991D01*
G01X-38108Y513193D02*
X-35351Y512928D01*
G01X-38108Y517130D02*
X-35351Y516865D01*
G01X-38108Y521067D02*
X-35351Y520802D01*
G01Y506550D02*
X-10631Y506825D01*
G01X-35351Y510487D02*
X-10631Y510762D01*
G01X-35351Y514424D02*
X-10631Y514699D01*
G01X-35351Y518361D02*
X-10631Y518636D01*
G01X-35351Y522298D02*
X-10631Y522573D01*
G01X-35546Y506904D02*
X-1D01*
G01X-24509Y506983D02*
X-39607D01*
G01Y508557D02*
X-24509D01*
G01X-35546Y508636D02*
X-1D01*
G01X-35546Y510841D02*
X-1D01*
G01X-24509Y510920D02*
X-39607D01*
G01Y512494D02*
X-24509D01*
G01X-35546Y512573D02*
X-1D01*
G01X-35546Y514778D02*
X-1D01*
G01X-24509Y514857D02*
X-39607D01*
G01Y516431D02*
X-24509D01*
G01X-35546Y516510D02*
X-1D01*
G01X-27993Y518498D02*
X-39607D01*
G01X-35546Y518715D02*
X-1D01*
G01X-24509Y518794D02*
X-39607D01*
G01Y520369D02*
X-24509D01*
G01X-35546Y520447D02*
X-1D01*
G01X-39607Y521648D02*
X-24844D01*
G01X-35546Y522652D02*
X-1D01*
G01X-24509Y522731D02*
X-39607D01*
G01Y524306D02*
X-24509D01*
G01X-35546Y524384D02*
X-1D01*
G01X-10631Y508715D02*
X-35351Y508991D01*
G01X-10631Y512652D02*
X-35351Y512928D01*
G01X-10631Y516589D02*
X-35351Y516865D01*
G01X-10631Y520526D02*
X-35351Y520802D01*
G01X-10631Y524463D02*
X-35351Y524739D01*
G01X-38108Y525004D02*
X-35351Y524739D01*
G01Y506550D02*
X-38108Y506284D01*
G01X-35351Y510487D02*
X-38108Y510221D01*
G01X-35351Y514424D02*
X-38108Y514158D01*
G01X-35351Y518361D02*
X-38108Y518095D01*
G01X-35351Y522298D02*
X-38108Y522032D01*
G01X-38426Y546353D02*
Y543991D01*
G01Y542416D02*
Y540054D01*
G01Y538479D02*
Y536117D01*
G01Y534542D02*
Y532180D01*
G01Y530605D02*
Y528243D01*
G01X-38108Y545654D02*
Y544689D01*
G01Y541717D02*
Y540752D01*
G01Y537780D02*
Y536815D01*
G01Y533843D02*
Y532878D01*
G01Y529906D02*
Y528941D01*
G01X-37871Y545677D02*
Y544666D01*
G01Y541740D02*
Y540729D01*
G01Y537803D02*
Y536792D01*
G01Y533866D02*
Y532855D01*
G01Y529929D02*
Y528918D01*
G01X-35595Y545896D02*
Y544447D01*
G01Y541959D02*
Y540510D01*
G01Y538022D02*
Y536573D01*
G01Y534085D02*
Y532636D01*
G01Y530148D02*
Y528699D01*
G01X-35546Y546353D02*
Y543991D01*
G01Y542416D02*
Y540054D01*
G01Y538479D02*
Y536117D01*
G01Y534542D02*
Y532180D01*
G01Y530605D02*
Y528243D01*
G01X-35357Y545919D02*
Y544424D01*
G01Y541982D02*
Y540487D01*
G01Y538045D02*
Y536550D01*
G01Y534108D02*
Y532613D01*
G01Y530171D02*
Y528676D01*
G01X-34607Y546274D02*
Y544069D01*
G01Y542337D02*
Y540132D01*
G01Y538400D02*
Y536195D01*
G01Y534463D02*
Y532258D01*
G01Y530526D02*
Y528321D01*
G01X-34136Y545933D02*
Y544410D01*
G01Y541996D02*
Y540473D01*
G01Y538059D02*
Y536536D01*
G01Y534122D02*
Y532599D01*
G01Y530185D02*
Y528662D01*
G01X-33153Y545944D02*
Y544399D01*
G01Y542007D02*
Y540462D01*
G01Y538070D02*
Y536525D01*
G01Y534133D02*
Y532588D01*
G01Y530196D02*
Y528651D01*
G01X-32319Y545953D02*
Y544390D01*
G01Y542016D02*
Y540453D01*
G01Y538079D02*
Y536516D01*
G01Y534142D02*
Y532579D01*
G01Y530205D02*
Y528642D01*
G01X-31941Y545957D02*
Y544385D01*
G01Y542020D02*
Y540448D01*
G01Y538083D02*
Y536511D01*
G01Y534146D02*
Y532574D01*
G01Y530209D02*
Y528637D01*
G01X-35351Y526235D02*
X-10631Y526510D01*
G01X-35351Y530172D02*
X-10631Y530447D01*
G01X-35351Y534109D02*
X-10631Y534384D01*
G01X-35351Y538046D02*
X-10631Y538321D01*
G01X-35351Y541983D02*
X-10631Y542258D01*
G01X-39607Y525624D02*
X-24844D01*
G01X-35546Y526589D02*
X-1D01*
G01X-24509Y526668D02*
X-39607D01*
G01Y528243D02*
X-24509D01*
G01X-35546Y528321D02*
X-1D01*
G01X-39607Y528774D02*
X-27993D01*
G01X-35546Y530526D02*
X-1D01*
G01X-24509Y530605D02*
X-39607D01*
G01Y532180D02*
X-24509D01*
G01X-35546Y532258D02*
X-1D01*
G01X-35546Y534463D02*
X-1D01*
G01X-24509Y534542D02*
X-39607D01*
G01Y536117D02*
X-24509D01*
G01X-35546Y536195D02*
X-1D01*
G01X-35546Y538400D02*
X-1D01*
G01X-24509Y538479D02*
X-39607D01*
G01Y540054D02*
X-24509D01*
G01X-35546Y540132D02*
X-1D01*
G01X-27993Y542120D02*
X-39607D01*
G01X-35546Y542337D02*
X-1D01*
G01X-24509Y542416D02*
X-39607D01*
G01Y543991D02*
X-24509D01*
G01X-35546Y544069D02*
X-1D01*
G01X-39607Y545270D02*
X-24844D01*
G01X-10631Y528400D02*
X-35351Y528676D01*
G01X-10631Y532337D02*
X-35351Y532613D01*
G01X-10631Y536274D02*
X-35351Y536550D01*
G01X-10631Y540211D02*
X-35351Y540487D01*
G01X-10631Y544148D02*
X-35351Y544424D01*
G01X-38108Y528941D02*
X-35351Y528676D01*
G01X-38108Y532878D02*
X-35351Y532613D01*
G01X-38108Y536815D02*
X-35351Y536550D01*
G01X-38108Y540752D02*
X-35351Y540487D01*
G01X-38108Y544689D02*
X-35351Y544424D01*
G01Y526235D02*
X-38108Y525969D01*
G01X-35351Y530172D02*
X-38108Y529906D01*
G01X-35351Y534109D02*
X-38108Y533843D01*
G01X-35351Y538046D02*
X-38108Y537780D01*
G01X-35351Y541983D02*
X-38108Y541717D01*
G01X-35351Y545920D02*
X-38108Y545654D01*
G01X-38426Y562101D02*
Y559739D01*
G01Y558164D02*
Y555802D01*
G01Y550290D02*
Y547928D01*
G01Y554227D02*
Y551865D01*
G01X-38108Y561402D02*
Y560437D01*
G01Y557465D02*
Y556500D01*
G01Y553528D02*
Y552563D01*
G01Y549591D02*
Y548626D01*
G01X-37871Y561425D02*
Y560414D01*
G01Y557488D02*
Y556477D01*
G01Y549614D02*
Y548603D01*
G01Y553551D02*
Y552540D01*
G01X-35595Y561644D02*
Y560195D01*
G01Y557707D02*
Y556258D01*
G01Y553770D02*
Y552321D01*
G01Y549833D02*
Y548384D01*
G01X-35546Y562101D02*
Y559739D01*
G01Y558164D02*
Y555802D01*
G01Y554227D02*
Y551865D01*
G01Y550290D02*
Y547928D01*
G01X-35357Y561667D02*
Y560172D01*
G01Y557730D02*
Y556235D01*
G01Y553793D02*
Y552298D01*
G01Y549856D02*
Y548361D01*
G01X-34607Y562022D02*
Y559817D01*
G01Y558085D02*
Y555880D01*
G01Y550211D02*
Y548006D01*
G01Y554148D02*
Y551943D01*
G01X-34136Y561681D02*
Y560158D01*
G01Y553807D02*
Y552284D01*
G01Y557744D02*
Y556221D01*
G01Y549870D02*
Y548347D01*
G01X-33153Y561692D02*
Y560147D01*
G01Y557755D02*
Y556210D01*
G01Y553818D02*
Y552273D01*
G01Y549881D02*
Y548336D01*
G01X-32319Y561701D02*
Y560138D01*
G01Y553827D02*
Y552264D01*
G01Y557764D02*
Y556201D01*
G01Y549890D02*
Y548327D01*
G01X-31941Y561706D02*
Y560133D01*
G01Y553831D02*
Y552259D01*
G01Y557769D02*
Y556196D01*
G01Y549894D02*
Y548322D01*
G01X-35546Y546274D02*
X-1D01*
G01X-24509Y546353D02*
X-39607D01*
G01Y547928D02*
X-24509D01*
G01X-35546Y548006D02*
X-1D01*
G01X-39607Y549246D02*
X-24844D01*
G01X-10631Y548085D02*
X-35351Y548361D01*
G01X-10631Y552022D02*
X-35351Y552298D01*
G01X-38108Y548626D02*
X-35351Y548361D01*
G01X-38108Y552563D02*
X-35351Y552298D01*
G01X-38108Y556500D02*
X-35351Y556235D01*
G01X-38108Y560437D02*
X-35351Y560172D01*
G01Y549857D02*
X-38108Y549591D01*
G01X-35351Y553794D02*
X-38108Y553528D01*
G01X-35351Y557731D02*
X-38108Y557465D01*
G01X-35351Y561668D02*
X-38108Y561402D01*
G01X-35351Y545920D02*
X-10631Y546195D01*
G01X-35351Y549857D02*
X-10631Y550132D01*
G01X-35351Y553794D02*
X-10631Y554069D01*
G01X-35351Y557731D02*
X-10631Y558006D01*
G01X-35351Y561668D02*
X-10631Y561943D01*
G01X-35546Y550211D02*
X-1D01*
G01X-24509Y550290D02*
X-39607D01*
G01Y551865D02*
X-24509D01*
G01X-35546Y551943D02*
X-1D01*
G01X-39607Y552396D02*
X-27993D01*
G01X-35546Y554148D02*
X-1D01*
G01X-24509Y554227D02*
X-39607D01*
G01Y555802D02*
X-24509D01*
G01X-35546Y555880D02*
X-1D01*
G01X-35546Y558085D02*
X-1D01*
G01X-24509Y558164D02*
X-39607D01*
G01Y559739D02*
X-24509D01*
G01X-35546Y559817D02*
X-1D01*
G01X-35546Y562022D02*
X-1D01*
G01X-24509Y562101D02*
X-39607D01*
G01X-10631Y555959D02*
X-35351Y556235D01*
G01X-10631Y559896D02*
X-35351Y560172D01*
G01X-27265Y487298D02*
Y484935D01*
G01Y483361D02*
Y480998D01*
G01X-26943Y486958D02*
Y485274D01*
G01Y483021D02*
Y481337D01*
G01X-26566Y486962D02*
Y485270D01*
G01Y483025D02*
Y481333D01*
G01X-24509Y487298D02*
Y484935D01*
G01Y483361D02*
Y480998D01*
G01X-24122Y486989D02*
Y485243D01*
G01Y483052D02*
Y481306D01*
G01X-23684Y486994D02*
Y485238D01*
G01Y483057D02*
Y481301D01*
G01X-12993Y485014D02*
Y484699D01*
G01Y483597D02*
Y483282D01*
G01Y481077D02*
Y480762D01*
G01X-12280Y487122D02*
Y485111D01*
G01Y483185D02*
Y481174D01*
G01X-11843Y487126D02*
Y485106D01*
G01Y483189D02*
Y481169D01*
G01X-12993Y480762D02*
X-1D01*
G01Y483597D02*
X-12993D01*
G01Y484699D02*
X-1D01*
G01X-27993Y502002D02*
Y521648D01*
G01X-27265Y506983D02*
Y504620D01*
G01Y503046D02*
Y500683D01*
G01Y499109D02*
Y496746D01*
G01Y495172D02*
Y492809D01*
G01Y491235D02*
Y488872D01*
G01X-26943Y506643D02*
Y504959D01*
G01Y502706D02*
Y501022D01*
G01Y498769D02*
Y497085D01*
G01Y494832D02*
Y493148D01*
G01Y490895D02*
Y489211D01*
G01X-26566Y506647D02*
Y504956D01*
G01Y498773D02*
Y497081D01*
G01Y502710D02*
Y501019D01*
G01Y494836D02*
Y493144D01*
G01Y490899D02*
Y489207D01*
G01X-24844Y502002D02*
Y521648D01*
G01X-24509Y506983D02*
Y504620D01*
G01Y503046D02*
Y500683D01*
G01Y499109D02*
Y496746D01*
G01Y495172D02*
Y492809D01*
G01Y491235D02*
Y488872D01*
G01X-24122Y502737D02*
Y500991D01*
G01Y506674D02*
Y504928D01*
G01Y498800D02*
Y497054D01*
G01Y494863D02*
Y493117D01*
G01Y490926D02*
Y489180D01*
G01X-23684Y502743D02*
Y500986D01*
G01Y506680D02*
Y504923D01*
G01Y498806D02*
Y497049D01*
G01Y494869D02*
Y493112D01*
G01Y490931D02*
Y489175D01*
G01X-12993Y504699D02*
Y504384D01*
G01Y503282D02*
Y502967D01*
G01Y500762D02*
Y500447D01*
G01Y499345D02*
Y499030D01*
G01Y496825D02*
Y496510D01*
G01Y492888D02*
Y492573D01*
G01Y495408D02*
Y495093D01*
G01Y488951D02*
Y488636D01*
G01Y491471D02*
Y491156D01*
G01Y487534D02*
Y487219D01*
G01X-12280Y502870D02*
Y500859D01*
G01Y506807D02*
Y504796D01*
G01Y498933D02*
Y496922D01*
G01Y494996D02*
Y492985D01*
G01Y491059D02*
Y489048D01*
G01X-11843Y506811D02*
Y504791D01*
G01Y502874D02*
Y500854D01*
G01Y498937D02*
Y496917D01*
G01Y495000D02*
Y492980D01*
G01Y491063D02*
Y489043D01*
G01X-1Y487534D02*
X-12993D01*
G01Y488636D02*
X-1D01*
G01Y491471D02*
X-12993D01*
G01Y492573D02*
X-1D01*
G01Y495408D02*
X-12993D01*
G01Y496510D02*
X-1D01*
G01Y499345D02*
X-12993D01*
G01Y500447D02*
X-1D01*
G01Y503282D02*
X-12993D01*
G01Y504384D02*
X-1D01*
G01X-27265Y526668D02*
Y524306D01*
G01Y522731D02*
Y520369D01*
G01Y518794D02*
Y516431D01*
G01Y514857D02*
Y512494D01*
G01Y510920D02*
Y508557D01*
G01X-26943Y526328D02*
Y524644D01*
G01Y522391D02*
Y520707D01*
G01Y518454D02*
Y516770D01*
G01Y514517D02*
Y512833D01*
G01Y510580D02*
Y508896D01*
G01X-26566Y522395D02*
Y520704D01*
G01Y526332D02*
Y524641D01*
G01Y518458D02*
Y516767D01*
G01Y514521D02*
Y512830D01*
G01Y510584D02*
Y508893D01*
G01X-24509Y526668D02*
Y524306D01*
G01Y522731D02*
Y520369D01*
G01Y518794D02*
Y516431D01*
G01Y514857D02*
Y512494D01*
G01Y510920D02*
Y508557D01*
G01X-24122Y526359D02*
Y524613D01*
G01Y522422D02*
Y520676D01*
G01Y518485D02*
Y516739D01*
G01Y514548D02*
Y512802D01*
G01Y510611D02*
Y508865D01*
G01X-23684Y526365D02*
Y524608D01*
G01Y522428D02*
Y520671D01*
G01Y518491D02*
Y516734D01*
G01Y514554D02*
Y512797D01*
G01Y510617D02*
Y508860D01*
G01X-12993Y524384D02*
Y524069D01*
G01Y522967D02*
Y522652D01*
G01Y520447D02*
Y520132D01*
G01Y516510D02*
Y516195D01*
G01Y519030D02*
Y518715D01*
G01Y512573D02*
Y512258D01*
G01Y515093D02*
Y514778D01*
G01Y508636D02*
Y508321D01*
G01Y511156D02*
Y510841D01*
G01Y507219D02*
Y506904D01*
G01X-12280Y526492D02*
Y524481D01*
G01Y522555D02*
Y520544D01*
G01Y518618D02*
Y516607D01*
G01Y514681D02*
Y512670D01*
G01Y510744D02*
Y508733D01*
G01X-11843Y526496D02*
Y524476D01*
G01Y522559D02*
Y520539D01*
G01Y518622D02*
Y516602D01*
G01Y514685D02*
Y512665D01*
G01Y510748D02*
Y508728D01*
G01X-1Y507219D02*
X-12993D01*
G01Y508321D02*
X-1D01*
G01Y511156D02*
X-12993D01*
G01Y512258D02*
X-1D01*
G01Y515093D02*
X-12993D01*
G01Y516195D02*
X-1D01*
G01Y519030D02*
X-12993D01*
G01Y520132D02*
X-1D01*
G01Y522967D02*
X-12993D01*
G01Y524069D02*
X-1D01*
G01X-27993Y525624D02*
Y545270D01*
G01X-27265Y546353D02*
Y543991D01*
G01Y542416D02*
Y540054D01*
G01Y538479D02*
Y536117D01*
G01Y534542D02*
Y532180D01*
G01Y530605D02*
Y528243D01*
G01X-26943Y546013D02*
Y544330D01*
G01Y542076D02*
Y540393D01*
G01Y538139D02*
Y536456D01*
G01Y534202D02*
Y532519D01*
G01Y530265D02*
Y528581D01*
G01X-26566Y546017D02*
Y544326D01*
G01Y542080D02*
Y540389D01*
G01Y538143D02*
Y536452D01*
G01Y534206D02*
Y532515D01*
G01Y530269D02*
Y528578D01*
G01X-24844Y525624D02*
Y545270D01*
G01X-24509Y546353D02*
Y543991D01*
G01Y542416D02*
Y540054D01*
G01Y538479D02*
Y536117D01*
G01Y534542D02*
Y532180D01*
G01Y530605D02*
Y528243D01*
G01X-24122Y546044D02*
Y544298D01*
G01Y542107D02*
Y540361D01*
G01Y538170D02*
Y536424D01*
G01Y534233D02*
Y532487D01*
G01Y530296D02*
Y528550D01*
G01X-23684Y546050D02*
Y544293D01*
G01Y542113D02*
Y540356D01*
G01Y538176D02*
Y536419D01*
G01Y534239D02*
Y532482D01*
G01Y530302D02*
Y528545D01*
G01X-12993Y544069D02*
Y543754D01*
G01Y540132D02*
Y539817D01*
G01Y542652D02*
Y542337D01*
G01Y536195D02*
Y535880D01*
G01Y538715D02*
Y538400D01*
G01Y532258D02*
Y531943D01*
G01Y534778D02*
Y534463D01*
G01Y530841D02*
Y530526D01*
G01Y528321D02*
Y528006D01*
G01Y526904D02*
Y526589D01*
G01X-12280Y546177D02*
Y544166D01*
G01Y542240D02*
Y540229D01*
G01Y538303D02*
Y536292D01*
G01Y530429D02*
Y528418D01*
G01Y534366D02*
Y532355D01*
G01X-11843Y546181D02*
Y544161D01*
G01Y542244D02*
Y540224D01*
G01Y538307D02*
Y536287D01*
G01Y534370D02*
Y532350D01*
G01Y530433D02*
Y528413D01*
G01X-1Y526904D02*
X-12993D01*
G01Y528006D02*
X-1D01*
G01Y530841D02*
X-12993D01*
G01Y531943D02*
X-1D01*
G01Y534778D02*
X-12993D01*
G01Y535880D02*
X-1D01*
G01Y538715D02*
X-12993D01*
G01Y539817D02*
X-1D01*
G01Y542652D02*
X-12993D01*
G01Y543754D02*
X-1D01*
G01X-27993Y549246D02*
Y568892D01*
G01X-27265Y562101D02*
Y559739D01*
G01Y558164D02*
Y555802D01*
G01Y554227D02*
Y551865D01*
G01Y550290D02*
Y547928D01*
G01X-26943Y561761D02*
Y560078D01*
G01Y557824D02*
Y556141D01*
G01Y553887D02*
Y552204D01*
G01Y549950D02*
Y548267D01*
G01X-26566Y561765D02*
Y560074D01*
G01Y557828D02*
Y556137D01*
G01Y553891D02*
Y552200D01*
G01Y549954D02*
Y548263D01*
G01X-24844Y549246D02*
Y568892D01*
G01X-24509Y562101D02*
Y559739D01*
G01Y558164D02*
Y555802D01*
G01Y554227D02*
Y551865D01*
G01Y550290D02*
Y547928D01*
G01X-24122Y561793D02*
Y560046D01*
G01Y553919D02*
Y552172D01*
G01Y557856D02*
Y556109D01*
G01Y549981D02*
Y548235D01*
G01X-23684Y561798D02*
Y560041D01*
G01Y553924D02*
Y552167D01*
G01Y557861D02*
Y556104D01*
G01Y549987D02*
Y548230D01*
G01X-12993Y559817D02*
Y559502D01*
G01Y562337D02*
Y562022D01*
G01Y555880D02*
Y555565D01*
G01Y558400D02*
Y558085D01*
G01Y554463D02*
Y554148D01*
G01Y551943D02*
Y551628D01*
G01Y550526D02*
Y550211D01*
G01Y548006D02*
Y547691D01*
G01Y546589D02*
Y546274D01*
G01X-12280Y561925D02*
Y559914D01*
G01Y557988D02*
Y555977D01*
G01Y554051D02*
Y552040D01*
G01Y550114D02*
Y548103D01*
G01X-11843Y561930D02*
Y559909D01*
G01Y557993D02*
Y555972D01*
G01Y554056D02*
Y552035D01*
G01Y550119D02*
Y548098D01*
G01X-1Y546589D02*
X-12993D01*
G01Y547691D02*
X-1D01*
G01Y550526D02*
X-12993D01*
G01Y551628D02*
X-1D01*
G01Y554463D02*
X-12993D01*
G01Y555565D02*
X-1D01*
G01Y558400D02*
X-12993D01*
G01Y559502D02*
X-1D01*
G01Y562337D02*
X-12993D01*
G01X-10631Y481156D02*
X-9844Y480802D01*
G01X-10631Y485093D02*
X-9844Y484739D01*
G01X-2197Y481117D02*
X-1970Y480723D01*
G01X-3151Y483243D02*
X-3378Y483636D01*
G01X-2197Y485054D02*
X-1970Y484660D01*
G01X-4259Y480959D02*
X-3378Y480723D01*
G01X-4259Y484896D02*
X-3378Y484660D01*
G01X-10531Y487185D02*
Y485048D01*
G01Y483248D02*
Y481111D01*
G01X-6694Y485329D02*
Y484739D01*
G01Y483557D02*
Y482967D01*
G01Y481392D02*
Y480802D01*
G01X-4725Y485329D02*
Y484424D01*
G01Y483872D02*
Y482967D01*
G01X-3757Y487219D02*
Y485014D01*
G01Y483282D02*
Y481077D01*
G01X-4725Y484424D02*
X-6694Y484739D01*
G01X-2521Y487219D02*
Y485014D01*
G01Y483282D02*
Y481077D01*
G01X-2251Y487534D02*
Y484699D01*
G01Y483597D02*
Y480762D01*
G01X-985Y482849D02*
Y481510D01*
G01X8523Y482849D02*
Y481510D01*
G01X-1Y480723D02*
X-1970D01*
G01X-6694Y480802D02*
X-9844D01*
G01X-4259Y480959D02*
X-4725D01*
G01X-2197Y481117D02*
X-3151D01*
G01X-4725Y481392D02*
X-6694D01*
G01X15077Y481510D02*
X8523D01*
G01D02*
X-1D01*
G01D02*
X-985D01*
G01Y482849D02*
X-1D01*
G01D02*
X8523D01*
G01D02*
X12600D01*
G01X-4725Y482967D02*
X-6694D01*
G01X-3151Y483243D02*
X-2197D01*
G01X-4725Y483400D02*
X-4259D01*
G01X-9844Y483557D02*
X-6694D01*
G01X-1970Y483636D02*
X-1D01*
G01Y484660D02*
X-1970D01*
G01X-6694Y484739D02*
X-9844D01*
G01X-4259Y484896D02*
X-4725D01*
G01X-2197Y485054D02*
X-3151D01*
G01X-4725Y485329D02*
X-6694D01*
G01Y483557D02*
X-4725Y483872D01*
G01X-3378Y483636D02*
X-4259Y483400D01*
G01X-3378Y484660D02*
X-3151Y485054D01*
G01X-1970Y483636D02*
X-2197Y483243D01*
G01X-3378Y480723D02*
X-3151Y481117D01*
G01X-9844Y483557D02*
X-10631Y483203D01*
G01Y489030D02*
X-9844Y488676D01*
G01X-10631Y492967D02*
X-9844Y492613D01*
G01X-3151Y487180D02*
X-3378Y487573D01*
G01X-2197Y488991D02*
X-1970Y488597D01*
G01X-3151Y491117D02*
X-3378Y491510D01*
G01X-2197Y492928D02*
X-1970Y492534D01*
G01X-3151Y495054D02*
X-3378Y495447D01*
G01X-2197Y496865D02*
X-1970Y496471D01*
G01X-3151Y498991D02*
X-3378Y499384D01*
G01X-2197Y500802D02*
X-1970Y500408D01*
G01X-3151Y502928D02*
X-3378Y503321D01*
G01X-2197Y504739D02*
X-1970Y504345D01*
G01X-4259Y488833D02*
X-3378Y488597D01*
G01X-4259Y492770D02*
X-3378Y492534D01*
G01X-4259Y496707D02*
X-3378Y496471D01*
G01X-4259Y500644D02*
X-3378Y500408D01*
G01X-4259Y504581D02*
X-3378Y504345D01*
G01X-10631Y496904D02*
X-9844Y496550D01*
G01X-10631Y500841D02*
X-9844Y500487D01*
G01X-10631Y504778D02*
X-9844Y504424D01*
G01X-10531Y502933D02*
Y500796D01*
G01Y506870D02*
Y504733D01*
G01Y498996D02*
Y496859D01*
G01Y495059D02*
Y492922D01*
G01Y491122D02*
Y488985D01*
G01X-6694Y505014D02*
Y504424D01*
G01Y503243D02*
Y502652D01*
G01Y501077D02*
Y500487D01*
G01Y499306D02*
Y498715D01*
G01Y495369D02*
Y494778D01*
G01Y493203D02*
Y492613D01*
G01Y497140D02*
Y496550D01*
G01Y491431D02*
Y490841D01*
G01Y489266D02*
Y488676D01*
G01Y487494D02*
Y486904D01*
G01X-4725Y503557D02*
Y502652D01*
G01Y505014D02*
Y504109D01*
G01Y499620D02*
Y498715D01*
G01Y501077D02*
Y500172D01*
G01Y495683D02*
Y494778D01*
G01Y497140D02*
Y496235D01*
G01Y491746D02*
Y490841D01*
G01Y489266D02*
Y488361D01*
G01Y493203D02*
Y492298D01*
G01Y487809D02*
Y486904D01*
G01X-3757Y502967D02*
Y500762D01*
G01Y506904D02*
Y504699D01*
G01Y499030D02*
Y496825D01*
G01Y495093D02*
Y492888D01*
G01Y491156D02*
Y488951D01*
G01X-4725Y488361D02*
X-6694Y488676D01*
G01X-4725Y492298D02*
X-6694Y492613D01*
G01X-4725Y496235D02*
X-6694Y496550D01*
G01X-4725Y500172D02*
X-6694Y500487D01*
G01X-4725Y504109D02*
X-6694Y504424D01*
G01X-2521Y502967D02*
Y500762D01*
G01Y506904D02*
Y504699D01*
G01Y499030D02*
Y496825D01*
G01Y495093D02*
Y492888D01*
G01Y491156D02*
Y488951D01*
G01X-2251Y507219D02*
Y504384D01*
G01Y503282D02*
Y500447D01*
G01Y499345D02*
Y496510D01*
G01Y495408D02*
Y492573D01*
G01Y491471D02*
Y488636D01*
G01X-985Y502534D02*
Y501195D01*
G01Y506471D02*
Y505132D01*
G01Y498597D02*
Y497258D01*
G01Y494660D02*
Y493321D01*
G01Y490723D02*
Y489384D01*
G01Y486786D02*
Y485447D01*
G01X8523Y506471D02*
Y505132D01*
G01Y502534D02*
Y501195D01*
G01Y498597D02*
Y497258D01*
G01Y494660D02*
Y493321D01*
G01Y490723D02*
Y489384D01*
G01Y486786D02*
Y485447D01*
G01X15077D02*
X8523D01*
G01D02*
X-1D01*
G01D02*
X-985D01*
G01Y486786D02*
X-1D01*
G01D02*
X8523D01*
G01D02*
X12600D01*
G01X-4725Y486904D02*
X-6694D01*
G01X-3151Y487180D02*
X-2197D01*
G01X-4725Y487337D02*
X-4259D01*
G01X-9844Y487494D02*
X-6694D01*
G01X-1970Y487573D02*
X-1D01*
G01Y488597D02*
X-1970D01*
G01X-6694Y488676D02*
X-9844D01*
G01X-4259Y488833D02*
X-4725D01*
G01X-2197Y488991D02*
X-3151D01*
G01X-4725Y489266D02*
X-6694D01*
G01X15077Y489384D02*
X8523D01*
G01D02*
X-1D01*
G01D02*
X-985D01*
G01Y490723D02*
X-1D01*
G01D02*
X8523D01*
G01D02*
X12600D01*
G01X-4725Y490841D02*
X-6694D01*
G01X-3151Y491117D02*
X-2197D01*
G01X-4725Y491274D02*
X-4259D01*
G01X-9844Y491431D02*
X-6694D01*
G01X-1970Y491510D02*
X-1D01*
G01Y492534D02*
X-1970D01*
G01X-6694Y492613D02*
X-9844D01*
G01X-4259Y492770D02*
X-4725D01*
G01X-2197Y492928D02*
X-3151D01*
G01X-4725Y493203D02*
X-6694D01*
G01X15077Y493321D02*
X8523D01*
G01D02*
X-1D01*
G01D02*
X-985D01*
G01Y494660D02*
X-1D01*
G01D02*
X8523D01*
G01D02*
X12600D01*
G01X-4725Y494778D02*
X-6694D01*
G01X-3151Y495054D02*
X-2197D01*
G01X-4725Y495211D02*
X-4259D01*
G01X-9844Y495369D02*
X-6694D01*
G01X-1970Y495447D02*
X-1D01*
G01Y496471D02*
X-1970D01*
G01X-6694Y496550D02*
X-9844D01*
G01X-4259Y496707D02*
X-4725D01*
G01X-2197Y496865D02*
X-3151D01*
G01X-4725Y497140D02*
X-6694D01*
G01X15077Y497258D02*
X8523D01*
G01D02*
X-1D01*
G01D02*
X-985D01*
G01Y498597D02*
X-1D01*
G01D02*
X8523D01*
G01D02*
X12600D01*
G01X-4725Y498715D02*
X-6694D01*
G01X-3151Y498991D02*
X-2197D01*
G01X-4725Y499148D02*
X-4259D01*
G01X-9844Y499306D02*
X-6694D01*
G01X-1970Y499384D02*
X-1D01*
G01Y500408D02*
X-1970D01*
G01X-6694Y500487D02*
X-9844D01*
G01X-4259Y500644D02*
X-4725D01*
G01X-2197Y500802D02*
X-3151D01*
G01X-4725Y501077D02*
X-6694D01*
G01X15077Y501195D02*
X8523D01*
G01D02*
X-1D01*
G01D02*
X-985D01*
G01Y502534D02*
X-1D01*
G01D02*
X8523D01*
G01D02*
X12600D01*
G01X-4725Y502652D02*
X-6694D01*
G01X-3151Y502928D02*
X-2197D01*
G01X-4725Y503085D02*
X-4259D01*
G01X-9844Y503243D02*
X-6694D01*
G01X-1970Y503321D02*
X-1D01*
G01Y504345D02*
X-1970D01*
G01X-6694Y504424D02*
X-9844D01*
G01X-4259Y504581D02*
X-4725D01*
G01X-2197Y504739D02*
X-3151D01*
G01X-4725Y505014D02*
X-6694D01*
G01X15077Y505132D02*
X8523D01*
G01D02*
X-1D01*
G01D02*
X-985D01*
G01X-6694Y487494D02*
X-4725Y487809D01*
G01X-6694Y491431D02*
X-4725Y491746D01*
G01X-6694Y495369D02*
X-4725Y495683D01*
G01X-6694Y499306D02*
X-4725Y499620D01*
G01X-6694Y503243D02*
X-4725Y503557D01*
G01X-3378Y487573D02*
X-4259Y487337D01*
G01X-3378Y491510D02*
X-4259Y491274D01*
G01X-3378Y495447D02*
X-4259Y495211D01*
G01X-3378Y499384D02*
X-4259Y499148D01*
G01X-3378Y503321D02*
X-4259Y503085D01*
G01X-3378Y504345D02*
X-3151Y504739D01*
G01X-1970Y503321D02*
X-2197Y502928D01*
G01X-3378Y500408D02*
X-3151Y500802D01*
G01X-1970Y499384D02*
X-2197Y498991D01*
G01X-3378Y496471D02*
X-3151Y496865D01*
G01X-1970Y495447D02*
X-2197Y495054D01*
G01X-3378Y492534D02*
X-3151Y492928D01*
G01X-1970Y491510D02*
X-2197Y491117D01*
G01X-3378Y488597D02*
X-3151Y488991D01*
G01X-1970Y487573D02*
X-2197Y487180D01*
G01X-9844Y503243D02*
X-10631Y502888D01*
G01X-9844Y499306D02*
X-10631Y498951D01*
G01X-9844Y495369D02*
X-10631Y495014D01*
G01X-9844Y491431D02*
X-10631Y491077D01*
G01X-9844Y487494D02*
X-10631Y487140D01*
G01X-3151Y506865D02*
X-3378Y507258D01*
G01X-2197Y508676D02*
X-1970Y508282D01*
G01X-3151Y510802D02*
X-3378Y511195D01*
G01X-2197Y512613D02*
X-1970Y512219D01*
G01X-3151Y514739D02*
X-3378Y515132D01*
G01X-2197Y516550D02*
X-1970Y516156D01*
G01X-3151Y518676D02*
X-3378Y519069D01*
G01X-2197Y520487D02*
X-1970Y520093D01*
G01X-3151Y522613D02*
X-3378Y523006D01*
G01X-2197Y524424D02*
X-1970Y524030D01*
G01X-4259Y508518D02*
X-3378Y508282D01*
G01X-4259Y512455D02*
X-3378Y512219D01*
G01X-10631Y508715D02*
X-9844Y508361D01*
G01X-10631Y512652D02*
X-9844Y512298D01*
G01X-10631Y516589D02*
X-9844Y516235D01*
G01X-10631Y520526D02*
X-9844Y520172D01*
G01X-10631Y524463D02*
X-9844Y524109D01*
G01X-10531Y526555D02*
Y524418D01*
G01Y522618D02*
Y520481D01*
G01Y518681D02*
Y516544D01*
G01Y514744D02*
Y512607D01*
G01Y510807D02*
Y508670D01*
G01X-6694Y524699D02*
Y524109D01*
G01Y522928D02*
Y522337D01*
G01Y520762D02*
Y520172D01*
G01Y518991D02*
Y518400D01*
G01Y516825D02*
Y516235D01*
G01Y515054D02*
Y514463D01*
G01Y512888D02*
Y512298D01*
G01Y511117D02*
Y510526D01*
G01Y508951D02*
Y508361D01*
G01Y507180D02*
Y506589D01*
G01X-4725Y523243D02*
Y522337D01*
G01Y524699D02*
Y523794D01*
G01Y519306D02*
Y518400D01*
G01Y516825D02*
Y515920D01*
G01Y520762D02*
Y519857D01*
G01Y515369D02*
Y514463D01*
G01Y512888D02*
Y511983D01*
G01Y507494D02*
Y506589D01*
G01Y511431D02*
Y510526D01*
G01Y508951D02*
Y508046D01*
G01X-3757Y526589D02*
Y524384D01*
G01Y522652D02*
Y520447D01*
G01Y518715D02*
Y516510D01*
G01Y514778D02*
Y512573D01*
G01Y510841D02*
Y508636D01*
G01X-4725Y508046D02*
X-6694Y508361D01*
G01X-4725Y511983D02*
X-6694Y512298D01*
G01X-4725Y515920D02*
X-6694Y516235D01*
G01X-4725Y519857D02*
X-6694Y520172D01*
G01X-4725Y523794D02*
X-6694Y524109D01*
G01X-4259Y516392D02*
X-3378Y516156D01*
G01X-4259Y520329D02*
X-3378Y520093D01*
G01X-4259Y524266D02*
X-3378Y524030D01*
G01X-2521Y526589D02*
Y524384D01*
G01Y522652D02*
Y520447D01*
G01Y518715D02*
Y516510D01*
G01Y514778D02*
Y512573D01*
G01Y510841D02*
Y508636D01*
G01X-2251Y526904D02*
Y524069D01*
G01Y522967D02*
Y520132D01*
G01Y519030D02*
Y516195D01*
G01Y515093D02*
Y512258D01*
G01Y511156D02*
Y508321D01*
G01X-985Y526156D02*
Y524817D01*
G01Y522219D02*
Y520880D01*
G01Y518282D02*
Y516943D01*
G01Y514345D02*
Y513006D01*
G01Y510408D02*
Y509069D01*
G01X8523Y526156D02*
Y524817D01*
G01Y522219D02*
Y520880D01*
G01Y518282D02*
Y516943D01*
G01Y514345D02*
Y513006D01*
G01Y510408D02*
Y509069D01*
G01X-985Y506471D02*
X-1D01*
G01D02*
X8523D01*
G01D02*
X12600D01*
G01X-4725Y506589D02*
X-6694D01*
G01X-3151Y506865D02*
X-2197D01*
G01X-4725Y507022D02*
X-4259D01*
G01X-9844Y507180D02*
X-6694D01*
G01X-1970Y507258D02*
X-1D01*
G01Y508282D02*
X-1970D01*
G01X-6694Y508361D02*
X-9844D01*
G01X-4259Y508518D02*
X-4725D01*
G01X-2197Y508676D02*
X-3151D01*
G01X-4725Y508951D02*
X-6694D01*
G01X15077Y509069D02*
X8523D01*
G01D02*
X-1D01*
G01D02*
X-985D01*
G01Y510408D02*
X-1D01*
G01D02*
X8523D01*
G01D02*
X12600D01*
G01X-4725Y510526D02*
X-6694D01*
G01X-3151Y510802D02*
X-2197D01*
G01X-4725Y510959D02*
X-4259D01*
G01X-9844Y511117D02*
X-6694D01*
G01X-1970Y511195D02*
X-1D01*
G01Y512219D02*
X-1970D01*
G01X-6694Y512298D02*
X-9844D01*
G01X-4259Y512455D02*
X-4725D01*
G01X-2197Y512613D02*
X-3151D01*
G01X-4725Y512888D02*
X-6694D01*
G01X15077Y513006D02*
X8523D01*
G01D02*
X-1D01*
G01D02*
X-985D01*
G01Y514345D02*
X-1D01*
G01D02*
X8523D01*
G01D02*
X12600D01*
G01X-4725Y514463D02*
X-6694D01*
G01X-3151Y514739D02*
X-2197D01*
G01X-4725Y514896D02*
X-4259D01*
G01X-9844Y515054D02*
X-6694D01*
G01X-1970Y515132D02*
X-1D01*
G01Y516156D02*
X-1970D01*
G01X-6694Y516235D02*
X-9844D01*
G01X-4259Y516392D02*
X-4725D01*
G01X-2197Y516550D02*
X-3151D01*
G01X-4725Y516825D02*
X-6694D01*
G01X15077Y516943D02*
X8523D01*
G01D02*
X-1D01*
G01D02*
X-985D01*
G01Y518282D02*
X-1D01*
G01D02*
X8523D01*
G01D02*
X12600D01*
G01X-4725Y518400D02*
X-6694D01*
G01X-3151Y518676D02*
X-2197D01*
G01X-4725Y518833D02*
X-4259D01*
G01X-9844Y518991D02*
X-6694D01*
G01X-1970Y519069D02*
X-1D01*
G01Y520093D02*
X-1970D01*
G01X-6694Y520172D02*
X-9844D01*
G01X-4259Y520329D02*
X-4725D01*
G01X-2197Y520487D02*
X-3151D01*
G01X-4725Y520762D02*
X-6694D01*
G01X15077Y520880D02*
X8523D01*
G01D02*
X-1D01*
G01D02*
X-985D01*
G01Y522219D02*
X-1D01*
G01D02*
X8523D01*
G01D02*
X12600D01*
G01X-4725Y522337D02*
X-6694D01*
G01X-3151Y522613D02*
X-2197D01*
G01X-4725Y522770D02*
X-4259D01*
G01X-9844Y522928D02*
X-6694D01*
G01X-1970Y523006D02*
X-1D01*
G01Y524030D02*
X-1970D01*
G01X-6694Y524109D02*
X-9844D01*
G01X-4259Y524266D02*
X-4725D01*
G01X-2197Y524424D02*
X-3151D01*
G01X-4725Y524699D02*
X-6694D01*
G01X15077Y524817D02*
X8523D01*
G01D02*
X-1D01*
G01D02*
X-985D01*
G01X-6694Y507180D02*
X-4725Y507494D01*
G01X-6694Y511117D02*
X-4725Y511431D01*
G01X-6694Y515054D02*
X-4725Y515369D01*
G01X-6694Y518991D02*
X-4725Y519306D01*
G01X-6694Y522928D02*
X-4725Y523243D01*
G01X-3378Y507258D02*
X-4259Y507022D01*
G01X-3378Y511195D02*
X-4259Y510959D01*
G01X-3378Y515132D02*
X-4259Y514896D01*
G01X-3378Y519069D02*
X-4259Y518833D01*
G01X-3378Y523006D02*
X-4259Y522770D01*
G01X-3378Y524030D02*
X-3151Y524424D01*
G01X-1970Y523006D02*
X-2197Y522613D01*
G01X-3378Y520093D02*
X-3151Y520487D01*
G01X-1970Y519069D02*
X-2197Y518676D01*
G01X-3378Y516156D02*
X-3151Y516550D01*
G01X-1970Y515132D02*
X-2197Y514739D01*
G01X-3378Y512219D02*
X-3151Y512613D01*
G01X-1970Y511195D02*
X-2197Y510802D01*
G01X-3378Y508282D02*
X-3151Y508676D01*
G01X-1970Y507258D02*
X-2197Y506865D01*
G01X-9844Y522928D02*
X-10631Y522573D01*
G01X-9844Y518991D02*
X-10631Y518636D01*
G01X-9844Y515054D02*
X-10631Y514699D01*
G01X-9844Y511117D02*
X-10631Y510762D01*
G01X-9844Y507180D02*
X-10631Y506825D01*
G01X-3151Y526550D02*
X-3378Y526943D01*
G01X-2197Y528361D02*
X-1970Y527967D01*
G01X-3151Y530487D02*
X-3378Y530880D01*
G01X-2197Y532298D02*
X-1970Y531904D01*
G01X-3151Y534424D02*
X-3378Y534817D01*
G01X-2197Y536235D02*
X-1970Y535841D01*
G01X-3151Y538361D02*
X-3378Y538754D01*
G01X-2197Y540172D02*
X-1970Y539778D01*
G01X-3151Y542298D02*
X-3378Y542691D01*
G01X-2197Y544109D02*
X-1970Y543715D01*
G01X-10631Y528400D02*
X-9844Y528046D01*
G01X-10631Y532337D02*
X-9844Y531983D01*
G01X-10631Y536274D02*
X-9844Y535920D01*
G01X-10631Y540211D02*
X-9844Y539857D01*
G01X-10631Y544148D02*
X-9844Y543794D01*
G01X-10531Y546240D02*
Y544103D01*
G01Y542303D02*
Y540166D01*
G01Y538366D02*
Y536229D01*
G01Y530492D02*
Y528355D01*
G01Y534429D02*
Y532292D01*
G01X-6694Y544384D02*
Y543794D01*
G01Y542613D02*
Y542022D01*
G01Y540447D02*
Y539857D01*
G01Y538676D02*
Y538085D01*
G01Y536510D02*
Y535920D01*
G01Y534739D02*
Y534148D01*
G01Y532573D02*
Y531983D01*
G01Y530802D02*
Y530211D01*
G01Y528636D02*
Y528046D01*
G01Y526865D02*
Y526274D01*
G01X-4725Y544384D02*
Y543479D01*
G01Y542928D02*
Y542022D01*
G01Y540447D02*
Y539542D01*
G01Y538991D02*
Y538085D01*
G01Y536510D02*
Y535605D01*
G01Y535054D02*
Y534148D01*
G01Y531117D02*
Y530211D01*
G01Y532573D02*
Y531668D01*
G01Y527180D02*
Y526274D01*
G01Y528636D02*
Y527731D01*
G01X-3757Y546274D02*
Y544069D01*
G01Y542337D02*
Y540132D01*
G01Y538400D02*
Y536195D01*
G01Y530526D02*
Y528321D01*
G01Y534463D02*
Y532258D01*
G01X-4725Y527731D02*
X-6694Y528046D01*
G01X-4725Y531668D02*
X-6694Y531983D01*
G01X-4725Y535605D02*
X-6694Y535920D01*
G01X-4725Y539542D02*
X-6694Y539857D01*
G01X-4725Y543479D02*
X-6694Y543794D01*
G01X-4259Y528203D02*
X-3378Y527967D01*
G01X-4259Y532140D02*
X-3378Y531904D01*
G01X-4259Y536077D02*
X-3378Y535841D01*
G01X-4259Y540014D02*
X-3378Y539778D01*
G01X-4259Y543951D02*
X-3378Y543715D01*
G01X-2521Y546274D02*
Y544069D01*
G01Y542337D02*
Y540132D01*
G01Y538400D02*
Y536195D01*
G01Y530526D02*
Y528321D01*
G01Y534463D02*
Y532258D01*
G01X-2251Y546589D02*
Y543754D01*
G01Y542652D02*
Y539817D01*
G01Y538715D02*
Y535880D01*
G01Y534778D02*
Y531943D01*
G01Y530841D02*
Y528006D01*
G01X-985Y545841D02*
Y544502D01*
G01Y541904D02*
Y540565D01*
G01Y537967D02*
Y536628D01*
G01Y534030D02*
Y532691D01*
G01Y530093D02*
Y528754D01*
G01X8523Y545841D02*
Y544502D01*
G01Y541904D02*
Y540565D01*
G01Y537967D02*
Y536628D01*
G01Y534030D02*
Y532691D01*
G01Y530093D02*
Y528754D01*
G01X-985Y526156D02*
X-1D01*
G01D02*
X8523D01*
G01D02*
X12600D01*
G01X-4725Y526274D02*
X-6694D01*
G01X-3151Y526550D02*
X-2197D01*
G01X-4725Y526707D02*
X-4259D01*
G01X-9844Y526865D02*
X-6694D01*
G01X-1970Y526943D02*
X-1D01*
G01Y527967D02*
X-1970D01*
G01X-6694Y528046D02*
X-9844D01*
G01X-4259Y528203D02*
X-4725D01*
G01X-2197Y528361D02*
X-3151D01*
G01X-4725Y528636D02*
X-6694D01*
G01X15077Y528754D02*
X8523D01*
G01D02*
X-1D01*
G01D02*
X-985D01*
G01Y530093D02*
X-1D01*
G01D02*
X8523D01*
G01D02*
X12600D01*
G01X-4725Y530211D02*
X-6694D01*
G01X-3151Y530487D02*
X-2197D01*
G01X-4725Y530644D02*
X-4259D01*
G01X-9844Y530802D02*
X-6694D01*
G01X-1970Y530880D02*
X-1D01*
G01Y531904D02*
X-1970D01*
G01X-6694Y531983D02*
X-9844D01*
G01X-4259Y532140D02*
X-4725D01*
G01X-2197Y532298D02*
X-3151D01*
G01X-4725Y532573D02*
X-6694D01*
G01X15077Y532691D02*
X8523D01*
G01D02*
X-1D01*
G01D02*
X-985D01*
G01Y534030D02*
X-1D01*
G01D02*
X8523D01*
G01D02*
X12600D01*
G01X-4725Y534148D02*
X-6694D01*
G01X-3151Y534424D02*
X-2197D01*
G01X-4725Y534581D02*
X-4259D01*
G01X-9844Y534739D02*
X-6694D01*
G01X-1970Y534817D02*
X-1D01*
G01Y535841D02*
X-1970D01*
G01X-6694Y535920D02*
X-9844D01*
G01X-4259Y536077D02*
X-4725D01*
G01X-2197Y536235D02*
X-3151D01*
G01X-4725Y536510D02*
X-6694D01*
G01X15077Y536628D02*
X8523D01*
G01D02*
X-1D01*
G01D02*
X-985D01*
G01Y537967D02*
X-1D01*
G01D02*
X8523D01*
G01D02*
X12600D01*
G01X-4725Y538085D02*
X-6694D01*
G01X-3151Y538361D02*
X-2197D01*
G01X-4725Y538518D02*
X-4259D01*
G01X-9844Y538676D02*
X-6694D01*
G01X-1970Y538754D02*
X-1D01*
G01Y539778D02*
X-1970D01*
G01X-6694Y539857D02*
X-9844D01*
G01X-4259Y540014D02*
X-4725D01*
G01X-2197Y540172D02*
X-3151D01*
G01X-4725Y540447D02*
X-6694D01*
G01X15077Y540565D02*
X8523D01*
G01D02*
X-1D01*
G01D02*
X-985D01*
G01Y541904D02*
X-1D01*
G01D02*
X8523D01*
G01D02*
X12600D01*
G01X-4725Y542022D02*
X-6694D01*
G01X-3151Y542298D02*
X-2197D01*
G01X-4725Y542455D02*
X-4259D01*
G01X-9844Y542613D02*
X-6694D01*
G01X-1970Y542691D02*
X-1D01*
G01Y543715D02*
X-1970D01*
G01X-6694Y543794D02*
X-9844D01*
G01X-4259Y543951D02*
X-4725D01*
G01X-2197Y544109D02*
X-3151D01*
G01X-4725Y544384D02*
X-6694D01*
G01X15077Y544502D02*
X8523D01*
G01D02*
X-1D01*
G01D02*
X-985D01*
G01X-6694Y526865D02*
X-4725Y527180D01*
G01X-6694Y530802D02*
X-4725Y531117D01*
G01X-6694Y534739D02*
X-4725Y535054D01*
G01X-3378Y526943D02*
X-4259Y526707D01*
G01X-3378Y530880D02*
X-4259Y530644D01*
G01X-3378Y534817D02*
X-4259Y534581D01*
G01X-3378Y538754D02*
X-4259Y538518D01*
G01X-3378Y542691D02*
X-4259Y542455D01*
G01X-6694Y538676D02*
X-4725Y538991D01*
G01X-6694Y542613D02*
X-4725Y542928D01*
G01X-3378Y543715D02*
X-3151Y544109D01*
G01X-1970Y542691D02*
X-2197Y542298D01*
G01X-3378Y539778D02*
X-3151Y540172D01*
G01X-1970Y538754D02*
X-2197Y538361D01*
G01X-3378Y535841D02*
X-3151Y536235D01*
G01X-1970Y534817D02*
X-2197Y534424D01*
G01X-3378Y531904D02*
X-3151Y532298D01*
G01X-1970Y530880D02*
X-2197Y530487D01*
G01X-3378Y527967D02*
X-3151Y528361D01*
G01X-1970Y526943D02*
X-2197Y526550D01*
G01X-9844Y542613D02*
X-10631Y542258D01*
G01X-9844Y538676D02*
X-10631Y538321D01*
G01X-9844Y534739D02*
X-10631Y534384D01*
G01X-9844Y530802D02*
X-10631Y530447D01*
G01X-9844Y526865D02*
X-10631Y526510D01*
G01X-3151Y546235D02*
X-3378Y546628D01*
G01X-2197Y548046D02*
X-1970Y547652D01*
G01X-3151Y550172D02*
X-3378Y550565D01*
G01X-10631Y548085D02*
X-9844Y547731D01*
G01X-10631Y552022D02*
X-9844Y551668D01*
G01X-10631Y555959D02*
X-9844Y555605D01*
G01X-10631Y559896D02*
X-9844Y559542D01*
G01X-2197Y551983D02*
X-1970Y551589D01*
G01X-3151Y554109D02*
X-3378Y554502D01*
G01X-2197Y555920D02*
X-1970Y555526D01*
G01X-3151Y558046D02*
X-3378Y558439D01*
G01X-2197Y559857D02*
X-1970Y559463D01*
G01X-3151Y561983D02*
X-3378Y562376D01*
G01X-10531Y561988D02*
Y559851D01*
G01Y554114D02*
Y551977D01*
G01Y558051D02*
Y555914D01*
G01Y550177D02*
Y548040D01*
G01X-6694Y562298D02*
Y561707D01*
G01Y560132D02*
Y559542D01*
G01Y558361D02*
Y557770D01*
G01Y556195D02*
Y555605D01*
G01Y554424D02*
Y553833D01*
G01Y552258D02*
Y551668D01*
G01Y550487D02*
Y549896D01*
G01Y548321D02*
Y547731D01*
G01Y546550D02*
Y545959D01*
G01X-4725Y564069D02*
Y563164D01*
G01Y562613D02*
Y561707D01*
G01Y560132D02*
Y559227D01*
G01Y558676D02*
Y557770D01*
G01Y556195D02*
Y555290D01*
G01Y554739D02*
Y553833D01*
G01Y552258D02*
Y551353D01*
G01Y550802D02*
Y549896D01*
G01Y548321D02*
Y547416D01*
G01Y546865D02*
Y545959D01*
G01X-3757Y562022D02*
Y559817D01*
G01Y554148D02*
Y551943D01*
G01Y558085D02*
Y555880D01*
G01Y550211D02*
Y548006D01*
G01X-4725Y547416D02*
X-6694Y547731D01*
G01X-4259Y547888D02*
X-3378Y547652D01*
G01X-4259Y551825D02*
X-3378Y551589D01*
G01X-4259Y555762D02*
X-3378Y555526D01*
G01X-4259Y559699D02*
X-3378Y559463D01*
G01X-2521Y562022D02*
Y559817D01*
G01Y554148D02*
Y551943D01*
G01Y558085D02*
Y555880D01*
G01Y550211D02*
Y548006D01*
G01X-2251Y562337D02*
Y559502D01*
G01Y558400D02*
Y555565D01*
G01Y554463D02*
Y551628D01*
G01Y550526D02*
Y547691D01*
G01X-985Y561589D02*
Y560250D01*
G01Y557652D02*
Y556313D01*
G01Y549778D02*
Y548439D01*
G01Y553715D02*
Y552376D01*
G01X8523Y561589D02*
Y560250D01*
G01Y557652D02*
Y556313D01*
G01Y553715D02*
Y552376D01*
G01Y549778D02*
Y548439D01*
G01X-985Y545841D02*
X-1D01*
G01D02*
X8523D01*
G01D02*
X12600D01*
G01X-4725Y545959D02*
X-6694D01*
G01X-3151Y546235D02*
X-2197D01*
G01X-4725Y546392D02*
X-4259D01*
G01X-9844Y546550D02*
X-6694D01*
G01X-1970Y546628D02*
X-1D01*
G01Y547652D02*
X-1970D01*
G01X-6694Y547731D02*
X-9844D01*
G01X-4259Y547888D02*
X-4725D01*
G01X-2197Y548046D02*
X-3151D01*
G01X-4725Y548321D02*
X-6694D01*
G01X15077Y548439D02*
X8523D01*
G01D02*
X-1D01*
G01D02*
X-985D01*
G01X-4725Y551353D02*
X-6694Y551668D01*
G01X-4725Y555290D02*
X-6694Y555605D01*
G01X-4725Y559227D02*
X-6694Y559542D01*
G01X-4725Y563164D02*
X-6694Y563479D01*
G01X-985Y549778D02*
X-1D01*
G01D02*
X8523D01*
G01D02*
X12600D01*
G01X-4725Y549896D02*
X-6694D01*
G01X-3151Y550172D02*
X-2197D01*
G01X-4725Y550329D02*
X-4259D01*
G01X-9844Y550487D02*
X-6694D01*
G01X-1970Y550565D02*
X-1D01*
G01Y551589D02*
X-1970D01*
G01X-6694Y551668D02*
X-9844D01*
G01X-4259Y551825D02*
X-4725D01*
G01X-2197Y551983D02*
X-3151D01*
G01X-4725Y552258D02*
X-6694D01*
G01X15077Y552376D02*
X8523D01*
G01D02*
X-1D01*
G01D02*
X-985D01*
G01Y553715D02*
X-1D01*
G01D02*
X8523D01*
G01D02*
X12600D01*
G01X-4725Y553833D02*
X-6694D01*
G01X-3151Y554109D02*
X-2197D01*
G01X-4725Y554266D02*
X-4259D01*
G01X-9844Y554424D02*
X-6694D01*
G01X-1970Y554502D02*
X-1D01*
G01Y555526D02*
X-1970D01*
G01X-6694Y555605D02*
X-9844D01*
G01X-4259Y555762D02*
X-4725D01*
G01X-2197Y555920D02*
X-3151D01*
G01X-4725Y556195D02*
X-6694D01*
G01X15077Y556313D02*
X8523D01*
G01D02*
X-1D01*
G01D02*
X-985D01*
G01Y557652D02*
X-1D01*
G01D02*
X8523D01*
G01D02*
X12600D01*
G01X-4725Y557770D02*
X-6694D01*
G01X-3151Y558046D02*
X-2197D01*
G01X-4725Y558203D02*
X-4259D01*
G01X-9844Y558361D02*
X-6694D01*
G01X-1970Y558439D02*
X-1D01*
G01Y559463D02*
X-1970D01*
G01X-6694Y559542D02*
X-9844D01*
G01X-4259Y559699D02*
X-4725D01*
G01X-2197Y559857D02*
X-3151D01*
G01X-4725Y560132D02*
X-6694D01*
G01X15077Y560250D02*
X8523D01*
G01D02*
X-1D01*
G01D02*
X-985D01*
G01Y561589D02*
X-1D01*
G01D02*
X8523D01*
G01D02*
X12600D01*
G01X-4725Y561707D02*
X-6694D01*
G01X-3151Y561983D02*
X-2197D01*
G01X-4725Y562140D02*
X-4259D01*
G01X-9844Y562298D02*
X-6694D01*
G01X-1970Y562376D02*
X-1D01*
G01X-3378Y546628D02*
X-4259Y546392D01*
G01X-3378Y550565D02*
X-4259Y550329D01*
G01X-6694Y546550D02*
X-4725Y546865D01*
G01X-6694Y550487D02*
X-4725Y550802D01*
G01X-6694Y554424D02*
X-4725Y554739D01*
G01X-6694Y558361D02*
X-4725Y558676D01*
G01X-6694Y562298D02*
X-4725Y562613D01*
G01X-1970Y562376D02*
X-2197Y561983D01*
G01X-3378Y559463D02*
X-3151Y559857D01*
G01X-1970Y558439D02*
X-2197Y558046D01*
G01X-3378Y555526D02*
X-3151Y555920D01*
G01X-1970Y554502D02*
X-2197Y554109D01*
G01X-3378Y551589D02*
X-3151Y551983D01*
G01X-1970Y550565D02*
X-2197Y550172D01*
G01X-3378Y547652D02*
X-3151Y548046D01*
G01X-1970Y546628D02*
X-2197Y546235D01*
G01X-3378Y554502D02*
X-4259Y554266D01*
G01X-3378Y558439D02*
X-4259Y558203D01*
G01X-3378Y562376D02*
X-4259Y562140D01*
G01X-9844Y562298D02*
X-10631Y561943D01*
G01X-9844Y558361D02*
X-10631Y558006D01*
G01X-9844Y554424D02*
X-10631Y554069D01*
G01X-9844Y550487D02*
X-10631Y550132D01*
G01X-9844Y546550D02*
X-10631Y546195D01*
G01X-38426Y566038D02*
Y563676D01*
G01X-38108Y565339D02*
Y564374D01*
G01X-37871Y565362D02*
Y564351D01*
G01X-35595Y565581D02*
Y564132D01*
G01X-35546Y566038D02*
Y563676D01*
G01X-35357Y565604D02*
Y564109D01*
G01X-34607Y565959D02*
Y563754D01*
G01X-34136Y565618D02*
Y564095D01*
G01X-33153Y565629D02*
Y564084D01*
G01X-32319Y565638D02*
Y564075D01*
G01X-31941Y565643D02*
Y564070D01*
G01X-38108Y564374D02*
X-35351Y564109D01*
G01Y565605D02*
X-38108Y565339D01*
G01X-35351Y565605D02*
X-10631Y565880D01*
G01X-39607Y563676D02*
X-24509D01*
G01X-35546Y563754D02*
X-1D01*
G01X-27993Y565743D02*
X-39607D01*
G01X-10631Y563833D02*
X-35351Y564109D01*
G01X-38426Y585723D02*
Y583361D01*
G01Y581786D02*
Y579424D01*
G01Y577849D02*
Y575487D01*
G01Y573912D02*
Y571550D01*
G01Y569975D02*
Y567613D01*
G01X-38108Y585024D02*
Y584059D01*
G01Y577150D02*
Y576185D01*
G01Y581087D02*
Y580122D01*
G01Y573213D02*
Y572248D01*
G01Y569276D02*
Y568311D01*
G01X-37871Y585047D02*
Y584036D01*
G01Y577173D02*
Y576162D01*
G01Y581110D02*
Y580099D01*
G01Y573236D02*
Y572225D01*
G01Y569299D02*
Y568288D01*
G01X-35595Y585266D02*
Y583817D01*
G01Y581329D02*
Y579880D01*
G01Y573455D02*
Y572006D01*
G01Y577392D02*
Y575943D01*
G01Y569518D02*
Y568069D01*
G01X-35546Y585723D02*
Y583361D01*
G01Y581786D02*
Y579424D01*
G01Y577849D02*
Y575487D01*
G01Y573912D02*
Y571550D01*
G01Y569975D02*
Y567613D01*
G01X-35357Y585289D02*
Y583794D01*
G01Y577415D02*
Y575920D01*
G01Y581352D02*
Y579857D01*
G01Y573478D02*
Y571983D01*
G01Y569541D02*
Y568046D01*
G01X-34607Y585644D02*
Y583439D01*
G01Y581707D02*
Y579502D01*
G01Y573833D02*
Y571628D01*
G01Y577770D02*
Y575565D01*
G01Y569896D02*
Y567691D01*
G01X-34136Y585303D02*
Y583780D01*
G01Y577429D02*
Y575906D01*
G01Y581366D02*
Y579843D01*
G01Y573492D02*
Y571969D01*
G01Y569555D02*
Y568032D01*
G01X-33153Y585314D02*
Y583769D01*
G01Y581377D02*
Y579832D01*
G01Y573503D02*
Y571958D01*
G01Y577440D02*
Y575895D01*
G01Y569566D02*
Y568021D01*
G01X-32319Y585323D02*
Y583760D01*
G01Y577449D02*
Y575886D01*
G01Y581386D02*
Y579823D01*
G01Y573512D02*
Y571949D01*
G01Y569575D02*
Y568012D01*
G01X-31941Y585328D02*
Y583756D01*
G01Y577454D02*
Y575881D01*
G01Y581391D02*
Y579819D01*
G01Y573517D02*
Y571944D01*
G01Y569580D02*
Y568007D01*
G01X-38108Y568311D02*
X-35351Y568046D01*
G01X-38108Y572248D02*
X-35351Y571983D01*
G01X-38108Y576185D02*
X-35351Y575920D01*
G01X-38108Y580122D02*
X-35351Y579857D01*
G01X-38108Y584059D02*
X-35351Y583794D01*
G01Y569542D02*
X-38108Y569276D01*
G01X-35351Y569542D02*
X-10631Y569817D01*
G01X-35351Y573479D02*
X-10631Y573754D01*
G01X-35351Y577416D02*
X-10631Y577691D01*
G01X-35351Y581353D02*
X-10631Y581628D01*
G01X-35351Y585290D02*
X-10631Y585565D01*
G01X-35546Y565959D02*
X-1D01*
G01X-24509Y566038D02*
X-39607D01*
G01Y567613D02*
X-24509D01*
G01X-35546Y567691D02*
X-1D01*
G01X-39607Y568892D02*
X-24844D01*
G01X-35546Y569896D02*
X-1D01*
G01X-24509Y569975D02*
X-39607D01*
G01Y571550D02*
X-24509D01*
G01X-35546Y571628D02*
X-1D01*
G01X-39607Y572869D02*
X-24844D01*
G01X-35546Y573833D02*
X-1D01*
G01X-24509Y573912D02*
X-39607D01*
G01Y575487D02*
X-24509D01*
G01X-35546Y575565D02*
X-1D01*
G01X-39607Y576018D02*
X-27993D01*
G01X-35546Y577770D02*
X-1D01*
G01X-24509Y577849D02*
X-39607D01*
G01Y579424D02*
X-24509D01*
G01X-35546Y579502D02*
X-1D01*
G01X-35546Y581707D02*
X-1D01*
G01X-24509Y581786D02*
X-39607D01*
G01Y583361D02*
X-24509D01*
G01X-35546Y583439D02*
X-1D01*
G01X-35546Y585644D02*
X-1D01*
G01X-24509Y585723D02*
X-39607D01*
G01X-10631Y567770D02*
X-35351Y568046D01*
G01X-10631Y571707D02*
X-35351Y571983D01*
G01X-10631Y575644D02*
X-35351Y575920D01*
G01X-10631Y579581D02*
X-35351Y579857D01*
G01X-10631Y583518D02*
X-35351Y583794D01*
G01Y573479D02*
X-38108Y573213D01*
G01X-35351Y577416D02*
X-38108Y577150D01*
G01X-35351Y581353D02*
X-38108Y581087D01*
G01X-35351Y585290D02*
X-38108Y585024D01*
G01X-38426Y605408D02*
Y603046D01*
G01Y597534D02*
Y595172D01*
G01Y601471D02*
Y599109D01*
G01Y593597D02*
Y591235D01*
G01Y589660D02*
Y587298D01*
G01X-38108Y604709D02*
Y603744D01*
G01Y600772D02*
Y599807D01*
G01Y596835D02*
Y595870D01*
G01Y592898D02*
Y591933D01*
G01Y588961D02*
Y587996D01*
G01X-37871Y600795D02*
Y599784D01*
G01Y604732D02*
Y603721D01*
G01Y596858D02*
Y595847D01*
G01Y592921D02*
Y591910D01*
G01Y588984D02*
Y587973D01*
G01X-35595Y604951D02*
Y603502D01*
G01Y601014D02*
Y599565D01*
G01Y597077D02*
Y595628D01*
G01Y593140D02*
Y591691D01*
G01Y589203D02*
Y587754D01*
G01X-35546Y605408D02*
Y603046D01*
G01Y601471D02*
Y599109D01*
G01Y597534D02*
Y595172D01*
G01Y593597D02*
Y591235D01*
G01Y589660D02*
Y587298D01*
G01X-35357Y604974D02*
Y603479D01*
G01Y601037D02*
Y599542D01*
G01Y597100D02*
Y595605D01*
G01Y593163D02*
Y591668D01*
G01Y589226D02*
Y587731D01*
G01X-34607Y605329D02*
Y603124D01*
G01Y597455D02*
Y595250D01*
G01Y601392D02*
Y599187D01*
G01Y593518D02*
Y591313D01*
G01Y589581D02*
Y587376D01*
G01X-34136Y601051D02*
Y599528D01*
G01Y604988D02*
Y603465D01*
G01Y597114D02*
Y595591D01*
G01Y593177D02*
Y591654D01*
G01Y589240D02*
Y587717D01*
G01X-33153Y604999D02*
Y603454D01*
G01Y601062D02*
Y599517D01*
G01Y597125D02*
Y595580D01*
G01Y593188D02*
Y591643D01*
G01Y589251D02*
Y587706D01*
G01X-32319Y601071D02*
Y599508D01*
G01Y605008D02*
Y603445D01*
G01Y597134D02*
Y595571D01*
G01Y593197D02*
Y591634D01*
G01Y589260D02*
Y587697D01*
G01X-31941Y601076D02*
Y599504D01*
G01Y605013D02*
Y603441D01*
G01Y597139D02*
Y595567D01*
G01Y593202D02*
Y591630D01*
G01Y589265D02*
Y587693D01*
G01X-38108Y587996D02*
X-35351Y587731D01*
G01X-38108Y591933D02*
X-35351Y591668D01*
G01X-38108Y595870D02*
X-35351Y595605D01*
G01X-38108Y599807D02*
X-35351Y599542D01*
G01Y589227D02*
X-10631Y589502D01*
G01X-35351Y593164D02*
X-10631Y593439D01*
G01X-35351Y597101D02*
X-10631Y597376D01*
G01X-35351Y601038D02*
X-10631Y601313D01*
G01X-35351Y604975D02*
X-10631Y605250D01*
G01X-39607Y587298D02*
X-24509D01*
G01X-35546Y587376D02*
X-1D01*
G01X-27993Y589365D02*
X-39607D01*
G01X-35546Y589581D02*
X-1D01*
G01X-24509Y589660D02*
X-39607D01*
G01Y591235D02*
X-24509D01*
G01X-35546Y591313D02*
X-1D01*
G01X-39607Y592514D02*
X-24844D01*
G01X-35546Y593518D02*
X-1D01*
G01X-24509Y593597D02*
X-39607D01*
G01Y595172D02*
X-24509D01*
G01X-35546Y595250D02*
X-1D01*
G01X-39607Y596491D02*
X-24844D01*
G01X-35546Y597455D02*
X-1D01*
G01X-24509Y597534D02*
X-39607D01*
G01Y599109D02*
X-24509D01*
G01X-35546Y599187D02*
X-1D01*
G01X-39607Y599640D02*
X-27993D01*
G01X-35546Y601392D02*
X-1D01*
G01X-24509Y601471D02*
X-39607D01*
G01Y603046D02*
X-24509D01*
G01X-35546Y603124D02*
X-1D01*
G01X-35546Y605329D02*
X-1D01*
G01X-24509Y605408D02*
X-39607D01*
G01X-10631Y587455D02*
X-35351Y587731D01*
G01X-10631Y591392D02*
X-35351Y591668D01*
G01X-10631Y595329D02*
X-35351Y595605D01*
G01X-10631Y599266D02*
X-35351Y599542D01*
G01X-10631Y603203D02*
X-35351Y603479D01*
G01X-38108Y603744D02*
X-35351Y603479D01*
G01Y589227D02*
X-38108Y588961D01*
G01X-35351Y593164D02*
X-38108Y592898D01*
G01X-35351Y597101D02*
X-38108Y596835D01*
G01X-35351Y601038D02*
X-38108Y600772D01*
G01X-35351Y604975D02*
X-38108Y604709D01*
G01X-38426Y621156D02*
Y618794D01*
G01Y625093D02*
Y622731D01*
G01Y617219D02*
Y614857D01*
G01Y613282D02*
Y610920D01*
G01Y609345D02*
Y606983D01*
G01X-38108Y624394D02*
Y623429D01*
G01Y620457D02*
Y619492D01*
G01Y616520D02*
Y615555D01*
G01Y612583D02*
Y611618D01*
G01Y608646D02*
Y607681D01*
G01X-37871Y624417D02*
Y623406D01*
G01Y620480D02*
Y619469D01*
G01Y616543D02*
Y615532D01*
G01Y612606D02*
Y611595D01*
G01Y608669D02*
Y607658D01*
G01X-35595Y624636D02*
Y623187D01*
G01Y620699D02*
Y619250D01*
G01Y616762D02*
Y615313D01*
G01Y612825D02*
Y611376D01*
G01Y608888D02*
Y607439D01*
G01X-35546Y625093D02*
Y622731D01*
G01Y621156D02*
Y618794D01*
G01Y617219D02*
Y614857D01*
G01Y613282D02*
Y610920D01*
G01Y609345D02*
Y606983D01*
G01X-35357Y624659D02*
Y623164D01*
G01Y620722D02*
Y619227D01*
G01Y616785D02*
Y615290D01*
G01Y612848D02*
Y611353D01*
G01Y608911D02*
Y607416D01*
G01X-34607Y621077D02*
Y618872D01*
G01Y625014D02*
Y622809D01*
G01Y617140D02*
Y614935D01*
G01Y613203D02*
Y610998D01*
G01Y609266D02*
Y607061D01*
G01X-34136Y624673D02*
Y623150D01*
G01Y620736D02*
Y619213D01*
G01Y616799D02*
Y615276D01*
G01Y612862D02*
Y611339D01*
G01Y608925D02*
Y607402D01*
G01X-33153Y624684D02*
Y623139D01*
G01Y620747D02*
Y619202D01*
G01Y616810D02*
Y615265D01*
G01Y612873D02*
Y611328D01*
G01Y608936D02*
Y607391D01*
G01X-32319Y624693D02*
Y623130D01*
G01Y620756D02*
Y619193D01*
G01Y616819D02*
Y615256D01*
G01Y612882D02*
Y611319D01*
G01Y608945D02*
Y607382D01*
G01X-31941Y624698D02*
Y623126D01*
G01Y620761D02*
Y619189D01*
G01Y616824D02*
Y615252D01*
G01Y612887D02*
Y611315D01*
G01Y608950D02*
Y607378D01*
G01X-35351Y608912D02*
X-10631Y609187D01*
G01X-35351Y612849D02*
X-10631Y613124D01*
G01X-35351Y616786D02*
X-10631Y617061D01*
G01X-39607Y606983D02*
X-24509D01*
G01X-35546Y607061D02*
X-1D01*
G01X-35546Y609266D02*
X-1D01*
G01X-24509Y609345D02*
X-39607D01*
G01Y610920D02*
X-24509D01*
G01X-35546Y610998D02*
X-1D01*
G01X-27993Y612987D02*
X-39607D01*
G01X-35546Y613203D02*
X-1D01*
G01X-24509Y613282D02*
X-39607D01*
G01Y614857D02*
X-24509D01*
G01X-35546Y614935D02*
X-1D01*
G01X-39607Y616136D02*
X-24844D01*
G01X-35546Y617140D02*
X-1D01*
G01X-24509Y617219D02*
X-39607D01*
G01Y618794D02*
X-24509D01*
G01X-35546Y618872D02*
X-1D01*
G01X-39607Y620113D02*
X-24844D01*
G01X-35546Y621077D02*
X-1D01*
G01X-24509Y621156D02*
X-39607D01*
G01Y622731D02*
X-24509D01*
G01X-35546Y622809D02*
X-1D01*
G01X-39607Y623262D02*
X-27993D01*
G01X-35546Y625014D02*
X-1D01*
G01X-24509Y625093D02*
X-39607D01*
G01X-10631Y607140D02*
X-35351Y607416D01*
G01X-10631Y611077D02*
X-35351Y611353D01*
G01X-10631Y615014D02*
X-35351Y615290D01*
G01X-10631Y618951D02*
X-35351Y619227D01*
G01X-10631Y622888D02*
X-35351Y623164D01*
G01X-38108Y607681D02*
X-35351Y607416D01*
G01X-38108Y611618D02*
X-35351Y611353D01*
G01X-38108Y615555D02*
X-35351Y615290D01*
G01X-38108Y619492D02*
X-35351Y619227D01*
G01X-38108Y623429D02*
X-35351Y623164D01*
G01Y608912D02*
X-38108Y608646D01*
G01X-35351Y612849D02*
X-38108Y612583D01*
G01X-35351Y616786D02*
X-38108Y616520D01*
G01X-35351Y620723D02*
X-38108Y620457D01*
G01X-35351Y624660D02*
X-38108Y624394D01*
G01X-35351Y620723D02*
X-10631Y620998D01*
G01X-35351Y624660D02*
X-10631Y624935D01*
G01X-38426Y644778D02*
Y642416D01*
G01Y640841D02*
Y638479D01*
G01Y636904D02*
Y634542D01*
G01Y629030D02*
Y626668D01*
G01Y632967D02*
Y630605D01*
G01X-38108Y644079D02*
Y643114D01*
G01Y640142D02*
Y639177D01*
G01Y636205D02*
Y635240D01*
G01Y632268D02*
Y631303D01*
G01Y628331D02*
Y627366D01*
G01X-37871Y644102D02*
Y643091D01*
G01Y640165D02*
Y639154D01*
G01Y636228D02*
Y635217D01*
G01Y632291D02*
Y631280D01*
G01Y628354D02*
Y627343D01*
G01X-35595Y644321D02*
Y642872D01*
G01Y640384D02*
Y638935D01*
G01Y636447D02*
Y634998D01*
G01Y632510D02*
Y631061D01*
G01Y628573D02*
Y627124D01*
G01X-35546Y644778D02*
Y642416D01*
G01Y640841D02*
Y638479D01*
G01Y636904D02*
Y634542D01*
G01Y632967D02*
Y630605D01*
G01Y629030D02*
Y626668D01*
G01X-35357Y644344D02*
Y642849D01*
G01Y640407D02*
Y638912D01*
G01Y636470D02*
Y634975D01*
G01Y632533D02*
Y631038D01*
G01Y628596D02*
Y627101D01*
G01X-34607Y644699D02*
Y642494D01*
G01Y640762D02*
Y638557D01*
G01Y636825D02*
Y634620D01*
G01Y628951D02*
Y626746D01*
G01Y632888D02*
Y630683D01*
G01X-34136Y644358D02*
Y642835D01*
G01Y640421D02*
Y638898D01*
G01Y636484D02*
Y634961D01*
G01Y632547D02*
Y631024D01*
G01Y628610D02*
Y627087D01*
G01X-33153Y644369D02*
Y642824D01*
G01Y640432D02*
Y638887D01*
G01Y636495D02*
Y634950D01*
G01Y632558D02*
Y631013D01*
G01Y628621D02*
Y627076D01*
G01X-32319Y644378D02*
Y642815D01*
G01Y640441D02*
Y638878D01*
G01Y636504D02*
Y634941D01*
G01Y632567D02*
Y631004D01*
G01Y628630D02*
Y627067D01*
G01X-31941Y644383D02*
Y642811D01*
G01Y640446D02*
Y638874D01*
G01Y636509D02*
Y634937D01*
G01Y628635D02*
Y627063D01*
G01Y632572D02*
Y631000D01*
G01X-10631Y626825D02*
X-35351Y627101D01*
G01X-10631Y630762D02*
X-35351Y631038D01*
G01X-38108Y627366D02*
X-35351Y627101D01*
G01X-38108Y631303D02*
X-35351Y631038D01*
G01X-38108Y635240D02*
X-35351Y634975D01*
G01X-38108Y639177D02*
X-35351Y638912D01*
G01X-38108Y643114D02*
X-35351Y642849D01*
G01Y628597D02*
X-38108Y628331D01*
G01X-35351Y632534D02*
X-38108Y632268D01*
G01X-35351Y636471D02*
X-38108Y636205D01*
G01X-35351Y640408D02*
X-38108Y640142D01*
G01X-35351Y644345D02*
X-38108Y644079D01*
G01X-35351Y628597D02*
X-10631Y628872D01*
G01X-35351Y632534D02*
X-10631Y632809D01*
G01X-35351Y636471D02*
X-10631Y636746D01*
G01X-35351Y640408D02*
X-10631Y640683D01*
G01X-35351Y644345D02*
X-10631Y644620D01*
G01X-39607Y626668D02*
X-24509D01*
G01X-35546Y626746D02*
X-1D01*
G01X-35546Y628951D02*
X-1D01*
G01X-24509Y629030D02*
X-39607D01*
G01Y630605D02*
X-24509D01*
G01X-35546Y630683D02*
X-1D01*
G01X-35546Y632888D02*
X-1D01*
G01X-24509Y632967D02*
X-39607D01*
G01Y634542D02*
X-24509D01*
G01X-35546Y634620D02*
X-1D01*
G01X-27993Y636609D02*
X-39607D01*
G01X-35546Y636825D02*
X-1D01*
G01X-24509Y636904D02*
X-39607D01*
G01Y638479D02*
X-24509D01*
G01X-35546Y638557D02*
X-1D01*
G01X-39607Y639758D02*
X-24844D01*
G01X-35546Y640762D02*
X-1D01*
G01X-24509Y640841D02*
X-39607D01*
G01Y642416D02*
X-24509D01*
G01X-35546Y642494D02*
X-1D01*
G01X-39607Y643735D02*
X-24844D01*
G01X-35546Y644699D02*
X-1D01*
G01X-24509Y644778D02*
X-39607D01*
G01X-10631Y634699D02*
X-35351Y634975D01*
G01X-10631Y638636D02*
X-35351Y638912D01*
G01X-10631Y642573D02*
X-35351Y642849D01*
G01X-27265Y566038D02*
Y563676D01*
G01X-26943Y565698D02*
Y564015D01*
G01X-26566Y565702D02*
Y564011D01*
G01X-24509Y566038D02*
Y563676D01*
G01X-24122Y565730D02*
Y563983D01*
G01X-23684Y565735D02*
Y563978D01*
G01X-12993Y563754D02*
Y563439D01*
G01X-12280Y565862D02*
Y563851D01*
G01X-11843Y565867D02*
Y563846D01*
G01X-12993Y563439D02*
X-1D01*
G01X-27993Y572869D02*
Y592514D01*
G01X-27265Y585723D02*
Y583361D01*
G01Y581786D02*
Y579424D01*
G01Y577849D02*
Y575487D01*
G01Y573912D02*
Y571550D01*
G01Y569975D02*
Y567613D01*
G01X-26943Y585383D02*
Y583700D01*
G01Y577509D02*
Y575826D01*
G01Y581446D02*
Y579763D01*
G01Y573572D02*
Y571889D01*
G01Y569635D02*
Y567952D01*
G01X-26566Y585387D02*
Y583696D01*
G01Y577513D02*
Y575822D01*
G01Y581450D02*
Y579759D01*
G01Y573576D02*
Y571885D01*
G01Y569639D02*
Y567948D01*
G01X-24844Y572869D02*
Y592514D01*
G01X-24509Y585723D02*
Y583361D01*
G01Y581786D02*
Y579424D01*
G01Y577849D02*
Y575487D01*
G01Y573912D02*
Y571550D01*
G01Y569975D02*
Y567613D01*
G01X-24122Y585415D02*
Y583669D01*
G01Y577541D02*
Y575794D01*
G01Y581478D02*
Y579731D01*
G01Y573604D02*
Y571857D01*
G01Y569667D02*
Y567920D01*
G01X-23684Y585420D02*
Y583663D01*
G01Y577546D02*
Y575789D01*
G01Y581483D02*
Y579726D01*
G01Y573609D02*
Y571852D01*
G01Y569672D02*
Y567915D01*
G01X-12993Y583439D02*
Y583124D01*
G01Y585959D02*
Y585644D01*
G01Y582022D02*
Y581707D01*
G01Y579502D02*
Y579187D01*
G01Y578085D02*
Y577770D01*
G01Y575565D02*
Y575250D01*
G01Y574148D02*
Y573833D01*
G01Y571628D02*
Y571313D01*
G01Y570211D02*
Y569896D01*
G01Y567691D02*
Y567376D01*
G01Y566274D02*
Y565959D01*
G01X-12280Y585547D02*
Y583536D01*
G01Y577673D02*
Y575662D01*
G01Y581610D02*
Y579599D01*
G01Y573736D02*
Y571725D01*
G01Y569799D02*
Y567788D01*
G01X-11843Y585552D02*
Y583531D01*
G01Y577678D02*
Y575657D01*
G01Y581615D02*
Y579594D01*
G01Y573741D02*
Y571720D01*
G01Y569804D02*
Y567783D01*
G01X-1Y566274D02*
X-12993D01*
G01Y567376D02*
X-1D01*
G01Y570211D02*
X-12993D01*
G01Y571313D02*
X-1D01*
G01Y574148D02*
X-12993D01*
G01Y575250D02*
X-1D01*
G01Y578085D02*
X-12993D01*
G01Y579187D02*
X-1D01*
G01Y582022D02*
X-12993D01*
G01Y583124D02*
X-1D01*
G01X-27993Y596491D02*
Y616136D01*
G01X-27265Y605408D02*
Y603046D01*
G01Y601471D02*
Y599109D01*
G01Y597534D02*
Y595172D01*
G01Y593597D02*
Y591235D01*
G01Y589660D02*
Y587298D01*
G01X-26943Y605069D02*
Y603385D01*
G01Y601131D02*
Y599448D01*
G01Y597194D02*
Y595511D01*
G01Y593257D02*
Y591574D01*
G01Y589320D02*
Y587637D01*
G01X-26566Y605072D02*
Y603381D01*
G01Y601135D02*
Y599444D01*
G01Y597198D02*
Y595507D01*
G01Y593261D02*
Y591570D01*
G01Y589324D02*
Y587633D01*
G01X-24844Y596491D02*
Y616136D01*
G01X-24509Y605408D02*
Y603046D01*
G01Y601471D02*
Y599109D01*
G01Y597534D02*
Y595172D01*
G01Y593597D02*
Y591235D01*
G01Y589660D02*
Y587298D01*
G01X-24122Y601163D02*
Y599417D01*
G01Y605100D02*
Y603354D01*
G01Y597226D02*
Y595480D01*
G01Y593289D02*
Y591543D01*
G01Y589352D02*
Y587606D01*
G01X-23684Y601168D02*
Y599411D01*
G01Y605105D02*
Y603348D01*
G01Y597231D02*
Y595474D01*
G01Y593294D02*
Y591537D01*
G01Y589357D02*
Y587600D01*
G01X-12993Y605644D02*
Y605329D01*
G01Y603124D02*
Y602809D01*
G01Y601707D02*
Y601392D01*
G01Y599187D02*
Y598872D01*
G01Y597770D02*
Y597455D01*
G01Y595250D02*
Y594935D01*
G01Y591313D02*
Y590998D01*
G01Y593833D02*
Y593518D01*
G01Y587376D02*
Y587061D01*
G01Y589896D02*
Y589581D01*
G01X-12280Y605232D02*
Y603221D01*
G01Y601295D02*
Y599284D01*
G01Y597358D02*
Y595347D01*
G01Y593421D02*
Y591410D01*
G01Y589484D02*
Y587473D01*
G01X-11843Y605237D02*
Y603217D01*
G01Y601300D02*
Y599280D01*
G01Y597363D02*
Y595343D01*
G01Y593426D02*
Y591406D01*
G01Y589489D02*
Y587469D01*
G01X-1Y585959D02*
X-12993D01*
G01Y587061D02*
X-1D01*
G01Y589896D02*
X-12993D01*
G01Y590998D02*
X-1D01*
G01Y593833D02*
X-12993D01*
G01Y594935D02*
X-1D01*
G01Y597770D02*
X-12993D01*
G01Y598872D02*
X-1D01*
G01Y601707D02*
X-12993D01*
G01Y602809D02*
X-1D01*
G01Y605644D02*
X-12993D01*
G01X-27993Y620113D02*
Y639758D01*
G01X-27265Y625093D02*
Y622731D01*
G01Y621156D02*
Y618794D01*
G01Y617219D02*
Y614857D01*
G01Y613282D02*
Y610920D01*
G01Y609345D02*
Y606983D01*
G01X-26943Y624754D02*
Y623070D01*
G01Y620817D02*
Y619133D01*
G01Y616880D02*
Y615196D01*
G01Y612943D02*
Y611259D01*
G01Y609006D02*
Y607322D01*
G01X-26566Y624757D02*
Y623066D01*
G01Y620820D02*
Y619129D01*
G01Y616883D02*
Y615192D01*
G01Y612946D02*
Y611255D01*
G01Y609009D02*
Y607318D01*
G01X-24844Y620113D02*
Y639758D01*
G01X-24509Y625093D02*
Y622731D01*
G01Y621156D02*
Y618794D01*
G01Y617219D02*
Y614857D01*
G01Y613282D02*
Y610920D01*
G01Y609345D02*
Y606983D01*
G01X-24122Y624785D02*
Y623039D01*
G01Y620848D02*
Y619102D01*
G01Y616911D02*
Y615165D01*
G01Y612974D02*
Y611228D01*
G01Y609037D02*
Y607291D01*
G01X-23684Y624790D02*
Y623033D01*
G01Y620853D02*
Y619096D01*
G01Y616916D02*
Y615159D01*
G01Y612979D02*
Y611222D01*
G01Y609042D02*
Y607285D01*
G01X-12993Y625329D02*
Y625014D01*
G01Y622809D02*
Y622494D01*
G01Y621392D02*
Y621077D01*
G01Y618872D02*
Y618557D01*
G01Y614935D02*
Y614620D01*
G01Y617455D02*
Y617140D01*
G01Y610998D02*
Y610683D01*
G01Y613518D02*
Y613203D01*
G01Y607061D02*
Y606746D01*
G01Y609581D02*
Y609266D01*
G01X-12280Y624917D02*
Y622906D01*
G01Y620980D02*
Y618969D01*
G01Y617043D02*
Y615032D01*
G01Y613106D02*
Y611095D01*
G01Y609169D02*
Y607158D01*
G01X-11843Y624922D02*
Y622902D01*
G01Y620985D02*
Y618965D01*
G01Y617048D02*
Y615028D01*
G01Y613111D02*
Y611091D01*
G01Y609174D02*
Y607154D01*
G01X-12993Y606746D02*
X-1D01*
G01Y609581D02*
X-12993D01*
G01Y610683D02*
X-1D01*
G01Y613518D02*
X-12993D01*
G01Y614620D02*
X-1D01*
G01Y617455D02*
X-12993D01*
G01Y618557D02*
X-1D01*
G01Y621392D02*
X-12993D01*
G01Y622494D02*
X-1D01*
G01Y625329D02*
X-12993D01*
G01X-27993Y643735D02*
Y663380D01*
G01X-27265Y644778D02*
Y642416D01*
G01Y640841D02*
Y638479D01*
G01Y636904D02*
Y634542D01*
G01Y632967D02*
Y630605D01*
G01Y629030D02*
Y626668D01*
G01X-26943Y644439D02*
Y642755D01*
G01Y640502D02*
Y638818D01*
G01Y636565D02*
Y634881D01*
G01Y632628D02*
Y630944D01*
G01Y628691D02*
Y627007D01*
G01X-26566Y644443D02*
Y642751D01*
G01Y640506D02*
Y638814D01*
G01Y636569D02*
Y634877D01*
G01Y632631D02*
Y630940D01*
G01Y628694D02*
Y627003D01*
G01X-24844Y643735D02*
Y663380D01*
G01X-24509Y644778D02*
Y642416D01*
G01Y640841D02*
Y638479D01*
G01Y636904D02*
Y634542D01*
G01Y632967D02*
Y630605D01*
G01Y629030D02*
Y626668D01*
G01X-24122Y644470D02*
Y642724D01*
G01Y640533D02*
Y638787D01*
G01Y636596D02*
Y634850D01*
G01Y628722D02*
Y626976D01*
G01Y632659D02*
Y630913D01*
G01X-23684Y644475D02*
Y642719D01*
G01Y640538D02*
Y638781D01*
G01Y636601D02*
Y634844D01*
G01Y628727D02*
Y626970D01*
G01Y632664D02*
Y630907D01*
G01X-12993Y646431D02*
Y646117D01*
G01Y645014D02*
Y644699D01*
G01Y642494D02*
Y642180D01*
G01Y638557D02*
Y638243D01*
G01Y641077D02*
Y640762D01*
G01Y634620D02*
Y634306D01*
G01Y637140D02*
Y636825D01*
G01Y630683D02*
Y630369D01*
G01Y633203D02*
Y632888D01*
G01Y629266D02*
Y628951D01*
G01Y626746D02*
Y626431D01*
G01X-12280Y644602D02*
Y642591D01*
G01Y640665D02*
Y638654D01*
G01Y636728D02*
Y634717D01*
G01Y632791D02*
Y630780D01*
G01Y628854D02*
Y626843D01*
G01X-11843Y644607D02*
Y642587D01*
G01Y640670D02*
Y638650D01*
G01Y636733D02*
Y634713D01*
G01Y632796D02*
Y630776D01*
G01Y628859D02*
Y626839D01*
G01X-12993Y626431D02*
X-1D01*
G01Y629266D02*
X-12993D01*
G01Y630369D02*
X-1D01*
G01Y633203D02*
X-12993D01*
G01Y634306D02*
X-1D01*
G01Y637140D02*
X-12993D01*
G01Y638243D02*
X-1D01*
G01Y641077D02*
X-12993D01*
G01Y642180D02*
X-1D01*
G01Y645014D02*
X-12993D01*
G01Y646117D02*
X-1D01*
G01X-10631Y563833D02*
X-9844Y563479D01*
G01X-2197Y563794D02*
X-1970Y563400D01*
G01X-10531Y565925D02*
Y563788D01*
G01X-6694Y566235D02*
Y565644D01*
G01Y564069D02*
Y563479D01*
G01X-4725Y566550D02*
Y565644D01*
G01X-3757Y565959D02*
Y563754D01*
G01X-4259Y563636D02*
X-3378Y563400D01*
G01X-2521Y565959D02*
Y563754D01*
G01X-2251Y566274D02*
Y563439D01*
G01X-985Y565526D02*
Y564187D01*
G01X8523Y565526D02*
Y564187D01*
G01X-1Y563400D02*
X-1970D01*
G01X-6694Y563479D02*
X-9844D01*
G01X-4259Y563636D02*
X-4725D01*
G01X-2197Y563794D02*
X-3151D01*
G01X-4725Y564069D02*
X-6694D01*
G01X15077Y564187D02*
X8523D01*
G01D02*
X-1D01*
G01D02*
X-985D01*
G01Y565526D02*
X-1D01*
G01D02*
X8523D01*
G01D02*
X12600D01*
G01X-4725Y565644D02*
X-6694D01*
G01X-3378Y563400D02*
X-3151Y563794D01*
G01X-10631Y567770D02*
X-9844Y567416D01*
G01X-10631Y571707D02*
X-9844Y571353D01*
G01X-10631Y575644D02*
X-9844Y575290D01*
G01X-3151Y565920D02*
X-3378Y566313D01*
G01X-2197Y567731D02*
X-1970Y567337D01*
G01X-3151Y569857D02*
X-3378Y570250D01*
G01X-2197Y571668D02*
X-1970Y571274D01*
G01X-3151Y573794D02*
X-3378Y574187D01*
G01X-2197Y575605D02*
X-1970Y575211D01*
G01X-3151Y577731D02*
X-3378Y578124D01*
G01X-2197Y579542D02*
X-1970Y579148D01*
G01X-3151Y581668D02*
X-3378Y582061D01*
G01X-2197Y583479D02*
X-1970Y583085D01*
G01X-3151Y585605D02*
X-3378Y585998D01*
G01X-10531Y585610D02*
Y583473D01*
G01Y577736D02*
Y575599D01*
G01Y581673D02*
Y579536D01*
G01Y573799D02*
Y571662D01*
G01Y569862D02*
Y567725D01*
G01X-6694Y585920D02*
Y585329D01*
G01Y583754D02*
Y583164D01*
G01Y581983D02*
Y581392D01*
G01Y578046D02*
Y577455D01*
G01Y579817D02*
Y579227D01*
G01Y574109D02*
Y573518D01*
G01Y575880D02*
Y575290D01*
G01Y571943D02*
Y571353D01*
G01Y570172D02*
Y569581D01*
G01Y568006D02*
Y567416D01*
G01X-4725Y586235D02*
Y585329D01*
G01Y583754D02*
Y582849D01*
G01Y582298D02*
Y581392D01*
G01Y578361D02*
Y577455D01*
G01Y579817D02*
Y578912D01*
G01Y574424D02*
Y573518D01*
G01Y575880D02*
Y574975D01*
G01Y571943D02*
Y571038D01*
G01Y570487D02*
Y569581D01*
G01Y568006D02*
Y567101D01*
G01X-3757Y585644D02*
Y583439D01*
G01Y581707D02*
Y579502D01*
G01Y577770D02*
Y575565D01*
G01Y573833D02*
Y571628D01*
G01Y569896D02*
Y567691D01*
G01X-4259Y567573D02*
X-3378Y567337D01*
G01X-4259Y571510D02*
X-3378Y571274D01*
G01X-4259Y575447D02*
X-3378Y575211D01*
G01X-4259Y579384D02*
X-3378Y579148D01*
G01X-4259Y583321D02*
X-3378Y583085D01*
G01X-10631Y579581D02*
X-9844Y579227D01*
G01X-10631Y583518D02*
X-9844Y583164D01*
G01X-2521Y585644D02*
Y583439D01*
G01Y577770D02*
Y575565D01*
G01Y581707D02*
Y579502D01*
G01Y573833D02*
Y571628D01*
G01Y569896D02*
Y567691D01*
G01X-2251Y585959D02*
Y583124D01*
G01Y582022D02*
Y579187D01*
G01Y578085D02*
Y575250D01*
G01Y574148D02*
Y571313D01*
G01Y570211D02*
Y567376D01*
G01X-985Y585211D02*
Y583872D01*
G01Y577337D02*
Y575998D01*
G01Y581274D02*
Y579935D01*
G01Y573400D02*
Y572061D01*
G01Y569463D02*
Y568124D01*
G01X8523Y585211D02*
Y583872D01*
G01Y577337D02*
Y575998D01*
G01Y581274D02*
Y579935D01*
G01Y573400D02*
Y572061D01*
G01Y569463D02*
Y568124D01*
G01X-4725Y567101D02*
X-6694Y567416D01*
G01X-4725Y571038D02*
X-6694Y571353D01*
G01X-4725Y574975D02*
X-6694Y575290D01*
G01X-4725Y578912D02*
X-6694Y579227D01*
G01X-4725Y582849D02*
X-6694Y583164D01*
G01X-3151Y565920D02*
X-2197D01*
G01X-4725Y566077D02*
X-4259D01*
G01X-9844Y566235D02*
X-6694D01*
G01X-1970Y566313D02*
X-1D01*
G01Y567337D02*
X-1970D01*
G01X-6694Y567416D02*
X-9844D01*
G01X-4259Y567573D02*
X-4725D01*
G01X-2197Y567731D02*
X-3151D01*
G01X-4725Y568006D02*
X-6694D01*
G01X15077Y568124D02*
X8523D01*
G01D02*
X-1D01*
G01D02*
X-985D01*
G01Y569463D02*
X-1D01*
G01D02*
X8523D01*
G01D02*
X12600D01*
G01X-4725Y569581D02*
X-6694D01*
G01X-3151Y569857D02*
X-2197D01*
G01X-4725Y570014D02*
X-4259D01*
G01X-9844Y570172D02*
X-6694D01*
G01X-1970Y570250D02*
X-1D01*
G01Y571274D02*
X-1970D01*
G01X-6694Y571353D02*
X-9844D01*
G01X-4259Y571510D02*
X-4725D01*
G01X-2197Y571668D02*
X-3151D01*
G01X-4725Y571943D02*
X-6694D01*
G01X15077Y572061D02*
X8523D01*
G01D02*
X-1D01*
G01D02*
X-985D01*
G01Y573400D02*
X-1D01*
G01D02*
X8523D01*
G01D02*
X12600D01*
G01X-4725Y573518D02*
X-6694D01*
G01X-3151Y573794D02*
X-2197D01*
G01X-4725Y573951D02*
X-4259D01*
G01X-9844Y574109D02*
X-6694D01*
G01X-1970Y574187D02*
X-1D01*
G01Y575211D02*
X-1970D01*
G01X-6694Y575290D02*
X-9844D01*
G01X-4259Y575447D02*
X-4725D01*
G01X-2197Y575605D02*
X-3151D01*
G01X-4725Y575880D02*
X-6694D01*
G01X15077Y575998D02*
X8523D01*
G01D02*
X-1D01*
G01D02*
X-985D01*
G01Y577337D02*
X-1D01*
G01D02*
X8523D01*
G01D02*
X12600D01*
G01X-4725Y577455D02*
X-6694D01*
G01X-3151Y577731D02*
X-2197D01*
G01X-4725Y577888D02*
X-4259D01*
G01X-9844Y578046D02*
X-6694D01*
G01X-1970Y578124D02*
X-1D01*
G01Y579148D02*
X-1970D01*
G01X-6694Y579227D02*
X-9844D01*
G01X-4259Y579384D02*
X-4725D01*
G01X-2197Y579542D02*
X-3151D01*
G01X-4725Y579817D02*
X-6694D01*
G01X15077Y579935D02*
X8523D01*
G01D02*
X-1D01*
G01D02*
X-985D01*
G01Y581274D02*
X-1D01*
G01D02*
X8523D01*
G01D02*
X12600D01*
G01X-4725Y581392D02*
X-6694D01*
G01X-3151Y581668D02*
X-2197D01*
G01X-4725Y581825D02*
X-4259D01*
G01X-9844Y581983D02*
X-6694D01*
G01X-1970Y582061D02*
X-1D01*
G01Y583085D02*
X-1970D01*
G01X-6694Y583164D02*
X-9844D01*
G01X-4259Y583321D02*
X-4725D01*
G01X-2197Y583479D02*
X-3151D01*
G01X-4725Y583754D02*
X-6694D01*
G01X15077Y583872D02*
X8523D01*
G01D02*
X-1D01*
G01D02*
X-985D01*
G01Y585211D02*
X-1D01*
G01D02*
X8523D01*
G01D02*
X12600D01*
G01X-4725Y585329D02*
X-6694D01*
G01X-3151Y585605D02*
X-2197D01*
G01X-4725Y585762D02*
X-4259D01*
G01X-6694Y566235D02*
X-4725Y566550D01*
G01X-6694Y570172D02*
X-4725Y570487D01*
G01X-6694Y574109D02*
X-4725Y574424D01*
G01X-6694Y578046D02*
X-4725Y578361D01*
G01X-6694Y581983D02*
X-4725Y582298D01*
G01X-1970Y585998D02*
X-2197Y585605D01*
G01X-3378Y583085D02*
X-3151Y583479D01*
G01X-1970Y582061D02*
X-2197Y581668D01*
G01X-3378Y579148D02*
X-3151Y579542D01*
G01X-1970Y578124D02*
X-2197Y577731D01*
G01X-3378Y575211D02*
X-3151Y575605D01*
G01X-1970Y574187D02*
X-2197Y573794D01*
G01X-3378Y571274D02*
X-3151Y571668D01*
G01X-1970Y570250D02*
X-2197Y569857D01*
G01X-3378Y567337D02*
X-3151Y567731D01*
G01X-1970Y566313D02*
X-2197Y565920D01*
G01X-3378Y566313D02*
X-4259Y566077D01*
G01X-3378Y570250D02*
X-4259Y570014D01*
G01X-3378Y574187D02*
X-4259Y573951D01*
G01X-3378Y578124D02*
X-4259Y577888D01*
G01X-3378Y582061D02*
X-4259Y581825D01*
G01X-3378Y585998D02*
X-4259Y585762D01*
G01X-9844Y585920D02*
X-10631Y585565D01*
G01X-9844Y581983D02*
X-10631Y581628D01*
G01X-9844Y578046D02*
X-10631Y577691D01*
G01X-9844Y574109D02*
X-10631Y573754D01*
G01X-9844Y570172D02*
X-10631Y569817D01*
G01X-9844Y566235D02*
X-10631Y565880D01*
G01X-2197Y587416D02*
X-1970Y587022D01*
G01X-3151Y589542D02*
X-3378Y589935D01*
G01X-2197Y591353D02*
X-1970Y590959D01*
G01X-3151Y593479D02*
X-3378Y593872D01*
G01X-2197Y595290D02*
X-1970Y594896D01*
G01X-3151Y597416D02*
X-3378Y597809D01*
G01X-2197Y599227D02*
X-1970Y598833D01*
G01X-3151Y601353D02*
X-3378Y601746D01*
G01X-2197Y603164D02*
X-1970Y602770D01*
G01X-3151Y605290D02*
X-3378Y605683D01*
G01X-10531Y605295D02*
Y603158D01*
G01Y601358D02*
Y599221D01*
G01Y597421D02*
Y595284D01*
G01Y593484D02*
Y591347D01*
G01Y589547D02*
Y587410D01*
G01X-6694Y605605D02*
Y605014D01*
G01Y603439D02*
Y602849D01*
G01Y601668D02*
Y601077D01*
G01Y599502D02*
Y598912D01*
G01Y597731D02*
Y597140D01*
G01Y595565D02*
Y594975D01*
G01Y593794D02*
Y593203D01*
G01Y591628D02*
Y591038D01*
G01Y589857D02*
Y589266D01*
G01Y587691D02*
Y587101D01*
G01X-4725Y605920D02*
Y605014D01*
G01Y603439D02*
Y602534D01*
G01Y601983D02*
Y601077D01*
G01Y599502D02*
Y598597D01*
G01Y598046D02*
Y597140D01*
G01Y595565D02*
Y594660D01*
G01Y594109D02*
Y593203D01*
G01Y591628D02*
Y590723D01*
G01Y590172D02*
Y589266D01*
G01Y587691D02*
Y586786D01*
G01X-3757Y605329D02*
Y603124D01*
G01Y601392D02*
Y599187D01*
G01Y597455D02*
Y595250D01*
G01Y593518D02*
Y591313D01*
G01Y589581D02*
Y587376D01*
G01X-4259Y587258D02*
X-3378Y587022D01*
G01X-4259Y591195D02*
X-3378Y590959D01*
G01X-4259Y595132D02*
X-3378Y594896D01*
G01X-10631Y587455D02*
X-9844Y587101D01*
G01X-10631Y591392D02*
X-9844Y591038D01*
G01X-10631Y595329D02*
X-9844Y594975D01*
G01X-10631Y599266D02*
X-9844Y598912D01*
G01X-10631Y603203D02*
X-9844Y602849D01*
G01X-2521Y605329D02*
Y603124D01*
G01Y601392D02*
Y599187D01*
G01Y597455D02*
Y595250D01*
G01Y593518D02*
Y591313D01*
G01Y589581D02*
Y587376D01*
G01X-2251Y605644D02*
Y602809D01*
G01Y601707D02*
Y598872D01*
G01Y597770D02*
Y594935D01*
G01Y593833D02*
Y590998D01*
G01Y589896D02*
Y587061D01*
G01X-985Y600959D02*
Y599620D01*
G01Y604896D02*
Y603557D01*
G01Y597022D02*
Y595683D01*
G01Y593085D02*
Y591746D01*
G01Y589148D02*
Y587809D01*
G01X8523Y604896D02*
Y603557D01*
G01Y600959D02*
Y599620D01*
G01Y597022D02*
Y595683D01*
G01Y593085D02*
Y591746D01*
G01Y589148D02*
Y587809D01*
G01X-4725Y586786D02*
X-6694Y587101D01*
G01X-4725Y590723D02*
X-6694Y591038D01*
G01X-4725Y594660D02*
X-6694Y594975D01*
G01X-4725Y598597D02*
X-6694Y598912D01*
G01X-4725Y602534D02*
X-6694Y602849D01*
G01X-4259Y599069D02*
X-3378Y598833D01*
G01X-4259Y603006D02*
X-3378Y602770D01*
G01X-9844Y585920D02*
X-6694D01*
G01X-1970Y585998D02*
X-1D01*
G01Y587022D02*
X-1970D01*
G01X-6694Y587101D02*
X-9844D01*
G01X-4259Y587258D02*
X-4725D01*
G01X-2197Y587416D02*
X-3151D01*
G01X-4725Y587691D02*
X-6694D01*
G01X15077Y587809D02*
X8523D01*
G01D02*
X-1D01*
G01D02*
X-985D01*
G01Y589148D02*
X-1D01*
G01D02*
X8523D01*
G01D02*
X12600D01*
G01X-4725Y589266D02*
X-6694D01*
G01X-3151Y589542D02*
X-2197D01*
G01X-4725Y589699D02*
X-4259D01*
G01X-9844Y589857D02*
X-6694D01*
G01X-1970Y589935D02*
X-1D01*
G01Y590959D02*
X-1970D01*
G01X-6694Y591038D02*
X-9844D01*
G01X-4259Y591195D02*
X-4725D01*
G01X-2197Y591353D02*
X-3151D01*
G01X-4725Y591628D02*
X-6694D01*
G01X15077Y591746D02*
X8523D01*
G01D02*
X-1D01*
G01D02*
X-985D01*
G01Y593085D02*
X-1D01*
G01D02*
X8523D01*
G01D02*
X12600D01*
G01X-4725Y593203D02*
X-6694D01*
G01X-3151Y593479D02*
X-2197D01*
G01X-4725Y593636D02*
X-4259D01*
G01X-9844Y593794D02*
X-6694D01*
G01X-1970Y593872D02*
X-1D01*
G01Y594896D02*
X-1970D01*
G01X-6694Y594975D02*
X-9844D01*
G01X-4259Y595132D02*
X-4725D01*
G01X-2197Y595290D02*
X-3151D01*
G01X-4725Y595565D02*
X-6694D01*
G01X15077Y595683D02*
X8523D01*
G01D02*
X-1D01*
G01D02*
X-985D01*
G01Y597022D02*
X-1D01*
G01D02*
X8523D01*
G01D02*
X12600D01*
G01X-4725Y597140D02*
X-6694D01*
G01X-3151Y597416D02*
X-2197D01*
G01X-4725Y597573D02*
X-4259D01*
G01X-9844Y597731D02*
X-6694D01*
G01X-1970Y597809D02*
X-1D01*
G01Y598833D02*
X-1970D01*
G01X-6694Y598912D02*
X-9844D01*
G01X-4259Y599069D02*
X-4725D01*
G01X-2197Y599227D02*
X-3151D01*
G01X-4725Y599502D02*
X-6694D01*
G01X15077Y599620D02*
X8523D01*
G01D02*
X-1D01*
G01D02*
X-985D01*
G01Y600959D02*
X-1D01*
G01D02*
X8523D01*
G01D02*
X12600D01*
G01X-4725Y601077D02*
X-6694D01*
G01X-3151Y601353D02*
X-2197D01*
G01X-4725Y601510D02*
X-4259D01*
G01X-9844Y601668D02*
X-6694D01*
G01X-1970Y601746D02*
X-1D01*
G01Y602770D02*
X-1970D01*
G01X-6694Y602849D02*
X-9844D01*
G01X-4259Y603006D02*
X-4725D01*
G01X-2197Y603164D02*
X-3151D01*
G01X-4725Y603439D02*
X-6694D01*
G01X15077Y603557D02*
X8523D01*
G01D02*
X-1D01*
G01D02*
X-985D01*
G01Y604896D02*
X-1D01*
G01D02*
X8523D01*
G01D02*
X12600D01*
G01X-4725Y605014D02*
X-6694D01*
G01X-3151Y605290D02*
X-2197D01*
G01X-4725Y605447D02*
X-4259D01*
G01X-9844Y605605D02*
X-6694D01*
G01X-1970Y605683D02*
X-1D01*
G01X-6694Y585920D02*
X-4725Y586235D01*
G01X-6694Y589857D02*
X-4725Y590172D01*
G01X-6694Y593794D02*
X-4725Y594109D01*
G01X-6694Y597731D02*
X-4725Y598046D01*
G01X-6694Y601668D02*
X-4725Y601983D01*
G01X-6694Y605605D02*
X-4725Y605920D01*
G01X-1970Y605683D02*
X-2197Y605290D01*
G01X-3378Y602770D02*
X-3151Y603164D01*
G01X-1970Y601746D02*
X-2197Y601353D01*
G01X-3378Y598833D02*
X-3151Y599227D01*
G01X-1970Y597809D02*
X-2197Y597416D01*
G01X-3378Y594896D02*
X-3151Y595290D01*
G01X-1970Y593872D02*
X-2197Y593479D01*
G01X-3378Y590959D02*
X-3151Y591353D01*
G01X-1970Y589935D02*
X-2197Y589542D01*
G01X-3378Y587022D02*
X-3151Y587416D01*
G01X-3378Y589935D02*
X-4259Y589699D01*
G01X-3378Y593872D02*
X-4259Y593636D01*
G01X-3378Y597809D02*
X-4259Y597573D01*
G01X-3378Y601746D02*
X-4259Y601510D01*
G01X-3378Y605683D02*
X-4259Y605447D01*
G01X-9844Y605605D02*
X-10631Y605250D01*
G01X-9844Y601668D02*
X-10631Y601313D01*
G01X-9844Y597731D02*
X-10631Y597376D01*
G01X-9844Y593794D02*
X-10631Y593439D01*
G01X-9844Y589857D02*
X-10631Y589502D01*
G01X-2197Y607101D02*
X-1970Y606707D01*
G01X-3151Y609227D02*
X-3378Y609620D01*
G01X-2197Y611038D02*
X-1970Y610644D01*
G01X-3151Y613164D02*
X-3378Y613557D01*
G01X-2197Y614975D02*
X-1970Y614581D01*
G01X-3151Y617101D02*
X-3378Y617494D01*
G01X-2197Y618912D02*
X-1970Y618518D01*
G01X-3151Y621038D02*
X-3378Y621431D01*
G01X-2197Y622849D02*
X-1970Y622455D01*
G01X-3151Y624975D02*
X-3378Y625369D01*
G01X-10531Y624980D02*
Y622843D01*
G01Y621043D02*
Y618906D01*
G01Y617106D02*
Y614969D01*
G01Y613169D02*
Y611032D01*
G01Y609232D02*
Y607095D01*
G01X-6694Y625290D02*
Y624699D01*
G01Y623124D02*
Y622534D01*
G01Y621353D02*
Y620762D01*
G01Y619187D02*
Y618597D01*
G01Y617416D02*
Y616825D01*
G01Y615250D02*
Y614660D01*
G01Y613479D02*
Y612888D01*
G01Y611313D02*
Y610723D01*
G01Y609542D02*
Y608951D01*
G01Y607376D02*
Y606786D01*
G01X-4725Y625605D02*
Y624699D01*
G01Y623124D02*
Y622219D01*
G01Y621668D02*
Y620762D01*
G01Y619187D02*
Y618282D01*
G01Y617731D02*
Y616825D01*
G01Y615250D02*
Y614345D01*
G01Y613794D02*
Y612888D01*
G01Y611313D02*
Y610408D01*
G01Y609857D02*
Y608951D01*
G01Y607376D02*
Y606471D01*
G01X-3757Y625014D02*
Y622809D01*
G01Y621077D02*
Y618872D01*
G01Y617140D02*
Y614935D01*
G01Y613203D02*
Y610998D01*
G01Y609266D02*
Y607061D01*
G01X-10631Y607140D02*
X-9844Y606786D01*
G01X-10631Y611077D02*
X-9844Y610723D01*
G01X-10631Y615014D02*
X-9844Y614660D01*
G01X-10631Y618951D02*
X-9844Y618597D01*
G01X-10631Y622888D02*
X-9844Y622534D01*
G01X-2521Y625014D02*
Y622809D01*
G01Y621077D02*
Y618872D01*
G01Y617140D02*
Y614935D01*
G01Y613203D02*
Y610998D01*
G01Y609266D02*
Y607061D01*
G01X-2251Y625329D02*
Y622494D01*
G01Y621392D02*
Y618557D01*
G01Y617455D02*
Y614620D01*
G01Y613518D02*
Y610683D01*
G01Y609581D02*
Y606746D01*
G01X-985Y624581D02*
Y623243D01*
G01Y620644D02*
Y619306D01*
G01Y616707D02*
Y615369D01*
G01Y612770D02*
Y611431D01*
G01Y608833D02*
Y607494D01*
G01X8523Y624581D02*
Y623243D01*
G01Y620644D02*
Y619306D01*
G01Y616707D02*
Y615369D01*
G01Y612770D02*
Y611431D01*
G01Y608833D02*
Y607494D01*
G01X-4725Y606471D02*
X-6694Y606786D01*
G01X-4725Y610408D02*
X-6694Y610723D01*
G01X-4725Y614345D02*
X-6694Y614660D01*
G01X-4725Y618282D02*
X-6694Y618597D01*
G01X-4725Y622219D02*
X-6694Y622534D01*
G01X-4259Y606943D02*
X-3378Y606707D01*
G01X-4259Y610880D02*
X-3378Y610644D01*
G01X-4259Y614817D02*
X-3378Y614581D01*
G01X-4259Y618754D02*
X-3378Y618518D01*
G01X-4259Y622691D02*
X-3378Y622455D01*
G01X-1Y606707D02*
X-1970D01*
G01X-6694Y606786D02*
X-9844D01*
G01X-4259Y606943D02*
X-4725D01*
G01X-2197Y607101D02*
X-3151D01*
G01X-4725Y607376D02*
X-6694D01*
G01X15077Y607494D02*
X8523D01*
G01D02*
X-1D01*
G01D02*
X-985D01*
G01Y608833D02*
X-1D01*
G01D02*
X8523D01*
G01D02*
X12600D01*
G01X-4725Y608951D02*
X-6694D01*
G01X-3151Y609227D02*
X-2197D01*
G01X-4725Y609384D02*
X-4259D01*
G01X-9844Y609542D02*
X-6694D01*
G01X-1970Y609620D02*
X-1D01*
G01Y610644D02*
X-1970D01*
G01X-6694Y610723D02*
X-9844D01*
G01X-4259Y610880D02*
X-4725D01*
G01X-2197Y611038D02*
X-3151D01*
G01X-4725Y611313D02*
X-6694D01*
G01X15077Y611431D02*
X8523D01*
G01D02*
X-1D01*
G01D02*
X-985D01*
G01Y612770D02*
X-1D01*
G01D02*
X8523D01*
G01D02*
X12600D01*
G01X-4725Y612888D02*
X-6694D01*
G01X-3151Y613164D02*
X-2197D01*
G01X-4725Y613321D02*
X-4259D01*
G01X-9844Y613479D02*
X-6694D01*
G01X-1970Y613557D02*
X-1D01*
G01Y614581D02*
X-1970D01*
G01X-6694Y614660D02*
X-9844D01*
G01X-4259Y614817D02*
X-4725D01*
G01X-2197Y614975D02*
X-3151D01*
G01X-4725Y615250D02*
X-6694D01*
G01X15077Y615369D02*
X8523D01*
G01D02*
X-1D01*
G01D02*
X-985D01*
G01Y616707D02*
X-1D01*
G01D02*
X8523D01*
G01D02*
X12600D01*
G01X-4725Y616825D02*
X-6694D01*
G01X-3151Y617101D02*
X-2197D01*
G01X-4725Y617258D02*
X-4259D01*
G01X-9844Y617416D02*
X-6694D01*
G01X-1970Y617494D02*
X-1D01*
G01Y618518D02*
X-1970D01*
G01X-6694Y618597D02*
X-9844D01*
G01X-4259Y618754D02*
X-4725D01*
G01X-2197Y618912D02*
X-3151D01*
G01X-4725Y619187D02*
X-6694D01*
G01X15077Y619306D02*
X8523D01*
G01D02*
X-1D01*
G01D02*
X-985D01*
G01Y620644D02*
X-1D01*
G01D02*
X8523D01*
G01D02*
X12600D01*
G01X-4725Y620762D02*
X-6694D01*
G01X-3151Y621038D02*
X-2197D01*
G01X-4725Y621195D02*
X-4259D01*
G01X-9844Y621353D02*
X-6694D01*
G01X-1970Y621431D02*
X-1D01*
G01Y622455D02*
X-1970D01*
G01X-6694Y622534D02*
X-9844D01*
G01X-4259Y622691D02*
X-4725D01*
G01X-2197Y622849D02*
X-3151D01*
G01X-4725Y623124D02*
X-6694D01*
G01X15077Y623243D02*
X8523D01*
G01D02*
X-1D01*
G01D02*
X-985D01*
G01Y624581D02*
X-1D01*
G01D02*
X8523D01*
G01D02*
X12600D01*
G01X-4725Y624699D02*
X-6694D01*
G01X-3151Y624975D02*
X-2197D01*
G01X-4725Y625132D02*
X-4259D01*
G01X-9844Y625290D02*
X-6694D01*
G01X-1970Y625369D02*
X-1D01*
G01X-6694Y609542D02*
X-4725Y609857D01*
G01X-6694Y613479D02*
X-4725Y613794D01*
G01X-1970Y625369D02*
X-2197Y624975D01*
G01X-3378Y622455D02*
X-3151Y622849D01*
G01X-1970Y621431D02*
X-2197Y621038D01*
G01X-3378Y618518D02*
X-3151Y618912D01*
G01X-1970Y617494D02*
X-2197Y617101D01*
G01X-3378Y614581D02*
X-3151Y614975D01*
G01X-1970Y613557D02*
X-2197Y613164D01*
G01X-3378Y610644D02*
X-3151Y611038D01*
G01X-1970Y609620D02*
X-2197Y609227D01*
G01X-3378Y606707D02*
X-3151Y607101D01*
G01X-3378Y609620D02*
X-4259Y609384D01*
G01X-3378Y613557D02*
X-4259Y613321D01*
G01X-3378Y617494D02*
X-4259Y617258D01*
G01X-3378Y621431D02*
X-4259Y621195D01*
G01X-3378Y625369D02*
X-4259Y625132D01*
G01X-6694Y617416D02*
X-4725Y617731D01*
G01X-6694Y621353D02*
X-4725Y621668D01*
G01X-6694Y625290D02*
X-4725Y625605D01*
G01X-9844Y625290D02*
X-10631Y624935D01*
G01X-9844Y621353D02*
X-10631Y620998D01*
G01X-9844Y617416D02*
X-10631Y617061D01*
G01X-9844Y613479D02*
X-10631Y613124D01*
G01X-9844Y609542D02*
X-10631Y609187D01*
G01X-2197Y626786D02*
X-1970Y626392D01*
G01X-3151Y628912D02*
X-3378Y629306D01*
G01X-2197Y630723D02*
X-1970Y630329D01*
G01X-3151Y632849D02*
X-3378Y633243D01*
G01X-2197Y634660D02*
X-1970Y634266D01*
G01X-3151Y636786D02*
X-3378Y637180D01*
G01X-2197Y638597D02*
X-1970Y638203D01*
G01X-3151Y640723D02*
X-3378Y641117D01*
G01X-2197Y642534D02*
X-1970Y642140D01*
G01X-3151Y644660D02*
X-3378Y645054D01*
G01X-2197Y646471D02*
X-1970Y646077D01*
G01X-10531Y644665D02*
Y642528D01*
G01Y640728D02*
Y638591D01*
G01Y636791D02*
Y634654D01*
G01Y628917D02*
Y626780D01*
G01Y632854D02*
Y630717D01*
G01X-6694Y644975D02*
Y644384D01*
G01Y642809D02*
Y642219D01*
G01Y641038D02*
Y640447D01*
G01Y638872D02*
Y638282D01*
G01Y637101D02*
Y636510D01*
G01Y634935D02*
Y634345D01*
G01Y633164D02*
Y632573D01*
G01Y630998D02*
Y630408D01*
G01Y629227D02*
Y628636D01*
G01Y627061D02*
Y626471D01*
G01X-4725Y646746D02*
Y645841D01*
G01Y645290D02*
Y644384D01*
G01Y642809D02*
Y641904D01*
G01Y641353D02*
Y640447D01*
G01Y638872D02*
Y637967D01*
G01Y637416D02*
Y636510D01*
G01Y634935D02*
Y634030D01*
G01Y633479D02*
Y632573D01*
G01Y630998D02*
Y630093D01*
G01Y629542D02*
Y628636D01*
G01Y627061D02*
Y626156D01*
G01X-3757Y644699D02*
Y642494D01*
G01Y640762D02*
Y638557D01*
G01Y636825D02*
Y634620D01*
G01Y628951D02*
Y626746D01*
G01Y632888D02*
Y630683D01*
G01X-10631Y626825D02*
X-9844Y626471D01*
G01X-10631Y630762D02*
X-9844Y630408D01*
G01X-10631Y634699D02*
X-9844Y634345D01*
G01X-10631Y638636D02*
X-9844Y638282D01*
G01X-10631Y642573D02*
X-9844Y642219D01*
G01X-2521Y644699D02*
Y642494D01*
G01Y640762D02*
Y638557D01*
G01Y636825D02*
Y634620D01*
G01Y628951D02*
Y626746D01*
G01Y632888D02*
Y630683D01*
G01X-2251Y648951D02*
Y646117D01*
G01Y645014D02*
Y642180D01*
G01Y641077D02*
Y638243D01*
G01Y637140D02*
Y634306D01*
G01Y633203D02*
Y630369D01*
G01Y629266D02*
Y626431D01*
G01X-985Y644266D02*
Y642928D01*
G01Y640329D02*
Y638991D01*
G01Y636392D02*
Y635054D01*
G01Y632455D02*
Y631117D01*
G01Y628518D02*
Y627180D01*
G01X8523Y644266D02*
Y642928D01*
G01Y640329D02*
Y638991D01*
G01Y636392D02*
Y635054D01*
G01Y632455D02*
Y631117D01*
G01Y628518D02*
Y627180D01*
G01X-4725Y626156D02*
X-6694Y626471D01*
G01X-4259Y626628D02*
X-3378Y626392D01*
G01X-4259Y630565D02*
X-3378Y630329D01*
G01X-4259Y634502D02*
X-3378Y634266D01*
G01X-4259Y638439D02*
X-3378Y638203D01*
G01X-4259Y642376D02*
X-3378Y642140D01*
G01X-4259Y646313D02*
X-3378Y646077D01*
G01X-4725Y630093D02*
X-6694Y630408D01*
G01X-4725Y634030D02*
X-6694Y634345D01*
G01X-4725Y637967D02*
X-6694Y638282D01*
G01X-4725Y641904D02*
X-6694Y642219D01*
G01X-4725Y645841D02*
X-6694Y646156D01*
G01X-1Y626392D02*
X-1970D01*
G01X-6694Y626471D02*
X-9844D01*
G01X-4259Y626628D02*
X-4725D01*
G01X-2197Y626786D02*
X-3151D01*
G01X-4725Y627061D02*
X-6694D01*
G01X15077Y627180D02*
X8523D01*
G01D02*
X-1D01*
G01D02*
X-985D01*
G01Y628518D02*
X-1D01*
G01D02*
X8523D01*
G01D02*
X12600D01*
G01X-4725Y628636D02*
X-6694D01*
G01X-3151Y628912D02*
X-2197D01*
G01X-4725Y629069D02*
X-4259D01*
G01X-9844Y629227D02*
X-6694D01*
G01X-1970Y629306D02*
X-1D01*
G01Y630329D02*
X-1970D01*
G01X-6694Y630408D02*
X-9844D01*
G01X-4259Y630565D02*
X-4725D01*
G01X-2197Y630723D02*
X-3151D01*
G01X-4725Y630998D02*
X-6694D01*
G01X15077Y631117D02*
X8523D01*
G01D02*
X-1D01*
G01D02*
X-985D01*
G01Y632455D02*
X-1D01*
G01D02*
X8523D01*
G01D02*
X12600D01*
G01X-4725Y632573D02*
X-6694D01*
G01X-3151Y632849D02*
X-2197D01*
G01X-4725Y633006D02*
X-4259D01*
G01X-9844Y633164D02*
X-6694D01*
G01X-1970Y633243D02*
X-1D01*
G01Y634266D02*
X-1970D01*
G01X-6694Y634345D02*
X-9844D01*
G01X-4259Y634502D02*
X-4725D01*
G01X-2197Y634660D02*
X-3151D01*
G01X-4725Y634935D02*
X-6694D01*
G01X15077Y635054D02*
X8523D01*
G01D02*
X-1D01*
G01D02*
X-985D01*
G01Y636392D02*
X-1D01*
G01D02*
X8523D01*
G01D02*
X12600D01*
G01X-4725Y636510D02*
X-6694D01*
G01X-3151Y636786D02*
X-2197D01*
G01X-4725Y636943D02*
X-4259D01*
G01X-9844Y637101D02*
X-6694D01*
G01X-1970Y637180D02*
X-1D01*
G01Y638203D02*
X-1970D01*
G01X-6694Y638282D02*
X-9844D01*
G01X-4259Y638439D02*
X-4725D01*
G01X-2197Y638597D02*
X-3151D01*
G01X-4725Y638872D02*
X-6694D01*
G01X15077Y638991D02*
X8523D01*
G01D02*
X-1D01*
G01D02*
X-985D01*
G01Y640329D02*
X-1D01*
G01D02*
X8523D01*
G01D02*
X12600D01*
G01X-4725Y640447D02*
X-6694D01*
G01X-3151Y640723D02*
X-2197D01*
G01X-4725Y640880D02*
X-4259D01*
G01X-9844Y641038D02*
X-6694D01*
G01X-1970Y641117D02*
X-1D01*
G01Y642140D02*
X-1970D01*
G01X-6694Y642219D02*
X-9844D01*
G01X-4259Y642376D02*
X-4725D01*
G01X-2197Y642534D02*
X-3151D01*
G01X-4725Y642809D02*
X-6694D01*
G01X15077Y642928D02*
X8523D01*
G01D02*
X-1D01*
G01D02*
X-985D01*
G01Y644266D02*
X-1D01*
G01D02*
X8523D01*
G01D02*
X12600D01*
G01X-4725Y644384D02*
X-6694D01*
G01X-3151Y644660D02*
X-2197D01*
G01X-4725Y644817D02*
X-4259D01*
G01X-9844Y644975D02*
X-6694D01*
G01X-1970Y645054D02*
X-1D01*
G01Y646077D02*
X-1970D01*
G01X-3378D02*
X-3151Y646471D01*
G01X-1970Y645054D02*
X-2197Y644660D01*
G01X-3378Y642140D02*
X-3151Y642534D01*
G01X-1970Y641117D02*
X-2197Y640723D01*
G01X-3378Y638203D02*
X-3151Y638597D01*
G01X-1970Y637180D02*
X-2197Y636786D01*
G01X-3378Y634266D02*
X-3151Y634660D01*
G01X-1970Y633243D02*
X-2197Y632849D01*
G01X-3378Y630329D02*
X-3151Y630723D01*
G01X-1970Y629306D02*
X-2197Y628912D01*
G01X-3378Y626392D02*
X-3151Y626786D01*
G01X-3378Y629306D02*
X-4259Y629069D01*
G01X-6694Y629227D02*
X-4725Y629542D01*
G01X-6694Y633164D02*
X-4725Y633479D01*
G01X-6694Y637101D02*
X-4725Y637416D01*
G01X-6694Y641038D02*
X-4725Y641353D01*
G01X-6694Y644975D02*
X-4725Y645290D01*
G01X-3378Y633243D02*
X-4259Y633006D01*
G01X-3378Y637180D02*
X-4259Y636943D01*
G01X-3378Y641117D02*
X-4259Y640880D01*
G01X-3378Y645054D02*
X-4259Y644817D01*
G01X-9844Y644975D02*
X-10631Y644620D01*
G01X-9844Y641038D02*
X-10631Y640683D01*
G01X-9844Y637101D02*
X-10631Y636746D01*
G01X-9844Y633164D02*
X-10631Y632809D01*
G01X-9844Y629227D02*
X-10631Y628872D01*
G01X-38426Y668400D02*
Y666038D01*
G01Y664463D02*
Y662101D01*
G01Y660526D02*
Y658164D01*
G01Y652652D02*
Y650290D01*
G01Y656589D02*
Y654227D01*
G01Y648715D02*
Y646353D01*
G01X-38108Y663764D02*
Y662799D01*
G01Y659827D02*
Y658862D01*
G01Y655890D02*
Y654925D01*
G01Y651953D02*
Y650988D01*
G01Y648016D02*
Y647051D01*
G01X-37871Y663787D02*
Y662776D01*
G01Y659850D02*
Y658839D01*
G01Y655913D02*
Y654902D01*
G01Y648039D02*
Y647028D01*
G01Y651976D02*
Y650965D01*
G01X-35595Y664006D02*
Y662557D01*
G01Y660069D02*
Y658620D01*
G01Y656132D02*
Y654683D01*
G01Y652195D02*
Y650746D01*
G01Y648258D02*
Y646809D01*
G01X-35546Y668400D02*
Y666038D01*
G01Y664463D02*
Y662101D01*
G01Y660526D02*
Y658164D01*
G01Y656589D02*
Y654227D01*
G01Y652652D02*
Y650290D01*
G01Y648715D02*
Y646353D01*
G01X-35357Y664029D02*
Y662534D01*
G01Y660092D02*
Y658597D01*
G01Y656155D02*
Y654660D01*
G01Y652218D02*
Y650723D01*
G01Y648281D02*
Y646786D01*
G01X-34607Y668321D02*
Y666117D01*
G01Y664384D02*
Y662180D01*
G01Y660447D02*
Y658243D01*
G01Y652573D02*
Y650369D01*
G01Y656510D02*
Y654306D01*
G01Y648636D02*
Y646431D01*
G01X-34136Y664043D02*
Y662520D01*
G01Y660106D02*
Y658583D01*
G01Y652232D02*
Y650709D01*
G01Y656169D02*
Y654646D01*
G01Y648295D02*
Y646772D01*
G01X-33153Y664054D02*
Y662509D01*
G01Y660117D02*
Y658572D01*
G01Y656180D02*
Y654635D01*
G01Y652243D02*
Y650698D01*
G01Y648306D02*
Y646761D01*
G01X-32319Y664063D02*
Y662500D01*
G01Y660126D02*
Y658563D01*
G01Y652252D02*
Y650689D01*
G01Y656189D02*
Y654626D01*
G01Y648315D02*
Y646752D01*
G01X-31941Y664068D02*
Y662496D01*
G01Y660131D02*
Y658559D01*
G01Y652257D02*
Y650685D01*
G01Y656194D02*
Y654622D01*
G01Y648320D02*
Y646748D01*
G01X-38108Y647051D02*
X-35351Y646786D01*
G01X-38108Y650988D02*
X-35351Y650723D01*
G01X-38108Y654925D02*
X-35351Y654660D01*
G01X-38108Y658862D02*
X-35351Y658597D01*
G01X-38108Y662799D02*
X-35351Y662534D01*
G01Y648282D02*
X-10631Y648557D01*
G01X-35351Y652219D02*
X-10631Y652494D01*
G01X-35351Y656156D02*
X-10631Y656431D01*
G01X-35351Y660093D02*
X-10631Y660369D01*
G01X-35351Y664030D02*
X-10631Y664306D01*
G01X-39607Y646353D02*
X-24509D01*
G01X-35546Y646431D02*
X-1D01*
G01X-39607Y646884D02*
X-27993D01*
G01X-35546Y648636D02*
X-1D01*
G01X-24509Y648715D02*
X-39607D01*
G01Y650290D02*
X-24509D01*
G01X-35546Y650369D02*
X-1D01*
G01X-35546Y652573D02*
X-1D01*
G01X-24509Y652652D02*
X-39607D01*
G01Y654227D02*
X-24509D01*
G01X-35546Y654306D02*
X-1D01*
G01X-35546Y656510D02*
X-1D01*
G01X-24509Y656589D02*
X-39607D01*
G01Y658164D02*
X-24509D01*
G01X-35546Y658243D02*
X-1D01*
G01X-27993Y660231D02*
X-39607D01*
G01X-35546Y660447D02*
X-1D01*
G01X-24509Y660526D02*
X-39607D01*
G01Y662101D02*
X-24509D01*
G01X-35546Y662180D02*
X-1D01*
G01X-39607Y663380D02*
X-24844D01*
G01X-35546Y664384D02*
X-1D01*
G01X-24509Y664463D02*
X-39607D01*
G01Y666038D02*
X-24509D01*
G01X-35546Y666117D02*
X-1D01*
G01X-10631Y646510D02*
X-35351Y646786D01*
G01X-10631Y650447D02*
X-35351Y650723D01*
G01X-10631Y654384D02*
X-35351Y654660D01*
G01X-10631Y658321D02*
X-35351Y658597D01*
G01X-10631Y662258D02*
X-35351Y662534D01*
G01Y648282D02*
X-38108Y648016D01*
G01X-35351Y652219D02*
X-38108Y651953D01*
G01X-35351Y656156D02*
X-38108Y655890D01*
G01X-35351Y660093D02*
X-38108Y659827D01*
G01X-35351Y664030D02*
X-38108Y663764D01*
G01X-38426Y688085D02*
Y685723D01*
G01Y680211D02*
Y677849D01*
G01Y684148D02*
Y681786D01*
G01Y676274D02*
Y673912D01*
G01Y672337D02*
Y669975D01*
G01X-38108Y683449D02*
Y682484D01*
G01Y679512D02*
Y678547D01*
G01Y675575D02*
Y674610D01*
G01Y671638D02*
Y670673D01*
G01Y667701D02*
Y666736D01*
G01X-37871Y683472D02*
Y682461D01*
G01Y675598D02*
Y674587D01*
G01Y679535D02*
Y678524D01*
G01Y671661D02*
Y670650D01*
G01Y667724D02*
Y666713D01*
G01X-35595Y687628D02*
Y686179D01*
G01Y683691D02*
Y682242D01*
G01Y679754D02*
Y678305D01*
G01Y675817D02*
Y674368D01*
G01Y671880D02*
Y670431D01*
G01Y667943D02*
Y666494D01*
G01X-35546Y688085D02*
Y685723D01*
G01Y684148D02*
Y681786D01*
G01Y680211D02*
Y677849D01*
G01Y676274D02*
Y673912D01*
G01Y672337D02*
Y669975D01*
G01X-35357Y687651D02*
Y686156D01*
G01Y683714D02*
Y682219D01*
G01Y679777D02*
Y678282D01*
G01Y675840D02*
Y674345D01*
G01Y671903D02*
Y670408D01*
G01Y667966D02*
Y666471D01*
G01X-34607Y688006D02*
Y685802D01*
G01Y680132D02*
Y677928D01*
G01Y684069D02*
Y681865D01*
G01Y676195D02*
Y673991D01*
G01Y672258D02*
Y670054D01*
G01X-34136Y687665D02*
Y686142D01*
G01Y683728D02*
Y682205D01*
G01Y675854D02*
Y674331D01*
G01Y679791D02*
Y678268D01*
G01Y671917D02*
Y670394D01*
G01Y667980D02*
Y666457D01*
G01X-33153Y687676D02*
Y686131D01*
G01Y683739D02*
Y682194D01*
G01Y679802D02*
Y678257D01*
G01Y675865D02*
Y674320D01*
G01Y671928D02*
Y670383D01*
G01Y667991D02*
Y666446D01*
G01X-32319Y687685D02*
Y686122D01*
G01Y683748D02*
Y682185D01*
G01Y675874D02*
Y674311D01*
G01Y679811D02*
Y678248D01*
G01Y671937D02*
Y670374D01*
G01Y668000D02*
Y666437D01*
G01X-31941Y687690D02*
Y686118D01*
G01Y683753D02*
Y682181D01*
G01Y675879D02*
Y674307D01*
G01Y679816D02*
Y678244D01*
G01Y671942D02*
Y670370D01*
G01Y668005D02*
Y666433D01*
G01X-38108Y666736D02*
X-35351Y666471D01*
G01X-38108Y670673D02*
X-35351Y670408D01*
G01X-38108Y674610D02*
X-35351Y674345D01*
G01Y667967D02*
X-10631Y668243D01*
G01X-35351Y671904D02*
X-10631Y672180D01*
G01X-35351Y675841D02*
X-10631Y676117D01*
G01X-35351Y679778D02*
X-10631Y680054D01*
G01X-35351Y683715D02*
X-10631Y683991D01*
G01X-39607Y667357D02*
X-24844D01*
G01X-35546Y668321D02*
X-1D01*
G01X-24509Y668400D02*
X-39607D01*
G01Y669975D02*
X-24509D01*
G01X-35546Y670054D02*
X-1D01*
G01X-39607Y670506D02*
X-27993D01*
G01X-35546Y672258D02*
X-1D01*
G01X-24509Y672337D02*
X-39607D01*
G01Y673912D02*
X-24509D01*
G01X-35546Y673991D02*
X-1D01*
G01X-35546Y676195D02*
X-1D01*
G01X-24509Y676274D02*
X-39607D01*
G01Y677849D02*
X-24509D01*
G01X-35546Y677928D02*
X-1D01*
G01X-35546Y680132D02*
X-1D01*
G01X-24509Y680211D02*
X-39607D01*
G01Y681786D02*
X-24509D01*
G01X-35546Y681865D02*
X-1D01*
G01X-27993Y683853D02*
X-39607D01*
G01X-35546Y684069D02*
X-1D01*
G01X-24509Y684148D02*
X-39607D01*
G01Y685723D02*
X-24509D01*
G01X-35546Y685802D02*
X-1D01*
G01X-10631Y666195D02*
X-35351Y666471D01*
G01X-10631Y670132D02*
X-35351Y670408D01*
G01X-10631Y674069D02*
X-35351Y674345D01*
G01X-10631Y678006D02*
X-35351Y678282D01*
G01X-10631Y681943D02*
X-35351Y682219D01*
G01X-10631Y685880D02*
X-35351Y686156D01*
G01X-38108Y678547D02*
X-35351Y678282D01*
G01X-38108Y682484D02*
X-35351Y682219D01*
G01X-38108Y686421D02*
X-35351Y686156D01*
G01Y667967D02*
X-38108Y667701D01*
G01X-35351Y671904D02*
X-38108Y671638D01*
G01X-35351Y675841D02*
X-38108Y675575D01*
G01X-35351Y679778D02*
X-38108Y679512D01*
G01X-35351Y683715D02*
X-38108Y683449D01*
G01X-38426Y699896D02*
Y697534D01*
G01Y692022D02*
Y689660D01*
G01Y695959D02*
Y693597D01*
G01X-38108Y699197D02*
Y698232D01*
G01Y695260D02*
Y694295D01*
G01Y691323D02*
Y690358D01*
G01Y687386D02*
Y686421D01*
G01X-37871Y699220D02*
Y698209D01*
G01Y695283D02*
Y694272D01*
G01Y691346D02*
Y690335D01*
G01Y687409D02*
Y686398D01*
G01X-35595Y699439D02*
Y697990D01*
G01Y695502D02*
Y694053D01*
G01Y691565D02*
Y690116D01*
G01X-35546Y699896D02*
Y697534D01*
G01Y695959D02*
Y693597D01*
G01Y692022D02*
Y689660D01*
G01X-35357Y699462D02*
Y697967D01*
G01Y695525D02*
Y694030D01*
G01Y691588D02*
Y690093D01*
G01X-34607Y699817D02*
Y697613D01*
G01Y691943D02*
Y689739D01*
G01Y695880D02*
Y693676D01*
G01X-34136Y699476D02*
Y697953D01*
G01Y695539D02*
Y694016D01*
G01Y691602D02*
Y690079D01*
G01X-33153Y699487D02*
Y697942D01*
G01Y695550D02*
Y694005D01*
G01Y691613D02*
Y690068D01*
G01X-32319Y699496D02*
Y697933D01*
G01Y695559D02*
Y693996D01*
G01Y691622D02*
Y690059D01*
G01X-31941Y699501D02*
Y697929D01*
G01Y695564D02*
Y693992D01*
G01Y691627D02*
Y690055D01*
G01X-36561Y703488D02*
X-39607Y705621D01*
G01X-35351Y687652D02*
X-10631Y687928D01*
G01X-35351Y691589D02*
X-10631Y691865D01*
G01X-39607Y687002D02*
X-24844D01*
G01X-35546Y688006D02*
X-1D01*
G01X-24509Y688085D02*
X-39607D01*
G01Y689660D02*
X-24509D01*
G01X-35546Y689739D02*
X-1D01*
G01X-39607Y690979D02*
X-24844D01*
G01X-35546Y691943D02*
X-1D01*
G01X-24509Y692022D02*
X-39607D01*
G01Y693597D02*
X-24509D01*
G01X-35546Y693676D02*
X-1D01*
G01X-39607Y694128D02*
X-27993D01*
G01X-35546Y695880D02*
X-1D01*
G01X-24509Y695959D02*
X-39607D01*
G01Y697534D02*
X-24509D01*
G01X-35546Y697613D02*
X-1D01*
G01X-35546Y699817D02*
X-1D01*
G01X-24509Y699896D02*
X-39607D01*
G01X-10631Y689817D02*
X-35351Y690093D01*
G01X-10631Y693754D02*
X-35351Y694030D01*
G01X-10631Y697691D02*
X-35351Y697967D01*
G01X-38108Y690358D02*
X-35351Y690093D01*
G01X-38108Y694295D02*
X-35351Y694030D01*
G01X-38108Y698232D02*
X-35351Y697967D01*
G01Y687652D02*
X-38108Y687386D01*
G01X-35351Y691589D02*
X-38108Y691323D01*
G01X-35351Y695526D02*
X-38108Y695260D01*
G01X-35351Y699463D02*
X-38108Y699197D01*
G01X-35351Y695526D02*
X-10631Y695802D01*
G01X-35351Y699463D02*
X-10631Y699739D01*
G01X-8899Y702947D02*
X-34845D01*
G01X-36561Y703488D02*
G03X-34845Y702947I1716J2451D01*
G01X-27993Y707475D02*
X-39607D01*
G01Y710624D02*
X-1D01*
G01X-27265Y668400D02*
Y666038D01*
G01Y664463D02*
Y662101D01*
G01Y660526D02*
Y658164D01*
G01Y656589D02*
Y654227D01*
G01Y652652D02*
Y650290D01*
G01Y648715D02*
Y646353D01*
G01X-26943Y664124D02*
Y662440D01*
G01Y660187D02*
Y658503D01*
G01Y656250D02*
Y654566D01*
G01Y652313D02*
Y650629D01*
G01Y648376D02*
Y646692D01*
G01X-26566Y664128D02*
Y662436D01*
G01Y660191D02*
Y658499D01*
G01Y656254D02*
Y654562D01*
G01Y652317D02*
Y650625D01*
G01Y648380D02*
Y646688D01*
G01X-24509Y668400D02*
Y666038D01*
G01Y664463D02*
Y662101D01*
G01Y660526D02*
Y658164D01*
G01Y656589D02*
Y654227D01*
G01Y652652D02*
Y650290D01*
G01Y648715D02*
Y646353D01*
G01X-24122Y664155D02*
Y662409D01*
G01Y660218D02*
Y658472D01*
G01Y652344D02*
Y650598D01*
G01Y656281D02*
Y654535D01*
G01Y648407D02*
Y646661D01*
G01X-23684Y664160D02*
Y662404D01*
G01Y660223D02*
Y658467D01*
G01Y652349D02*
Y650593D01*
G01Y656286D02*
Y654530D01*
G01Y648412D02*
Y646656D01*
G01X-12993Y666117D02*
Y665802D01*
G01Y662180D02*
Y661865D01*
G01Y664699D02*
Y664384D01*
G01Y658243D02*
Y657928D01*
G01Y660762D02*
Y660447D01*
G01Y656825D02*
Y656510D01*
G01Y654306D02*
Y653991D01*
G01Y652888D02*
Y652573D01*
G01Y650369D02*
Y650054D01*
G01Y648951D02*
Y648636D01*
G01X-12280Y668224D02*
Y666213D01*
G01Y664287D02*
Y662276D01*
G01Y660350D02*
Y658339D01*
G01Y656413D02*
Y654402D01*
G01Y652476D02*
Y650465D01*
G01Y648539D02*
Y646528D01*
G01X-11843Y668229D02*
Y666209D01*
G01Y664292D02*
Y662272D01*
G01Y660355D02*
Y658335D01*
G01Y656418D02*
Y654398D01*
G01Y652481D02*
Y650461D01*
G01Y648544D02*
Y646524D01*
G01X-1Y648951D02*
X-12993D01*
G01Y650054D02*
X-1D01*
G01Y652888D02*
X-12993D01*
G01Y653991D02*
X-1D01*
G01Y656825D02*
X-12993D01*
G01Y657928D02*
X-1D01*
G01Y660762D02*
X-12993D01*
G01Y661865D02*
X-1D01*
G01Y664699D02*
X-12993D01*
G01Y665802D02*
X-1D01*
G01X-27993Y667357D02*
Y687002D01*
G01X-27265Y688085D02*
Y685723D01*
G01Y684148D02*
Y681786D01*
G01Y680211D02*
Y677849D01*
G01Y676274D02*
Y673912D01*
G01Y672337D02*
Y669975D01*
G01X-26943Y687746D02*
Y686062D01*
G01Y683809D02*
Y682125D01*
G01Y679872D02*
Y678188D01*
G01Y675935D02*
Y674251D01*
G01Y671998D02*
Y670314D01*
G01Y668061D02*
Y666377D01*
G01X-26566Y687750D02*
Y686058D01*
G01Y683813D02*
Y682121D01*
G01Y679876D02*
Y678184D01*
G01Y675939D02*
Y674247D01*
G01Y672002D02*
Y670310D01*
G01Y668065D02*
Y666373D01*
G01X-24844Y667357D02*
Y687002D01*
G01X-24509Y688085D02*
Y685723D01*
G01Y684148D02*
Y681786D01*
G01Y680211D02*
Y677849D01*
G01Y676274D02*
Y673912D01*
G01Y672337D02*
Y669975D01*
G01X-24122Y687777D02*
Y686031D01*
G01Y683840D02*
Y682094D01*
G01Y675966D02*
Y674220D01*
G01Y679903D02*
Y678157D01*
G01Y672029D02*
Y670283D01*
G01Y668092D02*
Y666346D01*
G01X-23684Y687782D02*
Y686026D01*
G01Y683845D02*
Y682089D01*
G01Y675971D02*
Y674215D01*
G01Y679908D02*
Y678152D01*
G01Y672034D02*
Y670278D01*
G01Y668097D02*
Y666341D01*
G01X-12993Y685802D02*
Y685487D01*
G01Y681865D02*
Y681550D01*
G01Y684384D02*
Y684069D01*
G01Y680447D02*
Y680132D01*
G01Y677928D02*
Y677613D01*
G01Y676510D02*
Y676195D01*
G01Y673991D02*
Y673676D01*
G01Y672573D02*
Y672258D01*
G01Y670054D02*
Y669739D01*
G01Y668636D02*
Y668321D01*
G01X-12280Y687909D02*
Y685898D01*
G01Y683972D02*
Y681961D01*
G01Y680035D02*
Y678024D01*
G01Y676098D02*
Y674087D01*
G01Y672161D02*
Y670150D01*
G01X-11843Y687914D02*
Y685894D01*
G01Y683977D02*
Y681957D01*
G01Y680040D02*
Y678020D01*
G01Y676103D02*
Y674083D01*
G01Y672166D02*
Y670146D01*
G01X-1Y668636D02*
X-12993D01*
G01Y669739D02*
X-1D01*
G01Y672573D02*
X-12993D01*
G01Y673676D02*
X-1D01*
G01Y676510D02*
X-12993D01*
G01Y677613D02*
X-1D01*
G01Y680447D02*
X-12993D01*
G01Y681550D02*
X-1D01*
G01Y684384D02*
X-12993D01*
G01Y685487D02*
X-1D01*
G01X-27993Y690979D02*
Y710624D01*
G01X-27265Y699896D02*
Y697534D01*
G01Y695959D02*
Y693597D01*
G01Y692022D02*
Y689660D01*
G01X-26943Y699557D02*
Y697873D01*
G01Y695620D02*
Y693936D01*
G01Y691683D02*
Y689999D01*
G01X-26566Y699561D02*
Y697869D01*
G01Y695624D02*
Y693932D01*
G01Y691687D02*
Y689995D01*
G01X-24844Y690979D02*
Y710624D01*
G01X-24509Y699896D02*
Y697534D01*
G01Y695959D02*
Y693597D01*
G01Y692022D02*
Y689660D01*
G01X-24122Y699588D02*
Y697842D01*
G01Y695651D02*
Y693905D01*
G01Y691714D02*
Y689968D01*
G01X-23684Y699593D02*
Y697837D01*
G01Y695656D02*
Y693900D01*
G01Y691719D02*
Y689963D01*
G01X-12993Y700132D02*
Y699817D01*
G01Y696195D02*
Y695880D01*
G01Y697613D02*
Y697298D01*
G01Y693676D02*
Y693361D01*
G01Y689739D02*
Y689424D01*
G01Y692258D02*
Y691943D01*
G01Y688321D02*
Y688006D01*
G01X-12280Y699720D02*
Y697709D01*
G01Y695783D02*
Y693772D01*
G01Y691846D02*
Y689835D01*
G01X-11843Y699725D02*
Y697705D01*
G01Y695788D02*
Y693768D01*
G01Y691851D02*
Y689831D01*
G01X-1Y688321D02*
X-12993D01*
G01Y689424D02*
X-1D01*
G01Y692258D02*
X-12993D01*
G01Y693361D02*
X-1D01*
G01Y696195D02*
X-12993D01*
G01Y697298D02*
X-1D01*
G01Y700132D02*
X-12993D01*
G01X-3151Y648597D02*
X-3378Y648991D01*
G01X-2197Y650408D02*
X-1970Y650014D01*
G01X-3151Y652534D02*
X-3378Y652928D01*
G01X-2197Y654345D02*
X-1970Y653951D01*
G01X-3151Y656471D02*
X-3378Y656865D01*
G01X-2197Y658282D02*
X-1970Y657888D01*
G01X-3151Y660408D02*
X-3378Y660802D01*
G01X-2197Y662219D02*
X-1970Y661825D01*
G01X-3151Y664345D02*
X-3378Y664739D01*
G01X-2197Y666156D02*
X-1970Y665762D01*
G01X-10531Y668287D02*
Y666150D01*
G01Y664350D02*
Y662213D01*
G01Y660413D02*
Y658276D01*
G01Y652539D02*
Y650402D01*
G01Y656476D02*
Y654339D01*
G01Y648602D02*
Y646465D01*
G01X-6694Y666431D02*
Y665841D01*
G01Y664660D02*
Y664069D01*
G01Y662494D02*
Y661904D01*
G01Y656786D02*
Y656195D01*
G01Y660723D02*
Y660132D01*
G01Y658557D02*
Y657967D01*
G01Y654620D02*
Y654030D01*
G01Y652849D02*
Y652258D01*
G01Y650683D02*
Y650093D01*
G01Y648912D02*
Y648321D01*
G01Y646746D02*
Y646156D01*
G01X-4725Y666431D02*
Y665526D01*
G01Y664975D02*
Y664069D01*
G01Y662494D02*
Y661589D01*
G01Y661038D02*
Y660132D01*
G01Y658557D02*
Y657652D01*
G01Y657101D02*
Y656195D01*
G01Y654620D02*
Y653715D01*
G01Y653164D02*
Y652258D01*
G01Y650683D02*
Y649778D01*
G01Y649227D02*
Y648321D01*
G01X-3757Y668321D02*
Y666117D01*
G01Y664384D02*
Y662180D01*
G01Y660447D02*
Y658243D01*
G01Y652573D02*
Y650369D01*
G01Y656510D02*
Y654306D01*
G01Y648636D02*
Y646431D01*
G01X-10631Y646510D02*
X-9844Y646156D01*
G01X-10631Y650447D02*
X-9844Y650093D01*
G01X-10631Y654384D02*
X-9844Y654030D01*
G01X-10631Y658321D02*
X-9844Y657967D01*
G01X-2521Y668321D02*
Y666117D01*
G01Y664384D02*
Y662180D01*
G01Y660447D02*
Y658243D01*
G01Y652573D02*
Y650369D01*
G01Y656510D02*
Y654306D01*
G01Y648636D02*
Y646431D01*
G01X-2251Y668636D02*
Y665802D01*
G01Y664699D02*
Y661865D01*
G01Y660762D02*
Y657928D01*
G01Y656825D02*
Y653991D01*
G01Y652888D02*
Y650054D01*
G01X-985Y663951D02*
Y662613D01*
G01Y660014D02*
Y658676D01*
G01Y652140D02*
Y650802D01*
G01Y656077D02*
Y654739D01*
G01Y648203D02*
Y646865D01*
G01X8523Y663951D02*
Y662613D01*
G01Y660014D02*
Y658676D01*
G01Y656077D02*
Y654739D01*
G01Y652140D02*
Y650802D01*
G01Y648203D02*
Y646865D01*
G01X-4259Y650250D02*
X-3378Y650014D01*
G01X-4259Y654187D02*
X-3378Y653951D01*
G01X-4259Y658124D02*
X-3378Y657888D01*
G01X-4259Y662061D02*
X-3378Y661825D01*
G01X-4259Y665998D02*
X-3378Y665762D01*
G01X-10631Y662258D02*
X-9844Y661904D01*
G01X-10631Y666195D02*
X-9844Y665841D01*
G01X-4725Y649778D02*
X-6694Y650093D01*
G01X-4725Y653715D02*
X-6694Y654030D01*
G01X-4725Y657652D02*
X-6694Y657967D01*
G01X-4725Y661589D02*
X-6694Y661904D01*
G01X-4725Y665526D02*
X-6694Y665841D01*
G01Y646156D02*
X-9844D01*
G01X-4259Y646313D02*
X-4725D01*
G01X-2197Y646471D02*
X-3151D01*
G01X-4725Y646746D02*
X-6694D01*
G01X15077Y646865D02*
X8523D01*
G01D02*
X-1D01*
G01D02*
X-985D01*
G01Y648203D02*
X-1D01*
G01D02*
X8523D01*
G01D02*
X12600D01*
G01X-4725Y648321D02*
X-6694D01*
G01X-3151Y648597D02*
X-2197D01*
G01X-4725Y648754D02*
X-4259D01*
G01X-9844Y648912D02*
X-6694D01*
G01X-1970Y648991D02*
X-1D01*
G01Y650014D02*
X-1970D01*
G01X-6694Y650093D02*
X-9844D01*
G01X-4259Y650250D02*
X-4725D01*
G01X-2197Y650408D02*
X-3151D01*
G01X-4725Y650683D02*
X-6694D01*
G01X15077Y650802D02*
X8523D01*
G01D02*
X-1D01*
G01D02*
X-985D01*
G01Y652140D02*
X-1D01*
G01D02*
X8523D01*
G01D02*
X12600D01*
G01X-4725Y652258D02*
X-6694D01*
G01X-3151Y652534D02*
X-2197D01*
G01X-4725Y652691D02*
X-4259D01*
G01X-9844Y652849D02*
X-6694D01*
G01X-1970Y652928D02*
X-1D01*
G01Y653951D02*
X-1970D01*
G01X-6694Y654030D02*
X-9844D01*
G01X-4259Y654187D02*
X-4725D01*
G01X-2197Y654345D02*
X-3151D01*
G01X-4725Y654620D02*
X-6694D01*
G01X15077Y654739D02*
X8523D01*
G01D02*
X-1D01*
G01D02*
X-985D01*
G01Y656077D02*
X-1D01*
G01D02*
X8523D01*
G01D02*
X12600D01*
G01X-4725Y656195D02*
X-6694D01*
G01X-3151Y656471D02*
X-2197D01*
G01X-4725Y656628D02*
X-4259D01*
G01X-9844Y656786D02*
X-6694D01*
G01X-1970Y656865D02*
X-1D01*
G01Y657888D02*
X-1970D01*
G01X-6694Y657967D02*
X-9844D01*
G01X-4259Y658124D02*
X-4725D01*
G01X-2197Y658282D02*
X-3151D01*
G01X-4725Y658557D02*
X-6694D01*
G01X15077Y658676D02*
X8523D01*
G01D02*
X-1D01*
G01D02*
X-985D01*
G01Y660014D02*
X-1D01*
G01D02*
X8523D01*
G01D02*
X12600D01*
G01X-4725Y660132D02*
X-6694D01*
G01X-3151Y660408D02*
X-2197D01*
G01X-4725Y660565D02*
X-4259D01*
G01X-9844Y660723D02*
X-6694D01*
G01X-1970Y660802D02*
X-1D01*
G01Y661825D02*
X-1970D01*
G01X-6694Y661904D02*
X-9844D01*
G01X-4259Y662061D02*
X-4725D01*
G01X-2197Y662219D02*
X-3151D01*
G01X-4725Y662494D02*
X-6694D01*
G01X15077Y662613D02*
X8523D01*
G01D02*
X-1D01*
G01D02*
X-985D01*
G01Y663951D02*
X-1D01*
G01D02*
X8523D01*
G01D02*
X12600D01*
G01X-4725Y664069D02*
X-6694D01*
G01X-3151Y664345D02*
X-2197D01*
G01X-4725Y664502D02*
X-4259D01*
G01X-9844Y664660D02*
X-6694D01*
G01X-1970Y664739D02*
X-1D01*
G01Y665762D02*
X-1970D01*
G01X-6694Y665841D02*
X-9844D01*
G01X-4259Y665998D02*
X-4725D01*
G01X-2197Y666156D02*
X-3151D01*
G01X-3378Y665762D02*
X-3151Y666156D01*
G01X-1970Y664739D02*
X-2197Y664345D01*
G01X-3378Y661825D02*
X-3151Y662219D01*
G01X-1970Y660802D02*
X-2197Y660408D01*
G01X-3378Y657888D02*
X-3151Y658282D01*
G01X-1970Y656865D02*
X-2197Y656471D01*
G01X-3378Y653951D02*
X-3151Y654345D01*
G01X-1970Y652928D02*
X-2197Y652534D01*
G01X-3378Y650014D02*
X-3151Y650408D01*
G01X-1970Y648991D02*
X-2197Y648597D01*
G01X-6694Y648912D02*
X-4725Y649227D01*
G01X-6694Y652849D02*
X-4725Y653164D01*
G01X-6694Y656786D02*
X-4725Y657101D01*
G01X-6694Y660723D02*
X-4725Y661038D01*
G01X-6694Y664660D02*
X-4725Y664975D01*
G01X-3378Y648991D02*
X-4259Y648754D01*
G01X-3378Y652928D02*
X-4259Y652691D01*
G01X-3378Y656865D02*
X-4259Y656628D01*
G01X-3378Y660802D02*
X-4259Y660565D01*
G01X-3378Y664739D02*
X-4259Y664502D01*
G01X-9844Y664660D02*
X-10631Y664306D01*
G01X-9844Y660723D02*
X-10631Y660369D01*
G01X-9844Y656786D02*
X-10631Y656431D01*
G01X-9844Y652849D02*
X-10631Y652494D01*
G01X-9844Y648912D02*
X-10631Y648557D01*
G01X-3151Y668282D02*
X-3378Y668676D01*
G01X-2197Y670093D02*
X-1970Y669699D01*
G01X-3151Y672219D02*
X-3378Y672613D01*
G01X-2197Y674030D02*
X-1970Y673636D01*
G01X-3151Y676156D02*
X-3378Y676550D01*
G01X-2197Y677967D02*
X-1970Y677573D01*
G01X-3151Y680093D02*
X-3378Y680487D01*
G01X-2197Y681904D02*
X-1970Y681510D01*
G01X-3151Y684030D02*
X-3378Y684424D01*
G01X-2197Y685841D02*
X-1970Y685447D01*
G01X-10531Y687972D02*
Y685835D01*
G01Y684035D02*
Y681898D01*
G01Y676161D02*
Y674024D01*
G01Y680098D02*
Y677961D01*
G01Y672224D02*
Y670087D01*
G01X-6694Y686117D02*
Y685526D01*
G01Y684345D02*
Y683754D01*
G01Y682180D02*
Y681589D01*
G01Y680408D02*
Y679817D01*
G01Y678243D02*
Y677652D01*
G01Y676471D02*
Y675880D01*
G01Y674306D02*
Y673715D01*
G01Y672534D02*
Y671943D01*
G01Y670369D02*
Y669778D01*
G01Y668597D02*
Y668006D01*
G01X-4725Y686117D02*
Y685211D01*
G01Y684660D02*
Y683754D01*
G01Y682180D02*
Y681274D01*
G01Y680723D02*
Y679817D01*
G01Y678243D02*
Y677337D01*
G01Y676786D02*
Y675880D01*
G01Y674306D02*
Y673400D01*
G01Y672849D02*
Y671943D01*
G01Y670369D02*
Y669463D01*
G01Y668912D02*
Y668006D01*
G01X-3757Y688006D02*
Y685802D01*
G01Y680132D02*
Y677928D01*
G01Y684069D02*
Y681865D01*
G01Y676195D02*
Y673991D01*
G01Y672258D02*
Y670054D01*
G01X-2521Y688006D02*
Y685802D01*
G01Y680132D02*
Y677928D01*
G01Y684069D02*
Y681865D01*
G01Y676195D02*
Y673991D01*
G01Y672258D02*
Y670054D01*
G01X-2251Y688321D02*
Y685487D01*
G01Y684384D02*
Y681550D01*
G01Y680447D02*
Y677613D01*
G01Y676510D02*
Y673676D01*
G01Y672573D02*
Y669739D01*
G01X-985Y687573D02*
Y686235D01*
G01Y683636D02*
Y682298D01*
G01Y675762D02*
Y674424D01*
G01Y679699D02*
Y678361D01*
G01Y671825D02*
Y670487D01*
G01Y667888D02*
Y666550D01*
G01X8523Y687573D02*
Y686235D01*
G01Y683636D02*
Y682298D01*
G01Y679699D02*
Y678361D01*
G01Y675762D02*
Y674424D01*
G01Y671825D02*
Y670487D01*
G01Y667888D02*
Y666550D01*
G01X-4259Y669935D02*
X-3378Y669699D01*
G01X-4259Y673872D02*
X-3378Y673636D01*
G01X-10631Y670132D02*
X-9844Y669778D01*
G01X-10631Y674069D02*
X-9844Y673715D01*
G01X-10631Y678006D02*
X-9844Y677652D01*
G01X-10631Y681943D02*
X-9844Y681589D01*
G01X-10631Y685880D02*
X-9844Y685526D01*
G01X-4725Y669463D02*
X-6694Y669778D01*
G01X-4725Y673400D02*
X-6694Y673715D01*
G01X-4725Y677337D02*
X-6694Y677652D01*
G01X-4725Y681274D02*
X-6694Y681589D01*
G01X-4725Y685211D02*
X-6694Y685526D01*
G01X-4259Y677809D02*
X-3378Y677573D01*
G01X-4259Y681746D02*
X-3378Y681510D01*
G01X-4259Y685683D02*
X-3378Y685447D01*
G01D02*
X-3151Y685841D01*
G01X-1970Y684424D02*
X-2197Y684030D01*
G01X-3378Y681510D02*
X-3151Y681904D01*
G01X-4725Y666431D02*
X-6694D01*
G01X15077Y666550D02*
X8523D01*
G01D02*
X-1D01*
G01D02*
X-985D01*
G01Y667888D02*
X-1D01*
G01D02*
X8523D01*
G01D02*
X12600D01*
G01X-4725Y668006D02*
X-6694D01*
G01X-3151Y668282D02*
X-2197D01*
G01X-4725Y668439D02*
X-4259D01*
G01X-9844Y668597D02*
X-6694D01*
G01X-1970Y668676D02*
X-1D01*
G01Y669699D02*
X-1970D01*
G01X-6694Y669778D02*
X-9844D01*
G01X-4259Y669935D02*
X-4725D01*
G01X-2197Y670093D02*
X-3151D01*
G01X-4725Y670369D02*
X-6694D01*
G01X15077Y670487D02*
X8523D01*
G01D02*
X-1D01*
G01D02*
X-985D01*
G01Y671825D02*
X-1D01*
G01D02*
X8523D01*
G01D02*
X12600D01*
G01X-4725Y671943D02*
X-6694D01*
G01X-3151Y672219D02*
X-2197D01*
G01X-4725Y672376D02*
X-4259D01*
G01X-9844Y672534D02*
X-6694D01*
G01X-1970Y672613D02*
X-1D01*
G01Y673636D02*
X-1970D01*
G01X-6694Y673715D02*
X-9844D01*
G01X-4259Y673872D02*
X-4725D01*
G01X-2197Y674030D02*
X-3151D01*
G01X-4725Y674306D02*
X-6694D01*
G01X15077Y674424D02*
X8523D01*
G01D02*
X-1D01*
G01D02*
X-985D01*
G01Y675762D02*
X-1D01*
G01D02*
X8523D01*
G01D02*
X12600D01*
G01X-4725Y675880D02*
X-6694D01*
G01X-3151Y676156D02*
X-2197D01*
G01X-4725Y676313D02*
X-4259D01*
G01X-9844Y676471D02*
X-6694D01*
G01X-1970Y676550D02*
X-1D01*
G01Y677573D02*
X-1970D01*
G01X-6694Y677652D02*
X-9844D01*
G01X-4259Y677809D02*
X-4725D01*
G01X-2197Y677967D02*
X-3151D01*
G01X-4725Y678243D02*
X-6694D01*
G01X15077Y678361D02*
X8523D01*
G01D02*
X-1D01*
G01D02*
X-985D01*
G01Y679699D02*
X-1D01*
G01D02*
X8523D01*
G01D02*
X12600D01*
G01X-4725Y679817D02*
X-6694D01*
G01X-3151Y680093D02*
X-2197D01*
G01X-4725Y680250D02*
X-4259D01*
G01X-9844Y680408D02*
X-6694D01*
G01X-1970Y680487D02*
X-1D01*
G01Y681510D02*
X-1970D01*
G01X-6694Y681589D02*
X-9844D01*
G01X-4259Y681746D02*
X-4725D01*
G01X-2197Y681904D02*
X-3151D01*
G01X-4725Y682180D02*
X-6694D01*
G01X15077Y682298D02*
X8523D01*
G01D02*
X-1D01*
G01D02*
X-985D01*
G01Y683636D02*
X-1D01*
G01D02*
X8523D01*
G01D02*
X12600D01*
G01X-4725Y683754D02*
X-6694D01*
G01X-3151Y684030D02*
X-2197D01*
G01X-4725Y684187D02*
X-4259D01*
G01X-9844Y684345D02*
X-6694D01*
G01X-1970Y684424D02*
X-1D01*
G01Y685447D02*
X-1970D01*
G01X-6694Y685526D02*
X-9844D01*
G01X-4259Y685683D02*
X-4725D01*
G01X-2197Y685841D02*
X-3151D01*
G01X-4725Y686117D02*
X-6694D01*
G01X15077Y686235D02*
X8523D01*
G01D02*
X-1D01*
G01D02*
X-985D01*
G01X-1970Y680487D02*
X-2197Y680093D01*
G01X-3378Y677573D02*
X-3151Y677967D01*
G01X-1970Y676550D02*
X-2197Y676156D01*
G01X-3378Y673636D02*
X-3151Y674030D01*
G01X-1970Y672613D02*
X-2197Y672219D01*
G01X-3378Y669699D02*
X-3151Y670093D01*
G01X-1970Y668676D02*
X-2197Y668282D01*
G01X-6694Y668597D02*
X-4725Y668912D01*
G01X-6694Y672534D02*
X-4725Y672849D01*
G01X-6694Y676471D02*
X-4725Y676786D01*
G01X-6694Y680408D02*
X-4725Y680723D01*
G01X-6694Y684345D02*
X-4725Y684660D01*
G01X-3378Y668676D02*
X-4259Y668439D01*
G01X-3378Y672613D02*
X-4259Y672376D01*
G01X-3378Y676550D02*
X-4259Y676313D01*
G01X-3378Y680487D02*
X-4259Y680250D01*
G01X-3378Y684424D02*
X-4259Y684187D01*
G01X-9844Y684345D02*
X-10631Y683991D01*
G01X-9844Y680408D02*
X-10631Y680054D01*
G01X-9844Y676471D02*
X-10631Y676117D01*
G01X-9844Y672534D02*
X-10631Y672180D01*
G01X-9844Y668597D02*
X-10631Y668243D01*
G01X-3151Y687967D02*
X-3378Y688361D01*
G01X-2197Y689778D02*
X-1970Y689384D01*
G01X-3151Y691904D02*
X-3378Y692298D01*
G01X-2197Y693715D02*
X-1970Y693321D01*
G01X-3151Y695841D02*
X-3378Y696235D01*
G01X-2197Y697652D02*
X-1970Y697258D01*
G01X-3151Y699778D02*
X-3378Y700172D01*
G01X-10531Y699783D02*
Y697646D01*
G01Y695846D02*
Y693709D01*
G01Y691909D02*
Y689772D01*
G01X-6694Y700093D02*
Y699502D01*
G01Y697928D02*
Y697337D01*
G01Y696156D02*
Y695565D01*
G01Y693991D02*
Y693400D01*
G01Y692219D02*
Y691628D01*
G01Y690054D02*
Y689463D01*
G01Y688282D02*
Y687691D01*
G01X-4725Y700408D02*
Y699502D01*
G01Y697928D02*
Y697022D01*
G01Y696471D02*
Y695565D01*
G01Y693991D02*
Y693085D01*
G01Y692534D02*
Y691628D01*
G01Y690054D02*
Y689148D01*
G01Y688597D02*
Y687691D01*
G01X-3757Y699817D02*
Y697613D01*
G01Y695880D02*
Y693676D01*
G01Y691943D02*
Y689739D01*
G01X-2521Y699817D02*
Y697613D01*
G01Y695880D02*
Y693676D01*
G01Y691943D02*
Y689739D01*
G01X-2251Y700132D02*
Y697298D01*
G01Y696195D02*
Y693361D01*
G01Y692258D02*
Y689424D01*
G01X-985Y699384D02*
Y698046D01*
G01Y695447D02*
Y694109D01*
G01Y691510D02*
Y690172D01*
G01X8523Y699384D02*
Y698046D01*
G01Y695447D02*
Y694109D01*
G01Y691510D02*
Y690172D01*
G01X-10631Y689817D02*
X-9844Y689463D01*
G01X-10631Y693754D02*
X-9844Y693400D01*
G01X-10631Y697691D02*
X-9844Y697337D01*
G01X-4725Y689148D02*
X-6694Y689463D01*
G01X-4725Y693085D02*
X-6694Y693400D01*
G01X-4725Y697022D02*
X-6694Y697337D01*
G01X-4259Y689620D02*
X-3378Y689384D01*
G01X-4259Y693557D02*
X-3378Y693321D01*
G01X-4259Y697494D02*
X-3378Y697258D01*
G01X-1970Y700172D02*
X-2197Y699778D01*
G01X-3378Y697258D02*
X-3151Y697652D01*
G01X-1970Y696235D02*
X-2197Y695841D01*
G01X-3378Y693321D02*
X-3151Y693715D01*
G01X-1970Y692298D02*
X-2197Y691904D01*
G01X-3378Y689384D02*
X-3151Y689778D01*
G01X-1970Y688361D02*
X-2197Y687967D01*
G01X-985Y687573D02*
X-1D01*
G01D02*
X8523D01*
G01D02*
X12600D01*
G01X-4725Y687691D02*
X-6694D01*
G01X-3151Y687967D02*
X-2197D01*
G01X-4725Y688124D02*
X-4259D01*
G01X-9844Y688282D02*
X-6694D01*
G01X-1970Y688361D02*
X-1D01*
G01Y689384D02*
X-1970D01*
G01X-6694Y689463D02*
X-9844D01*
G01X-4259Y689620D02*
X-4725D01*
G01X-2197Y689778D02*
X-3151D01*
G01X-4725Y690054D02*
X-6694D01*
G01X15077Y690172D02*
X8523D01*
G01D02*
X-1D01*
G01D02*
X-985D01*
G01Y691510D02*
X-1D01*
G01D02*
X8523D01*
G01D02*
X12600D01*
G01X-4725Y691628D02*
X-6694D01*
G01X-3151Y691904D02*
X-2197D01*
G01X-4725Y692061D02*
X-4259D01*
G01X-9844Y692219D02*
X-6694D01*
G01X-1970Y692298D02*
X-1D01*
G01Y693321D02*
X-1970D01*
G01X-6694Y693400D02*
X-9844D01*
G01X-4259Y693557D02*
X-4725D01*
G01X-2197Y693715D02*
X-3151D01*
G01X-4725Y693991D02*
X-6694D01*
G01X15077Y694109D02*
X8523D01*
G01D02*
X-1D01*
G01D02*
X-985D01*
G01Y695447D02*
X-1D01*
G01D02*
X8523D01*
G01D02*
X12600D01*
G01X-4725Y695565D02*
X-6694D01*
G01X-3151Y695841D02*
X-2197D01*
G01X-4725Y695998D02*
X-4259D01*
G01X-9844Y696156D02*
X-6694D01*
G01X-1970Y696235D02*
X-1D01*
G01Y697258D02*
X-1970D01*
G01X-6694Y697337D02*
X-9844D01*
G01X-4259Y697494D02*
X-4725D01*
G01X-2197Y697652D02*
X-3151D01*
G01X-4725Y697928D02*
X-6694D01*
G01X15077Y698046D02*
X8523D01*
G01D02*
X-1D01*
G01D02*
X-985D01*
G01Y699384D02*
X-1D01*
G01D02*
X8523D01*
G01D02*
X12600D01*
G01X-4725Y699502D02*
X-6694D01*
G01X-3151Y699778D02*
X-2197D01*
G01X-4725Y699935D02*
X-4259D01*
G01X-9844Y700093D02*
X-6694D01*
G01X-1970Y700172D02*
X-1D01*
G01X-6694Y688282D02*
X-4725Y688597D01*
G01X-1Y704325D02*
X24802D01*
G01X-3378Y688361D02*
X-4259Y688124D01*
G01X-3378Y692298D02*
X-4259Y692061D01*
G01X-3378Y696235D02*
X-4259Y695998D01*
G01X-3378Y700172D02*
X-4259Y699935D01*
G01X-6694Y692219D02*
X-4725Y692534D01*
G01X-6694Y696156D02*
X-4725Y696471D01*
G01X-6694Y700093D02*
X-4725Y700408D01*
G01X-9844Y700093D02*
X-10631Y699739D01*
G01X-9844Y696156D02*
X-10631Y695802D01*
G01X-9844Y692219D02*
X-10631Y691865D01*
G01X-9844Y688282D02*
X-10631Y687928D01*
G01X-9056Y710624D02*
Y729916D01*
G01X-1Y710624D02*
Y729916D01*
G01X9842Y713774D02*
X-9056Y712603D01*
G01Y722052D02*
X9842Y721648D01*
G01X14369Y717711D02*
G03I-4527J0D01*
G01X13779D02*
G03I-3937J0D01*
G01X-39607Y868119D02*
Y769693D01*
G01X-38426Y786524D02*
Y784162D01*
G01Y782587D02*
Y780225D01*
G01X-36812Y824091D02*
Y776020D01*
G01X-36192Y785994D02*
Y784660D01*
G01Y782057D02*
Y780723D01*
G01X-35595Y786052D02*
Y784603D01*
G01Y782115D02*
Y780666D01*
G01X-35546Y784598D02*
Y784162D01*
G01Y786524D02*
Y786057D01*
G01Y780661D02*
Y780225D01*
G01Y782587D02*
Y782120D01*
G01X-35331Y786077D02*
Y784579D01*
G01Y782140D02*
Y780642D01*
G01X-34607Y782508D02*
Y780304D01*
G01Y784241D02*
Y786445D01*
G01X-34136Y786089D02*
Y784566D01*
G01Y782152D02*
Y780629D01*
G01X-33702Y777567D02*
Y773630D01*
G01X-33153Y780618D02*
Y782163D01*
G01Y784555D02*
Y786100D01*
G01X-31995Y786113D02*
Y784542D01*
G01Y782176D02*
Y780605D01*
G01X-31725Y786116D02*
Y784539D01*
G01Y782179D02*
Y780602D01*
G01X-39607Y769693D02*
X-1D01*
G01X-39607Y772843D02*
X-27993D01*
G01X-33702Y773630D02*
X-39607D01*
G01Y777567D02*
X-9607D01*
G01X-35351Y780642D02*
X-10631Y780367D01*
G01X-36192Y780723D02*
X-35351Y780642D01*
G01X-36192Y784660D02*
X-35351Y784579D01*
G01X-36192Y782057D02*
X-35341Y782139D01*
G01X-36192Y785994D02*
X-35341Y786076D01*
G01X-35351Y782138D02*
X-10631Y782414D01*
G01X-35351Y786075D02*
X-10631Y786351D01*
G01X-39607Y780225D02*
X-24509D01*
G01X-35546Y780304D02*
X-1D01*
G01X-39607Y782292D02*
X-27993D01*
G01X-35546Y782508D02*
X-1D01*
G01X-24509Y782587D02*
X-39607D01*
G01Y784162D02*
X-24509D01*
G01X-35546Y784241D02*
X-1D01*
G01X-39607Y785441D02*
X-24844D01*
G01X-35546Y786445D02*
X-1D01*
G01X-24509Y786524D02*
X-39607D01*
G01X-35351Y784579D02*
X-10631Y784304D01*
G01X-34603Y777567D02*
X-39607Y774063D01*
G01X-38426Y806209D02*
Y803847D01*
G01Y802272D02*
Y799910D01*
G01Y798335D02*
Y795973D01*
G01Y794398D02*
Y792036D01*
G01Y790461D02*
Y788099D01*
G01X-36192Y805680D02*
Y804345D01*
G01Y797806D02*
Y796471D01*
G01Y801743D02*
Y800408D01*
G01Y793869D02*
Y792534D01*
G01Y789931D02*
Y788597D01*
G01X-35595Y805737D02*
Y804288D01*
G01Y797863D02*
Y796414D01*
G01Y801800D02*
Y800351D01*
G01Y793926D02*
Y792477D01*
G01Y789989D02*
Y788540D01*
G01X-35546Y804283D02*
Y803847D01*
G01Y806209D02*
Y805742D01*
G01Y802272D02*
Y801805D01*
G01Y798335D02*
Y797868D01*
G01Y800346D02*
Y799910D01*
G01Y796409D02*
Y795973D01*
G01Y794398D02*
Y793931D01*
G01Y792472D02*
Y792036D01*
G01Y788535D02*
Y788099D01*
G01Y790461D02*
Y789994D01*
G01X-35331Y805762D02*
Y804264D01*
G01Y797888D02*
Y796390D01*
G01Y801825D02*
Y800327D01*
G01Y793951D02*
Y792453D01*
G01Y790014D02*
Y788516D01*
G01X-34607Y806130D02*
Y803926D01*
G01Y802193D02*
Y799989D01*
G01Y798256D02*
Y796052D01*
G01Y794319D02*
Y792115D01*
G01Y790382D02*
Y788178D01*
G01X-34136Y805774D02*
Y804251D01*
G01Y801837D02*
Y800314D01*
G01Y797900D02*
Y796377D01*
G01Y793963D02*
Y792440D01*
G01Y790026D02*
Y788503D01*
G01X-33153Y788492D02*
Y790037D01*
G01Y792429D02*
Y793974D01*
G01Y796366D02*
Y797911D01*
G01Y800303D02*
Y801848D01*
G01Y804240D02*
Y805785D01*
G01X-31995Y801861D02*
Y800290D01*
G01Y805798D02*
Y804227D01*
G01Y797924D02*
Y796353D01*
G01Y793987D02*
Y792416D01*
G01Y790050D02*
Y788479D01*
G01X-31725Y801864D02*
Y800287D01*
G01Y805801D02*
Y804224D01*
G01Y797927D02*
Y796350D01*
G01Y793990D02*
Y792413D01*
G01Y790053D02*
Y788476D01*
G01X-36192Y788597D02*
X-35351Y788516D01*
G01X-36192Y792534D02*
X-35351Y792453D01*
G01X-36192Y796471D02*
X-35351Y796390D01*
G01X-36192Y800408D02*
X-35351Y800327D01*
G01X-36192Y804345D02*
X-35351Y804264D01*
G01X-36192Y789931D02*
X-35341Y790013D01*
G01X-36192Y793869D02*
X-35341Y793950D01*
G01X-36192Y797806D02*
X-35341Y797887D01*
G01X-35351Y790012D02*
X-10631Y790288D01*
G01X-35351Y793949D02*
X-10631Y794225D01*
G01X-35351Y797886D02*
X-10631Y798162D01*
G01X-35351Y801823D02*
X-10631Y802099D01*
G01X-35351Y805760D02*
X-10631Y806036D01*
G01X-39607Y788099D02*
X-24509D01*
G01X-35546Y788178D02*
X-1D01*
G01X-39607Y790166D02*
X-24844D01*
G01X-35546Y790382D02*
X-1D01*
G01X-24509Y790461D02*
X-39607D01*
G01Y792036D02*
X-24509D01*
G01X-35546Y792115D02*
X-1D01*
G01X-27993Y793315D02*
X-39607D01*
G01X-35546Y794319D02*
X-1D01*
G01X-24509Y794398D02*
X-39607D01*
G01Y795973D02*
X-24509D01*
G01X-35546Y796052D02*
X-1D01*
G01X-35546Y798256D02*
X-1D01*
G01X-24509Y798335D02*
X-39607D01*
G01Y799910D02*
X-24509D01*
G01X-35546Y799989D02*
X-1D01*
G01X-35546Y802193D02*
X-1D01*
G01X-24509Y802272D02*
X-39607D01*
G01Y802764D02*
X-27993D01*
G01X-39607Y803847D02*
X-24509D01*
G01X-35546Y803926D02*
X-1D01*
G01X-39607Y805914D02*
X-24844D01*
G01X-35546Y806130D02*
X-1D01*
G01X-24509Y806209D02*
X-39607D01*
G01X-35351Y788516D02*
X-10631Y788241D01*
G01X-35351Y792453D02*
X-10631Y792178D01*
G01X-35351Y796390D02*
X-10631Y796115D01*
G01X-35351Y800327D02*
X-10631Y800052D01*
G01X-35351Y804264D02*
X-10631Y803989D01*
G01X-36192Y801743D02*
X-35341Y801824D01*
G01X-36192Y805680D02*
X-35341Y805761D01*
G01X-38426Y810146D02*
Y807784D01*
G01X-36192Y809617D02*
Y808282D01*
G01X-35595Y809674D02*
Y808225D01*
G01X-35546Y808220D02*
Y807784D01*
G01Y810146D02*
Y809679D01*
G01X-35331Y809699D02*
Y808201D01*
G01X-34607Y810067D02*
Y807863D01*
G01X-34136Y809711D02*
Y808188D01*
G01X-33153Y808177D02*
Y809722D01*
G01X-31995Y809735D02*
Y808164D01*
G01X-31725Y809738D02*
Y808161D01*
G01X-36192Y808282D02*
X-35351Y808201D01*
G01Y809697D02*
X-10631Y809973D01*
G01X-39607Y807784D02*
X-24509D01*
G01X-35546Y807863D02*
X-1D01*
G01X-35546Y810067D02*
X-1D01*
G01X-24509Y810146D02*
X-39607D01*
G01Y810638D02*
X-24844D01*
G01X-35351Y808201D02*
X-10631Y807926D01*
G01X-36192Y809617D02*
X-35341Y809698D01*
G01X-27993Y785441D02*
Y769693D01*
G01X-27265Y786524D02*
Y784162D01*
G01Y782587D02*
Y780225D01*
G01X-26511Y786174D02*
Y784481D01*
G01Y782237D02*
Y780544D01*
G01X-26242Y780541D02*
Y782240D01*
G01Y784478D02*
Y786177D01*
G01X-24844Y769693D02*
Y785441D01*
G01X-24509Y786524D02*
Y784162D01*
G01Y782587D02*
Y780225D01*
G01X-23998Y786202D02*
Y784453D01*
G01Y782265D02*
Y780516D01*
G01X-23519Y786207D02*
Y784447D01*
G01Y782270D02*
Y780510D01*
G01X-12993Y786760D02*
Y786445D01*
G01Y784241D02*
Y783926D01*
G01Y782823D02*
Y782508D01*
G01Y780304D02*
Y779989D01*
G01X-12445Y786331D02*
Y784324D01*
G01Y782394D02*
Y780387D01*
G01X-11967Y786336D02*
Y784319D01*
G01Y782399D02*
Y780381D01*
G01X-12993Y779989D02*
X-1D01*
G01Y782823D02*
X-12993D01*
G01Y783926D02*
X-1D01*
G01Y786760D02*
X-12993D01*
G01X-27993Y790166D02*
Y805914D01*
G01X-27265Y802272D02*
Y799910D01*
G01Y806209D02*
Y803847D01*
G01Y798335D02*
Y795973D01*
G01Y794398D02*
Y792036D01*
G01Y790461D02*
Y788099D01*
G01X-26511Y805859D02*
Y804166D01*
G01Y801922D02*
Y800229D01*
G01Y797985D02*
Y796292D01*
G01Y794048D02*
Y792355D01*
G01Y790111D02*
Y788418D01*
G01X-26242Y788415D02*
Y790114D01*
G01Y792352D02*
Y794051D01*
G01Y796289D02*
Y797988D01*
G01Y800226D02*
Y801925D01*
G01Y804163D02*
Y805862D01*
G01X-24844Y790166D02*
Y805914D01*
G01X-24509Y806209D02*
Y803847D01*
G01Y802272D02*
Y799910D01*
G01Y798335D02*
Y795973D01*
G01Y790461D02*
Y788099D01*
G01Y794398D02*
Y792036D01*
G01X-23998Y801950D02*
Y800201D01*
G01Y805887D02*
Y804138D01*
G01Y798013D02*
Y796264D01*
G01Y794076D02*
Y792327D01*
G01Y790139D02*
Y788390D01*
G01X-23519Y801956D02*
Y800195D01*
G01Y805893D02*
Y804132D01*
G01Y798019D02*
Y796258D01*
G01Y794081D02*
Y792321D01*
G01Y790144D02*
Y788384D01*
G01X-12993Y802508D02*
Y802193D01*
G01Y803926D02*
Y803611D01*
G01Y806445D02*
Y806130D01*
G01Y798571D02*
Y798256D01*
G01Y799989D02*
Y799674D01*
G01Y794634D02*
Y794319D01*
G01Y796052D02*
Y795737D01*
G01Y788178D02*
Y787863D01*
G01Y790697D02*
Y790382D01*
G01Y792115D02*
Y791800D01*
G01X-12445Y806016D02*
Y804009D01*
G01Y802079D02*
Y800072D01*
G01Y798142D02*
Y796135D01*
G01Y794205D02*
Y792198D01*
G01Y790268D02*
Y788261D01*
G01X-11967Y806021D02*
Y804004D01*
G01Y802084D02*
Y800067D01*
G01Y798147D02*
Y796130D01*
G01Y794210D02*
Y792193D01*
G01Y790273D02*
Y788256D01*
G01X-12993Y787863D02*
X-1D01*
G01Y790697D02*
X-12993D01*
G01Y791800D02*
X-1D01*
G01Y794634D02*
X-12993D01*
G01Y795737D02*
X-1D01*
G01Y798571D02*
X-12993D01*
G01Y799674D02*
X-1D01*
G01Y802508D02*
X-12993D01*
G01Y803611D02*
X-1D01*
G01Y806445D02*
X-12993D01*
G01X-27993Y810638D02*
Y826386D01*
G01X-27265Y810146D02*
Y807784D01*
G01X-26511Y809796D02*
Y808103D01*
G01X-26242Y808100D02*
Y809799D01*
G01X-24844Y810638D02*
Y826386D01*
G01X-24509Y810146D02*
Y807784D01*
G01X-23998Y809824D02*
Y808075D01*
G01X-23519Y809830D02*
Y808069D01*
G01X-12993Y811800D02*
Y811485D01*
G01Y807863D02*
Y807548D01*
G01Y810382D02*
Y810067D01*
G01X-12445Y809953D02*
Y807946D01*
G01X-11967Y809958D02*
Y807941D01*
G01X-12993Y807548D02*
X-1D01*
G01Y810382D02*
X-12993D01*
G01Y811485D02*
X-1D01*
G01Y729916D02*
Y750402D01*
G01X24802Y729916D02*
X-9056D01*
G01X26771Y731884D02*
X-1D01*
G01X-9056Y750402D02*
Y769693D01*
G01X-1Y750402D02*
Y769693D01*
G01Y748433D02*
X26771D01*
G01X-9056Y750402D02*
X24802D01*
G01X-9056Y767331D02*
X9842Y766544D01*
G01Y758670D02*
X-9056Y757882D01*
G01X14369Y762607D02*
G03I-4527J0D01*
G01X13779D02*
G03I-3937J0D01*
G01X-10531Y786396D02*
Y784259D01*
G01Y782459D02*
Y780322D01*
G01X-9607Y777567D02*
Y823374D01*
G01X-6694Y784540D02*
Y783949D01*
G01Y786705D02*
Y786115D01*
G01Y780603D02*
Y780012D01*
G01Y782768D02*
Y782178D01*
G01X-6038Y786760D02*
Y786445D01*
G01Y784241D02*
Y783926D01*
G01Y782823D02*
Y782508D01*
G01Y780304D02*
Y779989D01*
G01X-4725Y782178D02*
Y782823D01*
G01Y779989D02*
Y780603D01*
G01Y786115D02*
Y786760D01*
G01Y783926D02*
Y784540D01*
G01X-3757Y786445D02*
Y784241D01*
G01Y782508D02*
Y780304D01*
G01X-2197Y780327D02*
X-2001Y779989D01*
G01X-3151Y782453D02*
X-3364Y782823D01*
G01X-2197Y784264D02*
X-2001Y783926D01*
G01X-3151Y786390D02*
X-3364Y786760D01*
G01X-2521Y786445D02*
Y784241D01*
G01Y782508D02*
Y780304D01*
G01X-2251Y786760D02*
Y783926D01*
G01Y782823D02*
Y779989D01*
G01X-985Y785996D02*
Y784658D01*
G01Y782059D02*
Y780721D01*
G01X-1Y769693D02*
Y868119D01*
G01X196Y785996D02*
Y784658D01*
G01Y782059D02*
Y780721D01*
G01X8385Y779113D02*
Y780688D01*
G01Y782459D02*
Y782853D01*
G01X8787Y780754D02*
Y779507D01*
G01X8385Y780688D02*
X8452Y781016D01*
G01X8854Y782066D02*
X8385Y782459D01*
G01X8854Y780950D02*
X8787Y780754D01*
G01X-10631Y780367D02*
X-9844Y780012D01*
G01X-10631Y784304D02*
X-9844Y783949D01*
G01X-1983Y786760D02*
X-2197Y786390D01*
G01X-3346Y783926D02*
X-3151Y784264D01*
G01X-1983Y782823D02*
X-2197Y782453D01*
G01X-3346Y779989D02*
X-3151Y780327D01*
G01X-6545Y779989D02*
X-6694Y780012D01*
G01X-4259Y780170D02*
X-3582Y779989D01*
G01X-4259Y784107D02*
X-3582Y783926D01*
G01X8452Y781016D02*
X8653Y781278D01*
G01X24802Y775993D02*
X-1D01*
G01X-6545Y783926D02*
X-6694Y783949D01*
G01X11534Y779113D02*
X8385D01*
G01X8787Y779507D02*
X9725D01*
G01X-9844Y780012D02*
X-6694D01*
G01X-4725Y780170D02*
X-4259D01*
G01X-3151Y780327D02*
X-2197D01*
G01X-4725Y780603D02*
X-6694D01*
G01X9000Y780721D02*
X-1D01*
G01D02*
X-985D01*
G01X-1Y782059D02*
X9000D01*
G01X-985D02*
X-1D01*
G01X-4725Y782178D02*
X-6694D01*
G01X-3151Y782453D02*
X-2197D01*
G01X-4259Y782611D02*
X-4725D01*
G01X-6694Y782768D02*
X-9844D01*
G01X8385Y782853D02*
X11534D01*
G01X-9844Y783949D02*
X-6694D01*
G01X-4725Y784107D02*
X-4259D01*
G01X-3151Y784264D02*
X-2197D01*
G01X-4725Y784540D02*
X-6694D01*
G01X9000Y784658D02*
X-1D01*
G01D02*
X-985D01*
G01X-1Y785996D02*
X9000D01*
G01X-985D02*
X-1D01*
G01X-4725Y786115D02*
X-6694D01*
G01X-3151Y786390D02*
X-2197D01*
G01X-4259Y786548D02*
X-4725D01*
G01X-6694Y786705D02*
X-9844D01*
G01X8653Y781278D02*
X8921Y781475D01*
G01X-3467Y782823D02*
X-4259Y782611D01*
G01X-3467Y786760D02*
X-4259Y786548D01*
G01X-6351Y782823D02*
X-6694Y782768D01*
G01X-6351Y786760D02*
X-6694Y786705D01*
G01X-10631Y786351D02*
X-9844Y786705D01*
G01X-10631Y782414D02*
X-9844Y782768D01*
G01X-10531Y802144D02*
Y800007D01*
G01Y806081D02*
Y803944D01*
G01Y798207D02*
Y796070D01*
G01Y794270D02*
Y792133D01*
G01Y790333D02*
Y788196D01*
G01X-6694Y802453D02*
Y801863D01*
G01Y806390D02*
Y805800D01*
G01Y804225D02*
Y803634D01*
G01Y798516D02*
Y797926D01*
G01Y800288D02*
Y799697D01*
G01Y794579D02*
Y793989D01*
G01Y796351D02*
Y795760D01*
G01Y790642D02*
Y790052D01*
G01Y788477D02*
Y787886D01*
G01Y792414D02*
Y791823D01*
G01X-6038Y802508D02*
Y802193D01*
G01Y803926D02*
Y803611D01*
G01Y806445D02*
Y806130D01*
G01Y798571D02*
Y798256D01*
G01Y799989D02*
Y799674D01*
G01Y794634D02*
Y794319D01*
G01Y796052D02*
Y795737D01*
G01Y788178D02*
Y787863D01*
G01Y790697D02*
Y790382D01*
G01Y792115D02*
Y791800D01*
G01X-4725Y787863D02*
Y788477D01*
G01Y790052D02*
Y790697D01*
G01Y791800D02*
Y792414D01*
G01Y793989D02*
Y794634D01*
G01Y795737D02*
Y796351D01*
G01Y797926D02*
Y798571D01*
G01Y799674D02*
Y800288D01*
G01Y801863D02*
Y802508D01*
G01Y803611D02*
Y804225D01*
G01Y805800D02*
Y806445D01*
G01X-3757Y806130D02*
Y803926D01*
G01Y802193D02*
Y799989D01*
G01Y798256D02*
Y796052D01*
G01Y794319D02*
Y792115D01*
G01Y790382D02*
Y788178D01*
G01X-2197Y788201D02*
X-2001Y787863D01*
G01X-3151Y790327D02*
X-3364Y790697D01*
G01X-2197Y792138D02*
X-2001Y791800D01*
G01X-3151Y794264D02*
X-3364Y794634D01*
G01X-2197Y796075D02*
X-2001Y795737D01*
G01X-3151Y798201D02*
X-3364Y798571D01*
G01X-2197Y800012D02*
X-2001Y799674D01*
G01X-3151Y802138D02*
X-3364Y802508D01*
G01X-2197Y803949D02*
X-2001Y803611D01*
G01X-3151Y806075D02*
X-3364Y806445D01*
G01X-2521Y806130D02*
Y803926D01*
G01Y802193D02*
Y799989D01*
G01Y798256D02*
Y796052D01*
G01Y794319D02*
Y792115D01*
G01Y790382D02*
Y788178D01*
G01X-2251Y806445D02*
Y803611D01*
G01Y802508D02*
Y799674D01*
G01Y798571D02*
Y795737D01*
G01Y790697D02*
Y787863D01*
G01Y794634D02*
Y791800D01*
G01X-985Y805681D02*
Y804343D01*
G01Y801744D02*
Y800406D01*
G01Y797807D02*
Y796469D01*
G01Y793870D02*
Y792532D01*
G01Y789933D02*
Y788595D01*
G01X196Y805681D02*
Y804343D01*
G01Y801744D02*
Y800406D01*
G01Y797807D02*
Y796469D01*
G01Y793870D02*
Y792532D01*
G01Y789933D02*
Y788595D01*
G01X-10631Y788241D02*
X-9844Y787886D01*
G01X-10631Y792178D02*
X-9844Y791823D01*
G01X-10631Y796115D02*
X-9844Y795760D01*
G01X-10631Y800052D02*
X-9844Y799697D01*
G01X-10631Y803989D02*
X-9844Y803634D01*
G01X-1983Y806445D02*
X-2197Y806075D01*
G01X-3346Y803611D02*
X-3151Y803949D01*
G01X-1983Y802508D02*
X-2197Y802138D01*
G01X-3346Y799674D02*
X-3151Y800012D01*
G01X-1983Y798571D02*
X-2197Y798201D01*
G01X-3346Y795737D02*
X-3151Y796075D01*
G01X-1983Y794634D02*
X-2197Y794264D01*
G01X-3346Y791800D02*
X-3151Y792138D01*
G01X-1983Y790697D02*
X-2197Y790327D01*
G01X-3346Y787863D02*
X-3151Y788201D01*
G01X-4259Y788044D02*
X-3582Y787863D01*
G01X-4259Y791981D02*
X-3582Y791800D01*
G01X-4259Y795918D02*
X-3582Y795737D01*
G01X-4259Y799855D02*
X-3582Y799674D01*
G01X-4259Y803792D02*
X-3582Y803611D01*
G01X-6545Y787863D02*
X-6694Y787886D01*
G01X-6545Y791800D02*
X-6694Y791823D01*
G01X-6545Y795737D02*
X-6694Y795760D01*
G01X-6545Y799674D02*
X-6694Y799697D01*
G01X-6545Y803611D02*
X-6694Y803634D01*
G01X-9844Y787886D02*
X-6694D01*
G01X-4725Y788044D02*
X-4259D01*
G01X-3151Y788201D02*
X-2197D01*
G01X-4725Y788477D02*
X-6694D01*
G01X9000Y788595D02*
X-1D01*
G01D02*
X-985D01*
G01X-1Y789933D02*
X9000D01*
G01X-985D02*
X-1D01*
G01X-4725Y790052D02*
X-6694D01*
G01X-3151Y790327D02*
X-2197D01*
G01X-4259Y790485D02*
X-4725D01*
G01X-6694Y790642D02*
X-9844D01*
G01Y791823D02*
X-6694D01*
G01X-4725Y791981D02*
X-4259D01*
G01X-3151Y792138D02*
X-2197D01*
G01X-4725Y792414D02*
X-6694D01*
G01X9000Y792532D02*
X-1D01*
G01D02*
X-985D01*
G01X-1Y793870D02*
X9000D01*
G01X-985D02*
X-1D01*
G01X-4725Y793989D02*
X-6694D01*
G01X-3151Y794264D02*
X-2197D01*
G01X-4259Y794422D02*
X-4725D01*
G01X-6694Y794579D02*
X-9844D01*
G01Y795760D02*
X-6694D01*
G01X-4725Y795918D02*
X-4259D01*
G01X-3151Y796075D02*
X-2197D01*
G01X-4725Y796351D02*
X-6694D01*
G01X9000Y796469D02*
X-1D01*
G01D02*
X-985D01*
G01X-1Y797807D02*
X9000D01*
G01X-985D02*
X-1D01*
G01X-4725Y797926D02*
X-6694D01*
G01X-3151Y798201D02*
X-2197D01*
G01X-4259Y798359D02*
X-4725D01*
G01X-6694Y798516D02*
X-9844D01*
G01Y799697D02*
X-6694D01*
G01X-4725Y799855D02*
X-4259D01*
G01X-3151Y800012D02*
X-2197D01*
G01X-4725Y800288D02*
X-6694D01*
G01X9000Y800406D02*
X-1D01*
G01D02*
X-985D01*
G01X-1Y801744D02*
X9000D01*
G01X-985D02*
X-1D01*
G01X-4725Y801863D02*
X-6694D01*
G01X-3151Y802138D02*
X-2197D01*
G01X-4259Y802296D02*
X-4725D01*
G01X-6694Y802453D02*
X-9844D01*
G01Y803634D02*
X-6694D01*
G01X-4725Y803792D02*
X-4259D01*
G01X-3151Y803949D02*
X-2197D01*
G01X-4725Y804225D02*
X-6694D01*
G01X9000Y804343D02*
X-1D01*
G01D02*
X-985D01*
G01X-1Y805681D02*
X9000D01*
G01X-985D02*
X-1D01*
G01X-4725Y805800D02*
X-6694D01*
G01X-3151Y806075D02*
X-2197D01*
G01X-4259Y806233D02*
X-4725D01*
G01X-6694Y806390D02*
X-9844D01*
G01X-6351Y790697D02*
X-6694Y790642D01*
G01X-6351Y794634D02*
X-6694Y794579D01*
G01X-6351Y798571D02*
X-6694Y798516D01*
G01X-6351Y802508D02*
X-6694Y802453D01*
G01X-6351Y806445D02*
X-6694Y806390D01*
G01X-10631Y806036D02*
X-9844Y806390D01*
G01X-10631Y802099D02*
X-9844Y802453D01*
G01X-10631Y798162D02*
X-9844Y798516D01*
G01X-10631Y794225D02*
X-9844Y794579D01*
G01X-10631Y790288D02*
X-9844Y790642D01*
G01X-3467Y790697D02*
X-4259Y790485D01*
G01X-3467Y794634D02*
X-4259Y794422D01*
G01X-3467Y798571D02*
X-4259Y798359D01*
G01X-3467Y802508D02*
X-4259Y802296D01*
G01X-3467Y806445D02*
X-4259Y806233D01*
G01X-10531Y810018D02*
Y807881D01*
G01X-6694Y812099D02*
Y811508D01*
G01Y810327D02*
Y809737D01*
G01Y808162D02*
Y807571D01*
G01X-6038Y811800D02*
Y811485D01*
G01Y807863D02*
Y807548D01*
G01Y810382D02*
Y810067D01*
G01X-4725Y807548D02*
Y808162D01*
G01Y809737D02*
Y810382D01*
G01Y811485D02*
Y812099D01*
G01X-3757Y810067D02*
Y807863D01*
G01X-2197Y807886D02*
X-2001Y807548D01*
G01X-3151Y810012D02*
X-3364Y810382D01*
G01X-2197Y811823D02*
X-2001Y811485D01*
G01X-2521Y810067D02*
Y807863D01*
G01X-2251Y814319D02*
Y811485D01*
G01Y810382D02*
Y807548D01*
G01X-985Y809619D02*
Y808280D01*
G01X196Y809619D02*
Y808280D01*
G01X-10631Y807926D02*
X-9844Y807571D01*
G01X-10631Y811863D02*
X-9844Y811508D01*
G01X-3346Y811485D02*
X-3151Y811823D01*
G01X-1983Y810382D02*
X-2197Y810012D01*
G01X-3346Y807548D02*
X-3151Y807886D01*
G01X-4259Y807729D02*
X-3582Y807548D01*
G01X-4259Y811666D02*
X-3582Y811485D01*
G01X-6545Y807548D02*
X-6694Y807571D01*
G01X-6545Y811485D02*
X-6694Y811508D01*
G01X-9844Y807571D02*
X-6694D01*
G01X-4725Y807729D02*
X-4259D01*
G01X-3151Y807886D02*
X-2197D01*
G01X-4725Y808162D02*
X-6694D01*
G01X9000Y808280D02*
X-1D01*
G01D02*
X-985D01*
G01X-1Y809619D02*
X9000D01*
G01X-985D02*
X-1D01*
G01X-4725Y809737D02*
X-6694D01*
G01X-3151Y810012D02*
X-2197D01*
G01X-4259Y810170D02*
X-4725D01*
G01X-6694Y810327D02*
X-9844D01*
G01Y811508D02*
X-6694D01*
G01X-4725Y811666D02*
X-4259D01*
G01X-6351Y810382D02*
X-6694Y810327D01*
G01X-10631Y809973D02*
X-9844Y810327D01*
G01X-3467Y810382D02*
X-4259Y810170D01*
G01X11267Y781278D02*
X11468Y781016D01*
G01X9859Y781278D02*
X9926Y781147D01*
G01X9725Y780754D02*
X9658Y780950D01*
G01X11066D02*
X11132Y780754D01*
G01X11468Y781016D02*
X11534Y780688D01*
G01X9000Y785996D02*
Y784658D01*
G01Y782059D02*
Y780721D01*
G01X9725Y779507D02*
Y780754D01*
G01X10127Y779507D02*
Y780754D01*
G01X11132D02*
Y779507D01*
G01X11534Y780688D02*
Y779113D01*
G01Y782853D02*
Y782459D01*
G01X9591Y781475D02*
X9859Y781278D01*
G01X10999Y781475D02*
X11267Y781278D01*
G01X8921Y782459D02*
X9390Y782066D01*
G01X9658Y780950D02*
X9524Y781081D01*
G01X10931D02*
X11066Y780950D01*
G01X10127Y780754D02*
X10194Y780950D01*
G01X9926Y781147D02*
X9993Y781278D01*
G01X9524Y781081D02*
X9323Y781147D01*
G01X9390Y781541D02*
X9591Y781475D01*
G01X10730Y781147D02*
X10931Y781081D01*
G01X10797Y781541D02*
X10999Y781475D01*
G01X8988Y781081D02*
X8854Y780950D01*
G01X10194D02*
X10329Y781081D01*
G01X11132Y779507D02*
X10127D01*
G01X12829Y780721D02*
X9000D01*
G01X9323Y781147D02*
X9189D01*
G01X10529D02*
X10730D01*
G01X9122Y781541D02*
X9390D01*
G01X10462D02*
X10797D01*
G01X9000Y782059D02*
X12829D01*
G01X9390Y782066D02*
X8854D01*
G01X11534Y782459D02*
X8921D01*
G01X12829Y784658D02*
X9000D01*
G01Y785996D02*
X12829D01*
G01X9993Y781278D02*
X10261Y781475D01*
G01X8921D02*
X9122Y781541D01*
G01X9189Y781147D02*
X8988Y781081D01*
G01X10261Y781475D02*
X10462Y781541D01*
G01X10329Y781081D02*
X10529Y781147D01*
G01X9000Y805681D02*
Y804343D01*
G01Y801744D02*
Y800406D01*
G01Y797807D02*
Y796469D01*
G01Y793870D02*
Y792532D01*
G01Y789933D02*
Y788595D01*
G01X12829D02*
X9000D01*
G01Y789933D02*
X12829D01*
G01Y792532D02*
X9000D01*
G01Y793870D02*
X12829D01*
G01Y796469D02*
X9000D01*
G01Y797807D02*
X12829D01*
G01Y800406D02*
X9000D01*
G01Y801744D02*
X12829D01*
G01Y804343D02*
X9000D01*
G01Y805681D02*
X12829D01*
G01X9000Y809619D02*
Y808280D01*
G01X12829D02*
X9000D01*
G01Y809619D02*
X12829D01*
G01X-38426Y821957D02*
Y819595D01*
G01Y818020D02*
Y815658D01*
G01Y814083D02*
Y811721D01*
G01X-36192Y821428D02*
Y820093D01*
G01Y817491D02*
Y816156D01*
G01Y813554D02*
Y812219D01*
G01X-35595Y821485D02*
Y820036D01*
G01Y817548D02*
Y816099D01*
G01Y813611D02*
Y812162D01*
G01X-35546Y821957D02*
Y821490D01*
G01Y820031D02*
Y819595D01*
G01Y818020D02*
Y817553D01*
G01Y812157D02*
Y811721D01*
G01Y814083D02*
Y813616D01*
G01Y816094D02*
Y815658D01*
G01X-35434Y824181D02*
Y829181D01*
G01X-35331Y821510D02*
Y820012D01*
G01Y817573D02*
Y816075D01*
G01Y813636D02*
Y812138D01*
G01X-34607Y821878D02*
Y819674D01*
G01Y817941D02*
Y815737D01*
G01Y814004D02*
Y811800D01*
G01X-34136Y821522D02*
Y819999D01*
G01Y817585D02*
Y816062D01*
G01Y813648D02*
Y812125D01*
G01X-33153Y812114D02*
Y813659D01*
G01Y816051D02*
Y817596D01*
G01Y819988D02*
Y821533D01*
G01X-31995Y821546D02*
Y819975D01*
G01Y817609D02*
Y816038D01*
G01Y813672D02*
Y812101D01*
G01X-31725Y821549D02*
Y819972D01*
G01Y817612D02*
Y816035D01*
G01Y813675D02*
Y812098D01*
G01X-36561Y823915D02*
X-39020Y825637D01*
G01X-36192Y812219D02*
X-35351Y812138D01*
G01X-36192Y816156D02*
X-35351Y816075D01*
G01X-36192Y820093D02*
X-35351Y820012D01*
G01Y813634D02*
X-10631Y813910D01*
G01X-35351Y817571D02*
X-10631Y817847D01*
G01X-35351Y821508D02*
X-10631Y821784D01*
G01X-39607Y811721D02*
X-24509D01*
G01X-35546Y811800D02*
X-1D01*
G01X-27993Y813788D02*
X-39607D01*
G01X-35546Y814004D02*
X-1D01*
G01X-24509Y814083D02*
X-39607D01*
G01Y815658D02*
X-24509D01*
G01X-35546Y815737D02*
X-1D01*
G01X-35546Y817941D02*
X-1D01*
G01X-24509Y818020D02*
X-39607D01*
G01Y819595D02*
X-24509D01*
G01X-35546Y819674D02*
X-1D01*
G01X-35546Y821878D02*
X-1D01*
G01X-24509Y821957D02*
X-39607D01*
G01Y823237D02*
X-27993D01*
G01X-9607Y823374D02*
X-34845D01*
G01X-1Y824181D02*
X-35434D01*
G01X-39607Y826386D02*
X-24844D01*
G01X-35351Y812138D02*
X-10631Y811863D01*
G01X-35351Y816075D02*
X-10631Y815800D01*
G01X-35351Y820012D02*
X-10631Y819737D01*
G01X-36192Y813554D02*
X-35341Y813635D01*
G01X-36192Y817491D02*
X-35341Y817572D01*
G01X-36192Y821428D02*
X-35341Y821509D01*
G01X-36561Y823915D02*
G03X-34845Y823374I1716J2451D01*
G01X-39020Y827923D02*
G03X-39607Y826794I791J-1128D01*
G01Y826766D02*
G03X-39020Y825637I1378J-1D01*
G01X-38426Y845579D02*
Y843217D01*
G01Y841642D02*
Y839280D01*
G01Y837705D02*
Y835343D01*
G01Y833768D02*
Y831406D01*
G01X-36812Y861020D02*
Y829469D01*
G01X-36192Y845050D02*
Y843715D01*
G01Y841113D02*
Y839778D01*
G01Y837176D02*
Y835841D01*
G01Y833239D02*
Y831904D01*
G01X-35595Y845107D02*
Y843658D01*
G01Y841170D02*
Y839721D01*
G01Y837233D02*
Y835784D01*
G01Y833296D02*
Y831847D01*
G01X-35546Y845579D02*
Y845112D01*
G01Y843653D02*
Y843217D01*
G01Y839716D02*
Y839280D01*
G01Y841642D02*
Y841175D01*
G01Y835779D02*
Y835343D01*
G01Y837705D02*
Y837238D01*
G01Y831842D02*
Y831406D01*
G01Y833768D02*
Y833301D01*
G01X-35331Y845132D02*
Y843634D01*
G01Y841195D02*
Y839697D01*
G01Y837258D02*
Y835760D01*
G01Y833321D02*
Y831823D01*
G01X-34607Y841563D02*
Y839359D01*
G01Y845500D02*
Y843296D01*
G01Y837626D02*
Y835422D01*
G01Y831485D02*
Y833689D01*
G01X-34136Y845144D02*
Y843621D01*
G01Y841207D02*
Y839684D01*
G01Y837270D02*
Y835747D01*
G01Y833333D02*
Y831810D01*
G01X-33153Y831799D02*
Y833344D01*
G01Y835736D02*
Y837281D01*
G01Y839673D02*
Y841218D01*
G01Y843610D02*
Y845155D01*
G01X-31995Y845168D02*
Y843597D01*
G01Y841231D02*
Y839660D01*
G01Y837294D02*
Y835723D01*
G01Y833357D02*
Y831786D01*
G01X-31725Y845171D02*
Y843594D01*
G01Y841234D02*
Y839657D01*
G01Y837297D02*
Y835720D01*
G01Y833360D02*
Y831783D01*
G01X-39020Y827923D02*
X-36561Y829644D01*
G01X-35351Y833319D02*
X-10631Y833595D01*
G01X-35351Y837256D02*
X-10631Y837532D01*
G01X-35351Y841193D02*
X-10631Y841469D01*
G01X-35351Y845130D02*
X-10631Y845406D01*
G01X-35434Y829181D02*
X-1D01*
G01X-34845Y830185D02*
X-9607D01*
G01X-39607Y831111D02*
X-24844D01*
G01X-39607Y831406D02*
X-24509D01*
G01X-35546Y831485D02*
X-1D01*
G01X-35546Y833689D02*
X-1D01*
G01X-24509Y833768D02*
X-39607D01*
G01X-27993Y834260D02*
X-39607D01*
G01Y835343D02*
X-24509D01*
G01X-35546Y835422D02*
X-1D01*
G01X-35546Y837626D02*
X-1D01*
G01X-24509Y837705D02*
X-39607D01*
G01Y839280D02*
X-24509D01*
G01X-35546Y839359D02*
X-1D01*
G01X-35546Y841563D02*
X-1D01*
G01X-24509Y841642D02*
X-39607D01*
G01Y843217D02*
X-24509D01*
G01X-35546Y843296D02*
X-1D01*
G01X-39607Y843709D02*
X-27993D01*
G01X-35546Y845500D02*
X-1D01*
G01X-24509Y845579D02*
X-39607D01*
G01Y846859D02*
X-24844D01*
G01X-35351Y831823D02*
X-10631Y831548D01*
G01X-35351Y835760D02*
X-10631Y835485D01*
G01X-35351Y839697D02*
X-10631Y839422D01*
G01X-35351Y843634D02*
X-10631Y843359D01*
G01X-36192Y831904D02*
X-35351Y831823D01*
G01X-36192Y835841D02*
X-35351Y835760D01*
G01X-36192Y839778D02*
X-35351Y839697D01*
G01X-36192Y843715D02*
X-35351Y843634D01*
G01X-36192Y833239D02*
X-35341Y833320D01*
G01X-36192Y837176D02*
X-35341Y837257D01*
G01X-36192Y841113D02*
X-35341Y841194D01*
G01X-36192Y845050D02*
X-35341Y845131D01*
G01X-34845Y830185D02*
G03X-36561Y829644I0J-2992D01*
G01X-38426Y857390D02*
Y855028D01*
G01Y849516D02*
Y847154D01*
G01Y853453D02*
Y851091D01*
G01X-36192Y856861D02*
Y855526D01*
G01Y848987D02*
Y847652D01*
G01Y852924D02*
Y851589D01*
G01X-35595Y856918D02*
Y855469D01*
G01Y849044D02*
Y847595D01*
G01Y852981D02*
Y851532D01*
G01X-35546Y853453D02*
Y852986D01*
G01Y855464D02*
Y855028D01*
G01Y857390D02*
Y856923D01*
G01Y849516D02*
Y849049D01*
G01Y851527D02*
Y851091D01*
G01Y847590D02*
Y847154D01*
G01X-35331Y856943D02*
Y855445D01*
G01Y853006D02*
Y851508D01*
G01Y849069D02*
Y847571D01*
G01X-34607Y857311D02*
Y855107D01*
G01Y853374D02*
Y851170D01*
G01Y849437D02*
Y847233D01*
G01X-34136Y856955D02*
Y855432D01*
G01Y849081D02*
Y847558D01*
G01Y853018D02*
Y851495D01*
G01X-33153Y851484D02*
Y853029D01*
G01Y847547D02*
Y849092D01*
G01Y855421D02*
Y856966D01*
G01X-31995Y856979D02*
Y855408D01*
G01Y853042D02*
Y851471D01*
G01Y849105D02*
Y847534D01*
G01X-31725Y856982D02*
Y855405D01*
G01Y853045D02*
Y851468D01*
G01Y849108D02*
Y847531D01*
G01X-39607Y862978D02*
X-36561Y860844D01*
G01X-39607Y847154D02*
X-24509D01*
G01X-35546Y847233D02*
X-1D01*
G01X-35546Y849437D02*
X-1D01*
G01X-24509Y849516D02*
X-39607D01*
G01Y851091D02*
X-24509D01*
G01X-35546Y851170D02*
X-1D01*
G01X-39607Y851583D02*
X-24844D01*
G01X-35546Y853374D02*
X-1D01*
G01X-24509Y853453D02*
X-39607D01*
G01X-35351Y847571D02*
X-10631Y847296D01*
G01X-35351Y851508D02*
X-10631Y851233D01*
G01X-35351Y855445D02*
X-10631Y855170D01*
G01X-36192Y847652D02*
X-35351Y847571D01*
G01X-36192Y851589D02*
X-35351Y851508D01*
G01X-36192Y855526D02*
X-35351Y855445D01*
G01X-36192Y848987D02*
X-35341Y849069D01*
G01X-36192Y852924D02*
X-35341Y853006D01*
G01X-36192Y856861D02*
X-35341Y856943D01*
G01X-35351Y849067D02*
X-10631Y849343D01*
G01X-35351Y853004D02*
X-10631Y853280D01*
G01X-35351Y856941D02*
X-10631Y857217D01*
G01X-27993Y854733D02*
X-39607D01*
G01Y855028D02*
X-24509D01*
G01X-35546Y855107D02*
X-1D01*
G01X-35546Y857311D02*
X-1D01*
G01X-24509Y857390D02*
X-39607D01*
G01X-9607Y860304D02*
X-34845D01*
G01X-27993Y864969D02*
X-39607D01*
G01X-36561Y860844D02*
G03X-34845Y860304I1715J2452D01*
G01X-39607Y868119D02*
X-1D01*
G01X-27265Y821957D02*
Y819595D01*
G01Y818020D02*
Y815658D01*
G01Y814083D02*
Y811721D01*
G01X-26511Y821607D02*
Y819914D01*
G01Y817670D02*
Y815977D01*
G01Y813733D02*
Y812040D01*
G01X-26242Y812037D02*
Y813736D01*
G01Y815974D02*
Y817673D01*
G01Y819911D02*
Y821610D01*
G01X-24509Y821957D02*
Y819595D01*
G01Y818020D02*
Y815658D01*
G01Y814083D02*
Y811721D01*
G01X-23998Y821635D02*
Y819886D01*
G01Y817698D02*
Y815949D01*
G01Y813761D02*
Y812012D01*
G01X-23519Y821641D02*
Y819880D01*
G01Y817704D02*
Y815943D01*
G01Y813767D02*
Y812006D01*
G01X-12993Y822193D02*
Y821878D01*
G01Y819674D02*
Y819359D01*
G01Y818256D02*
Y817941D01*
G01Y815737D02*
Y815422D01*
G01Y814319D02*
Y814004D01*
G01X-12445Y821764D02*
Y819757D01*
G01Y817827D02*
Y815820D01*
G01Y813890D02*
Y811883D01*
G01X-11967Y821769D02*
Y819752D01*
G01Y817832D02*
Y815815D01*
G01Y813895D02*
Y811878D01*
G01X-1Y814319D02*
X-12993D01*
G01Y815422D02*
X-1D01*
G01Y818256D02*
X-12993D01*
G01Y819359D02*
X-1D01*
G01Y822193D02*
X-12993D01*
G01X-27993Y831111D02*
Y846859D01*
G01X-27265Y845579D02*
Y843217D01*
G01Y841642D02*
Y839280D01*
G01Y837705D02*
Y835343D01*
G01Y833768D02*
Y831406D01*
G01X-26511Y845229D02*
Y843536D01*
G01Y841292D02*
Y839599D01*
G01Y837355D02*
Y835662D01*
G01Y833418D02*
Y831725D01*
G01X-26242Y831722D02*
Y833421D01*
G01Y835659D02*
Y837358D01*
G01Y839596D02*
Y841295D01*
G01Y843533D02*
Y845232D01*
G01X-24844Y831111D02*
Y846859D01*
G01X-24509Y845579D02*
Y843217D01*
G01Y841642D02*
Y839280D01*
G01Y837705D02*
Y835343D01*
G01Y833768D02*
Y831406D01*
G01X-23998Y845257D02*
Y843508D01*
G01Y841320D02*
Y839571D01*
G01Y837383D02*
Y835634D01*
G01Y833446D02*
Y831697D01*
G01X-23519Y845263D02*
Y843502D01*
G01Y841326D02*
Y839565D01*
G01Y837389D02*
Y835628D01*
G01Y833452D02*
Y831691D01*
G01X-12993Y847233D02*
Y846918D01*
G01Y845815D02*
Y845500D01*
G01Y843296D02*
Y842981D01*
G01Y839359D02*
Y839044D01*
G01Y841878D02*
Y841563D01*
G01Y835422D02*
Y835107D01*
G01Y837941D02*
Y837626D01*
G01Y834004D02*
Y833689D01*
G01Y831485D02*
Y831170D01*
G01X-12445Y845386D02*
Y843379D01*
G01Y841449D02*
Y839442D01*
G01Y837512D02*
Y835505D01*
G01Y833575D02*
Y831568D01*
G01X-11967Y845391D02*
Y843374D01*
G01Y841454D02*
Y839437D01*
G01Y837517D02*
Y835500D01*
G01Y833580D02*
Y831563D01*
G01X-12993Y831170D02*
X-1D01*
G01Y834004D02*
X-12993D01*
G01Y835107D02*
X-1D01*
G01Y837941D02*
X-12993D01*
G01Y839044D02*
X-1D01*
G01Y841878D02*
X-12993D01*
G01Y842981D02*
X-1D01*
G01Y845815D02*
X-12993D01*
G01Y846918D02*
X-1D01*
G01X-27993Y851583D02*
Y868119D01*
G01X-27265Y857390D02*
Y855028D01*
G01Y853453D02*
Y851091D01*
G01Y849516D02*
Y847154D01*
G01X-26511Y857040D02*
Y855347D01*
G01Y849166D02*
Y847473D01*
G01Y853103D02*
Y851410D01*
G01X-26242Y851407D02*
Y853106D01*
G01Y847470D02*
Y849169D01*
G01Y855344D02*
Y857043D01*
G01X-24844Y851583D02*
Y868119D01*
G01X-24509Y857390D02*
Y855028D01*
G01Y853453D02*
Y851091D01*
G01Y849516D02*
Y847154D01*
G01X-23998Y857068D02*
Y855319D01*
G01Y853131D02*
Y851382D01*
G01Y849194D02*
Y847445D01*
G01X-23519Y857074D02*
Y855313D01*
G01Y853137D02*
Y851376D01*
G01Y849200D02*
Y847439D01*
G01X-12993Y855107D02*
Y854792D01*
G01Y857626D02*
Y857311D01*
G01Y853689D02*
Y853374D01*
G01Y851170D02*
Y850855D01*
G01Y849752D02*
Y849437D01*
G01X-12445Y857197D02*
Y855190D01*
G01Y849323D02*
Y847316D01*
G01Y853260D02*
Y851253D01*
G01X-11967Y857202D02*
Y855185D01*
G01Y849328D02*
Y847311D01*
G01Y853265D02*
Y851248D01*
G01X-1Y849752D02*
X-12993D01*
G01Y850855D02*
X-1D01*
G01Y853689D02*
X-12993D01*
G01Y854792D02*
X-1D01*
G01Y857626D02*
X-12993D01*
G01X-10531Y821829D02*
Y819692D01*
G01Y817892D02*
Y815755D01*
G01Y813955D02*
Y811818D01*
G01X-6694Y822138D02*
Y821548D01*
G01Y819973D02*
Y819382D01*
G01Y816036D02*
Y815445D01*
G01Y818201D02*
Y817611D01*
G01Y814264D02*
Y813674D01*
G01X-6038Y822193D02*
Y821878D01*
G01Y819674D02*
Y819359D01*
G01Y818256D02*
Y817941D01*
G01Y815737D02*
Y815422D01*
G01Y814319D02*
Y814004D01*
G01X-4725Y815422D02*
Y816036D01*
G01Y813674D02*
Y814319D01*
G01Y819359D02*
Y819973D01*
G01Y817611D02*
Y818256D01*
G01Y821548D02*
Y822193D01*
G01X-3757Y821878D02*
Y819674D01*
G01Y817941D02*
Y815737D01*
G01Y814004D02*
Y811800D01*
G01X-3151Y813949D02*
X-3364Y814319D01*
G01X-2197Y815760D02*
X-2001Y815422D01*
G01X-3151Y817886D02*
X-3364Y818256D01*
G01X-2197Y819697D02*
X-2001Y819359D01*
G01X-3151Y821823D02*
X-3364Y822193D01*
G01X-2521Y821878D02*
Y819674D01*
G01Y817941D02*
Y815737D01*
G01Y814004D02*
Y811800D01*
G01X-2251Y822193D02*
Y819359D01*
G01Y818256D02*
Y815422D01*
G01X-985Y821430D02*
Y820091D01*
G01Y817493D02*
Y816154D01*
G01Y813556D02*
Y812217D01*
G01X196Y821430D02*
Y820091D01*
G01Y817493D02*
Y816154D01*
G01Y813556D02*
Y812217D01*
G01X-10631Y815800D02*
X-9844Y815445D01*
G01X-10631Y819737D02*
X-9844Y819382D01*
G01X-1983Y822193D02*
X-2197Y821823D01*
G01X-3346Y819359D02*
X-3151Y819697D01*
G01X-1983Y818256D02*
X-2197Y817886D01*
G01X-3346Y815422D02*
X-3151Y815760D01*
G01X-1983Y814319D02*
X-2197Y813949D01*
G01X-4259Y815603D02*
X-3582Y815422D01*
G01X-4259Y819540D02*
X-3582Y819359D01*
G01X1968Y823031D02*
X281Y821345D01*
G01X-1Y821063D02*
X281Y821345D01*
G01X-6545Y815422D02*
X-6694Y815445D01*
G01X-6545Y819359D02*
X-6694Y819382D01*
G01X-3151Y811823D02*
X-2197D01*
G01X-4725Y812099D02*
X-6694D01*
G01X9000Y812217D02*
X-1D01*
G01D02*
X-985D01*
G01X-1Y813556D02*
X9000D01*
G01X-985D02*
X-1D01*
G01X-4725Y813674D02*
X-6694D01*
G01X-3151Y813949D02*
X-2197D01*
G01X-4259Y814107D02*
X-4725D01*
G01X-6694Y814264D02*
X-9844D01*
G01Y815445D02*
X-6694D01*
G01X-4725Y815603D02*
X-4259D01*
G01X-3151Y815760D02*
X-2197D01*
G01X-4725Y816036D02*
X-6694D01*
G01X9000Y816154D02*
X-1D01*
G01D02*
X-985D01*
G01X-1Y817493D02*
X9000D01*
G01X-985D02*
X-1D01*
G01X-4725Y817611D02*
X-6694D01*
G01X-3151Y817886D02*
X-2197D01*
G01X-4259Y818044D02*
X-4725D01*
G01X-6694Y818201D02*
X-9844D01*
G01Y819382D02*
X-6694D01*
G01X-4725Y819540D02*
X-4259D01*
G01X-3151Y819697D02*
X-2197D01*
G01X-4725Y819973D02*
X-6694D01*
G01X9000Y820091D02*
X-1D01*
G01D02*
X-985D01*
G01X-1Y821430D02*
X9000D01*
G01X-985D02*
X-1D01*
G01X-4725Y821548D02*
X-6694D01*
G01X-3151Y821823D02*
X-2197D01*
G01X-4259Y821981D02*
X-4725D01*
G01X-6694Y822138D02*
X-9844D01*
G01X1968Y823031D02*
X19881D01*
G01X-1Y823286D02*
X15550D01*
G01X-6351Y814319D02*
X-6694Y814264D01*
G01X-6351Y818256D02*
X-6694Y818201D01*
G01X-6351Y822193D02*
X-6694Y822138D01*
G01X-10631Y821784D02*
X-9844Y822138D01*
G01X-10631Y817847D02*
X-9844Y818201D01*
G01X-10631Y813910D02*
X-9844Y814264D01*
G01X-3467Y814319D02*
X-4259Y814107D01*
G01X-3467Y818256D02*
X-4259Y818044D01*
G01X-3467Y822193D02*
X-4259Y821981D01*
G01X-10531Y845451D02*
Y843314D01*
G01Y841514D02*
Y839377D01*
G01Y837577D02*
Y835440D01*
G01Y833640D02*
Y831503D01*
G01X-9607Y830185D02*
Y860304D01*
G01X-6694Y847532D02*
Y846941D01*
G01Y845760D02*
Y845170D01*
G01Y843595D02*
Y843004D01*
G01Y841823D02*
Y841233D01*
G01Y839658D02*
Y839067D01*
G01Y837886D02*
Y837296D01*
G01Y835721D02*
Y835130D01*
G01Y833949D02*
Y833359D01*
G01Y831784D02*
Y831193D01*
G01X-6038Y847233D02*
Y846918D01*
G01Y845815D02*
Y845500D01*
G01Y843296D02*
Y842981D01*
G01Y839359D02*
Y839044D01*
G01Y841878D02*
Y841563D01*
G01Y835422D02*
Y835107D01*
G01Y837941D02*
Y837626D01*
G01Y831485D02*
Y831170D01*
G01Y834004D02*
Y833689D01*
G01X-4725Y831170D02*
Y831784D01*
G01Y833359D02*
Y834004D01*
G01Y835107D02*
Y835721D01*
G01Y837296D02*
Y837941D01*
G01Y839044D02*
Y839658D01*
G01Y842981D02*
Y843595D01*
G01Y841233D02*
Y841878D01*
G01Y846918D02*
Y847532D01*
G01Y845170D02*
Y845815D01*
G01X-3757Y845500D02*
Y843296D01*
G01Y841563D02*
Y839359D01*
G01Y837626D02*
Y835422D01*
G01Y833689D02*
Y831485D01*
G01X-2197Y831508D02*
X-2001Y831170D01*
G01X-3151Y833634D02*
X-3364Y834004D01*
G01X-2197Y835445D02*
X-2001Y835107D01*
G01X-3151Y837571D02*
X-3364Y837941D01*
G01X-2197Y839382D02*
X-2001Y839044D01*
G01X-3151Y841508D02*
X-3364Y841878D01*
G01X-2197Y843319D02*
X-2001Y842981D01*
G01X-3151Y845445D02*
X-3364Y845815D01*
G01X-2197Y847256D02*
X-2001Y846918D01*
G01X-2521Y845500D02*
Y843296D01*
G01Y841563D02*
Y839359D01*
G01Y837626D02*
Y835422D01*
G01Y833689D02*
Y831485D01*
G01X-2251Y849752D02*
Y846918D01*
G01Y845815D02*
Y842981D01*
G01Y841878D02*
Y839044D01*
G01Y837941D02*
Y835107D01*
G01Y834004D02*
Y831170D01*
G01X-985Y845052D02*
Y843713D01*
G01Y841115D02*
Y839776D01*
G01Y837178D02*
Y835839D01*
G01Y833241D02*
Y831902D01*
G01X196Y845052D02*
Y843713D01*
G01Y841115D02*
Y839776D01*
G01Y837178D02*
Y835839D01*
G01Y833241D02*
Y831902D01*
G01X387Y832093D02*
X1968Y830512D01*
G01X387Y832093D02*
X-1Y832480D01*
G01X-3346Y846918D02*
X-3151Y847256D01*
G01X-1983Y845815D02*
X-2197Y845445D01*
G01X-3346Y842981D02*
X-3151Y843319D01*
G01X-1983Y841878D02*
X-2197Y841508D01*
G01X-3346Y839044D02*
X-3151Y839382D01*
G01X-1983Y837941D02*
X-2197Y837571D01*
G01X-3346Y835107D02*
X-3151Y835445D01*
G01X-1983Y834004D02*
X-2197Y833634D01*
G01X-3346Y831170D02*
X-3151Y831508D01*
G01X-4259Y831351D02*
X-3582Y831170D01*
G01X-10631Y831548D02*
X-9844Y831193D01*
G01X-10631Y835485D02*
X-9844Y835130D01*
G01X-10631Y839422D02*
X-9844Y839067D01*
G01X-10631Y843359D02*
X-9844Y843004D01*
G01X-10631Y847296D02*
X-9844Y846941D01*
G01X-6545Y831170D02*
X-6694Y831193D01*
G01X-6545Y835107D02*
X-6694Y835130D01*
G01X-6545Y839044D02*
X-6694Y839067D01*
G01X-6545Y842981D02*
X-6694Y843004D01*
G01X-6545Y846918D02*
X-6694Y846941D01*
G01X-4259Y835288D02*
X-3582Y835107D01*
G01X-4259Y839225D02*
X-3582Y839044D01*
G01X-4259Y843162D02*
X-3582Y842981D01*
G01X-4259Y847099D02*
X-3582Y846918D01*
G01X-1Y830294D02*
X15550D01*
G01X1968Y830512D02*
X19881D01*
G01X-9844Y831193D02*
X-6694D01*
G01X-4725Y831351D02*
X-4259D01*
G01X-3151Y831508D02*
X-2197D01*
G01X-4725Y831784D02*
X-6694D01*
G01X9000Y831902D02*
X-1D01*
G01D02*
X-985D01*
G01X-1Y833241D02*
X9000D01*
G01X-985D02*
X-1D01*
G01X-4725Y833359D02*
X-6694D01*
G01X-3151Y833634D02*
X-2197D01*
G01X-4259Y833792D02*
X-4725D01*
G01X-6694Y833949D02*
X-9844D01*
G01Y835130D02*
X-6694D01*
G01X-4725Y835288D02*
X-4259D01*
G01X-3151Y835445D02*
X-2197D01*
G01X-4725Y835721D02*
X-6694D01*
G01X9000Y835839D02*
X-1D01*
G01D02*
X-985D01*
G01X-1Y837178D02*
X9000D01*
G01X-985D02*
X-1D01*
G01X-4725Y837296D02*
X-6694D01*
G01X-3151Y837571D02*
X-2197D01*
G01X-4259Y837729D02*
X-4725D01*
G01X-6694Y837886D02*
X-9844D01*
G01Y839067D02*
X-6694D01*
G01X-4725Y839225D02*
X-4259D01*
G01X-3151Y839382D02*
X-2197D01*
G01X-4725Y839658D02*
X-6694D01*
G01X9000Y839776D02*
X-1D01*
G01D02*
X-985D01*
G01X-1Y841115D02*
X9000D01*
G01X-985D02*
X-1D01*
G01X-4725Y841233D02*
X-6694D01*
G01X-3151Y841508D02*
X-2197D01*
G01X-4259Y841666D02*
X-4725D01*
G01X-6694Y841823D02*
X-9844D01*
G01Y843004D02*
X-6694D01*
G01X-4725Y843162D02*
X-4259D01*
G01X-3151Y843319D02*
X-2197D01*
G01X-4725Y843595D02*
X-6694D01*
G01X9000Y843713D02*
X-1D01*
G01D02*
X-985D01*
G01X-1Y845052D02*
X9000D01*
G01X-985D02*
X-1D01*
G01X-4725Y845170D02*
X-6694D01*
G01X-3151Y845445D02*
X-2197D01*
G01X-4259Y845603D02*
X-4725D01*
G01X-6694Y845760D02*
X-9844D01*
G01Y846941D02*
X-6694D01*
G01X-10631Y845406D02*
X-9844Y845760D01*
G01X-10631Y841469D02*
X-9844Y841823D01*
G01Y837886D02*
X-10631Y837532D01*
G01Y833595D02*
X-9844Y833949D01*
G01X-6351Y834004D02*
X-6694Y833949D01*
G01X-6351Y837941D02*
X-6694Y837886D01*
G01X-6351Y841878D02*
X-6694Y841823D01*
G01X-3467Y834004D02*
X-4259Y833792D01*
G01X-3467Y837941D02*
X-4259Y837729D01*
G01X-3467Y841878D02*
X-4259Y841666D01*
G01X-3467Y845815D02*
X-4259Y845603D01*
G01X-6351Y845815D02*
X-6694Y845760D01*
G01X-10531Y857262D02*
Y855125D01*
G01Y853325D02*
Y851188D01*
G01Y849388D02*
Y847251D01*
G01X-6694Y855406D02*
Y854815D01*
G01Y857571D02*
Y856981D01*
G01Y853634D02*
Y853044D01*
G01Y851469D02*
Y850878D01*
G01Y849697D02*
Y849107D01*
G01X-6038Y855107D02*
Y854792D01*
G01Y857626D02*
Y857311D01*
G01Y853689D02*
Y853374D01*
G01Y851170D02*
Y850855D01*
G01Y849752D02*
Y849437D01*
G01X-4725Y850855D02*
Y851469D01*
G01Y849107D02*
Y849752D01*
G01Y856981D02*
Y857626D01*
G01Y854792D02*
Y855406D01*
G01Y853044D02*
Y853689D01*
G01X-3757Y857311D02*
Y855107D01*
G01Y853374D02*
Y851170D01*
G01Y849437D02*
Y847233D01*
G01X-3151Y849382D02*
X-3364Y849752D01*
G01X-2197Y851193D02*
X-2001Y850855D01*
G01X-3151Y853319D02*
X-3364Y853689D01*
G01X-2521Y857311D02*
Y855107D01*
G01Y853374D02*
Y851170D01*
G01Y849437D02*
Y847233D01*
G01X-2251Y857626D02*
Y854792D01*
G01Y853689D02*
Y850855D01*
G01X-985Y856863D02*
Y855524D01*
G01Y848989D02*
Y847650D01*
G01Y852926D02*
Y851587D01*
G01X196Y856863D02*
Y855524D01*
G01Y848989D02*
Y847650D01*
G01Y852926D02*
Y851587D01*
G01X-2197Y855130D02*
X-2001Y854792D01*
G01X-3151Y857256D02*
X-3364Y857626D01*
G01X-1983D02*
X-2197Y857256D01*
G01X-3346Y854792D02*
X-3151Y855130D01*
G01X-1983Y853689D02*
X-2197Y853319D01*
G01X-3346Y850855D02*
X-3151Y851193D01*
G01X-1983Y849752D02*
X-2197Y849382D01*
G01X-10631Y851233D02*
X-9844Y850878D01*
G01X-10631Y855170D02*
X-9844Y854815D01*
G01X-6545Y850855D02*
X-6694Y850878D01*
G01X-6545Y854792D02*
X-6694Y854815D01*
G01X-4259Y851036D02*
X-3582Y850855D01*
G01X-4259Y854973D02*
X-3582Y854792D01*
G01X-4725Y847099D02*
X-4259D01*
G01X-3151Y847256D02*
X-2197D01*
G01X-4725Y847532D02*
X-6694D01*
G01X9000Y847650D02*
X-1D01*
G01D02*
X-985D01*
G01X-1Y848989D02*
X9000D01*
G01X-985D02*
X-1D01*
G01X-4725Y849107D02*
X-6694D01*
G01X-3151Y849382D02*
X-2197D01*
G01X-4259Y849540D02*
X-4725D01*
G01X-6694Y849697D02*
X-9844D01*
G01Y850878D02*
X-6694D01*
G01X-4725Y851036D02*
X-4259D01*
G01X-3151Y851193D02*
X-2197D01*
G01X-4725Y851469D02*
X-6694D01*
G01X9000Y851587D02*
X-1D01*
G01D02*
X-985D01*
G01X-1Y852926D02*
X9000D01*
G01X-985D02*
X-1D01*
G01X-4725Y853044D02*
X-6694D01*
G01X-3151Y853319D02*
X-2197D01*
G01X-4259Y853477D02*
X-4725D01*
G01X-6694Y853634D02*
X-9844D01*
G01X-10631Y857217D02*
X-9844Y857571D01*
G01X-10631Y853280D02*
X-9844Y853634D01*
G01X-10631Y849343D02*
X-9844Y849697D01*
G01X-6694Y854815D02*
X-9844D01*
G01X-4259Y854973D02*
X-4725D01*
G01X-3151Y855130D02*
X-2197D01*
G01X-4725Y855406D02*
X-6694D01*
G01X9000Y855524D02*
X-1D01*
G01D02*
X-985D01*
G01X-1Y856863D02*
X9000D01*
G01X-985D02*
X-1D01*
G01X-4725Y856981D02*
X-6694D01*
G01X-3151Y857256D02*
X-2197D01*
G01X-4725Y857414D02*
X-4259D01*
G01X-9844Y857571D02*
X-6694D01*
G01X24802Y861819D02*
X-1D01*
G01X-3467Y849752D02*
X-4259Y849540D01*
G01X-3467Y853689D02*
X-4259Y853477D01*
G01X-3467Y857626D02*
X-4259Y857414D01*
G01X-6351Y849752D02*
X-6694Y849697D01*
G01X-6351Y853689D02*
X-6694Y853634D01*
G01Y857571D02*
X-6351Y857626D01*
G01X-9056Y887410D02*
Y868119D01*
G01X-1D02*
Y887410D01*
G01X9842Y871268D02*
X-9056Y870481D01*
G01Y879930D02*
X9842Y879142D01*
G01X14369Y875205D02*
G03I-4527J0D01*
G01X13779D02*
G03I-3937J0D01*
G01X-1Y887410D02*
Y1125205D01*
G01X24802Y887410D02*
X-9056D01*
G01X-1Y889378D02*
X26771D01*
G01X9000Y821430D02*
Y820091D01*
G01Y817493D02*
Y816154D01*
G01Y813556D02*
Y812217D01*
G01X12829D02*
X9000D01*
G01Y813556D02*
X12829D01*
G01Y816154D02*
X9000D01*
G01Y817493D02*
X12829D01*
G01Y820091D02*
X9000D01*
G01Y821430D02*
X12829D01*
G01X9000Y845052D02*
Y843713D01*
G01Y841115D02*
Y839776D01*
G01Y837178D02*
Y835839D01*
G01Y833241D02*
Y831902D01*
G01X12829D02*
X9000D01*
G01Y833241D02*
X12829D01*
G01Y835839D02*
X9000D01*
G01Y837178D02*
X12829D01*
G01Y839776D02*
X9000D01*
G01Y841115D02*
X12829D01*
G01Y843713D02*
X9000D01*
G01Y845052D02*
X12829D01*
G01X9000Y856863D02*
Y855524D01*
G01Y848989D02*
Y847650D01*
G01Y852926D02*
Y851587D01*
G01X12829Y847650D02*
X9000D01*
G01Y848989D02*
X12829D01*
G01Y851587D02*
X9000D01*
G01Y852926D02*
X12829D01*
G01Y855524D02*
X9000D01*
G01Y856863D02*
X12829D01*
G01X-7875Y905988D02*
Y893315D01*
G01D02*
X-63741D01*
G01X-35395Y917252D02*
G03I-4292J0D01*
G01X-7875Y1069005D02*
Y933234D01*
G01D02*
G03X-1I3937J0D01*
G01Y905988D02*
G03X-7875I-3937J0D01*
G01Y933234D02*
G03X-1I3937J0D01*
G01Y905988D02*
G03X-7875I-3937J0D01*
G01X-34510Y1082343D02*
G03I-4292J0D01*
G01X-9056Y1125205D02*
Y1144496D01*
G01X-1Y1125205D02*
Y1144496D01*
G01Y1125205D02*
Y1195866D01*
G01Y1123237D02*
X26771D01*
G01X-9056Y1125205D02*
X24802D01*
G01X9842Y1133473D02*
X-9056Y1132685D01*
G01Y1142134D02*
X9842Y1141347D01*
G01X14369Y1137410D02*
G03I-4527J0D01*
G01X13779D02*
G03I-3937J0D01*
G01X-7875Y1108863D02*
Y1119299D01*
G01X-19126D02*
X-7875D01*
G01X-15749D02*
X-63741D01*
G01X-7875Y1106300D02*
Y1111425D01*
G01Y1106300D02*
Y1092625D01*
G01D02*
G03X-1I3937J0D01*
G01Y1069005D02*
G03X-7875I-3937J0D01*
G01Y1092625D02*
G03X-1I3937J0D01*
G01Y1069005D02*
G03X-7875I-3937J0D01*
G01X-39607Y1242922D02*
Y1144496D01*
G01X-33702Y1152370D02*
Y1148433D01*
G01X-39607Y1144496D02*
X-1D01*
G01X-39607Y1147646D02*
X-27993D01*
G01X-33702Y1148433D02*
X-39607D01*
G01X-38426Y1169201D02*
Y1166839D01*
G01Y1165264D02*
Y1162902D01*
G01Y1161327D02*
Y1158965D01*
G01Y1157390D02*
Y1155028D01*
G01X-36812Y1198894D02*
Y1150824D01*
G01X-36192Y1168672D02*
Y1167337D01*
G01Y1164735D02*
Y1163400D01*
G01Y1160798D02*
Y1159463D01*
G01Y1156861D02*
Y1155526D01*
G01X-35595Y1168729D02*
Y1167280D01*
G01Y1164792D02*
Y1163343D01*
G01Y1160855D02*
Y1159406D01*
G01Y1156918D02*
Y1155469D01*
G01X-35546Y1167275D02*
Y1166839D01*
G01Y1163338D02*
Y1162902D01*
G01Y1165264D02*
Y1164797D01*
G01Y1159401D02*
Y1158965D01*
G01Y1161327D02*
Y1160860D01*
G01Y1155464D02*
Y1155028D01*
G01Y1157390D02*
Y1156923D01*
G01X-35331Y1168754D02*
Y1167256D01*
G01Y1164817D02*
Y1163319D01*
G01Y1160880D02*
Y1159382D01*
G01Y1156943D02*
Y1155445D01*
G01X-34607Y1169122D02*
Y1166918D01*
G01Y1165185D02*
Y1162981D01*
G01Y1157311D02*
Y1155107D01*
G01Y1159044D02*
Y1161248D01*
G01X-34136Y1155432D02*
Y1156955D01*
G01Y1159369D02*
Y1160892D01*
G01Y1163306D02*
Y1164829D01*
G01Y1167243D02*
Y1168766D01*
G01X-33153Y1168777D02*
Y1167232D01*
G01Y1164840D02*
Y1163295D01*
G01Y1160903D02*
Y1159358D01*
G01Y1156966D02*
Y1155421D01*
G01X-31995Y1168790D02*
Y1167219D01*
G01Y1164853D02*
Y1163282D01*
G01Y1160916D02*
Y1159345D01*
G01Y1156979D02*
Y1155408D01*
G01X-31725Y1168793D02*
Y1167216D01*
G01Y1164856D02*
Y1163279D01*
G01Y1160919D02*
Y1159342D01*
G01Y1156982D02*
Y1155405D01*
G01X-34603Y1152370D02*
X-39607Y1148867D01*
G01Y1152370D02*
X-9607D01*
G01X-39607Y1155028D02*
X-24509D01*
G01X-35546Y1155107D02*
X-1D01*
G01X-39607Y1157095D02*
X-27993D01*
G01X-35546Y1157311D02*
X-1D01*
G01X-24509Y1157390D02*
X-39607D01*
G01X-35351Y1155445D02*
X-10631Y1155170D01*
G01X-35351Y1159382D02*
X-10631Y1159107D01*
G01X-35351Y1163319D02*
X-10631Y1163044D01*
G01X-36192Y1155526D02*
X-35351Y1155445D01*
G01X-36192Y1159463D02*
X-35351Y1159382D01*
G01X-36192Y1163400D02*
X-35351Y1163319D01*
G01X-36192Y1167337D02*
X-35351Y1167256D01*
G01X-36192Y1156861D02*
X-35341Y1156943D01*
G01X-36192Y1160798D02*
X-35341Y1160880D01*
G01X-36192Y1164735D02*
X-35341Y1164817D01*
G01X-35351Y1156941D02*
X-10631Y1157217D01*
G01X-35351Y1160878D02*
X-10631Y1161154D01*
G01X-35351Y1164815D02*
X-10631Y1165091D01*
G01X-39607Y1158965D02*
X-24509D01*
G01X-35546Y1159044D02*
X-1D01*
G01X-39607Y1160244D02*
X-24844D01*
G01X-35546Y1161248D02*
X-1D01*
G01X-24509Y1161327D02*
X-39607D01*
G01Y1162902D02*
X-24509D01*
G01X-35546Y1162981D02*
X-1D01*
G01X-39607Y1164969D02*
X-24844D01*
G01X-35546Y1165185D02*
X-1D01*
G01X-24509Y1165264D02*
X-39607D01*
G01Y1166839D02*
X-24509D01*
G01X-35546Y1166918D02*
X-1D01*
G01X-27993Y1168119D02*
X-39607D01*
G01X-35351Y1167256D02*
X-10631Y1166981D01*
G01X-38426Y1188886D02*
Y1186524D01*
G01Y1184949D02*
Y1182587D01*
G01Y1181012D02*
Y1178650D01*
G01Y1177075D02*
Y1174713D01*
G01Y1173138D02*
Y1170776D01*
G01X-36192Y1188357D02*
Y1187022D01*
G01Y1184420D02*
Y1183085D01*
G01Y1180483D02*
Y1179148D01*
G01Y1176546D02*
Y1175211D01*
G01Y1172609D02*
Y1171274D01*
G01X-35595Y1188414D02*
Y1186965D01*
G01Y1184477D02*
Y1183028D01*
G01Y1180540D02*
Y1179091D01*
G01Y1176603D02*
Y1175154D01*
G01Y1172666D02*
Y1171217D01*
G01X-35546Y1186960D02*
Y1186524D01*
G01Y1188886D02*
Y1188419D01*
G01Y1183023D02*
Y1182587D01*
G01Y1184949D02*
Y1184482D01*
G01Y1181012D02*
Y1180545D01*
G01Y1179086D02*
Y1178650D01*
G01Y1177075D02*
Y1176608D01*
G01Y1173138D02*
Y1172671D01*
G01Y1175149D02*
Y1174713D01*
G01Y1171212D02*
Y1170776D01*
G01Y1169201D02*
Y1168734D01*
G01X-35331Y1188439D02*
Y1186941D01*
G01Y1184502D02*
Y1183004D01*
G01Y1176628D02*
Y1175130D01*
G01Y1180565D02*
Y1179067D01*
G01Y1172691D02*
Y1171193D01*
G01X-34607Y1188807D02*
Y1186603D01*
G01Y1184870D02*
Y1182666D01*
G01Y1180933D02*
Y1178729D01*
G01Y1176996D02*
Y1174792D01*
G01Y1173059D02*
Y1170855D01*
G01X-34136Y1171180D02*
Y1172703D01*
G01Y1175117D02*
Y1176640D01*
G01Y1179054D02*
Y1180577D01*
G01Y1182991D02*
Y1184514D01*
G01Y1186928D02*
Y1188451D01*
G01X-33153Y1188462D02*
Y1186917D01*
G01Y1184525D02*
Y1182980D01*
G01Y1180588D02*
Y1179043D01*
G01Y1176651D02*
Y1175106D01*
G01Y1172714D02*
Y1171169D01*
G01X-31995Y1188475D02*
Y1186904D01*
G01Y1184538D02*
Y1182967D01*
G01Y1176664D02*
Y1175093D01*
G01Y1180601D02*
Y1179030D01*
G01Y1172727D02*
Y1171156D01*
G01X-31725Y1188478D02*
Y1186901D01*
G01Y1184541D02*
Y1182964D01*
G01Y1176667D02*
Y1175090D01*
G01Y1180604D02*
Y1179027D01*
G01Y1172730D02*
Y1171153D01*
G01X-36192Y1171274D02*
X-35351Y1171193D01*
G01X-36192Y1175211D02*
X-35351Y1175130D01*
G01X-36192Y1179148D02*
X-35351Y1179067D01*
G01X-36192Y1183085D02*
X-35351Y1183004D01*
G01X-36192Y1187022D02*
X-35351Y1186941D01*
G01X-36192Y1168672D02*
X-35341Y1168754D01*
G01X-36192Y1172609D02*
X-35341Y1172691D01*
G01X-36192Y1176546D02*
X-35341Y1176628D01*
G01X-36192Y1180483D02*
X-35341Y1180565D01*
G01X-35351Y1168752D02*
X-10631Y1169028D01*
G01X-35351Y1172689D02*
X-10631Y1172965D01*
G01X-35351Y1176626D02*
X-10631Y1176902D01*
G01X-35351Y1180563D02*
X-10631Y1180839D01*
G01X-35351Y1184500D02*
X-10631Y1184776D01*
G01X-35351Y1188437D02*
X-10631Y1188713D01*
G01X-35546Y1169122D02*
X-1D01*
G01X-24509Y1169201D02*
X-39607D01*
G01Y1170776D02*
X-24509D01*
G01X-35546Y1170855D02*
X-1D01*
G01X-35546Y1173059D02*
X-1D01*
G01X-24509Y1173138D02*
X-39607D01*
G01Y1174713D02*
X-24509D01*
G01X-35546Y1174792D02*
X-1D01*
G01X-35546Y1176996D02*
X-1D01*
G01X-24509Y1177075D02*
X-39607D01*
G01Y1177567D02*
X-27993D01*
G01X-39607Y1178650D02*
X-24509D01*
G01X-35546Y1178729D02*
X-1D01*
G01X-39607Y1180717D02*
X-24844D01*
G01X-35546Y1180933D02*
X-1D01*
G01X-24509Y1181012D02*
X-39607D01*
G01Y1182587D02*
X-24509D01*
G01X-35546Y1182666D02*
X-1D01*
G01X-35546Y1184870D02*
X-1D01*
G01X-24509Y1184949D02*
X-39607D01*
G01Y1185441D02*
X-24844D01*
G01X-39607Y1186524D02*
X-24509D01*
G01X-35546Y1186603D02*
X-1D01*
G01X-27993Y1188591D02*
X-39607D01*
G01X-35351Y1171193D02*
X-10631Y1170918D01*
G01X-35351Y1175130D02*
X-10631Y1174855D01*
G01X-35351Y1179067D02*
X-10631Y1178792D01*
G01X-35351Y1183004D02*
X-10631Y1182729D01*
G01X-35351Y1186941D02*
X-10631Y1186666D01*
G01X-36192Y1184420D02*
X-35341Y1184502D01*
G01X-36192Y1188357D02*
X-35341Y1188439D01*
G01X-38426Y1208571D02*
Y1206209D01*
G01Y1196760D02*
Y1194398D01*
G01Y1192823D02*
Y1190461D01*
G01X-36812Y1235823D02*
Y1204272D01*
G01X-36192Y1208042D02*
Y1206707D01*
G01Y1196231D02*
Y1194896D01*
G01Y1192294D02*
Y1190959D01*
G01X-35595Y1208099D02*
Y1206650D01*
G01Y1196288D02*
Y1194839D01*
G01Y1192351D02*
Y1190902D01*
G01X-35546Y1206645D02*
Y1206209D01*
G01Y1208571D02*
Y1208104D01*
G01Y1196760D02*
Y1196293D01*
G01Y1194834D02*
Y1194398D01*
G01Y1190897D02*
Y1190461D01*
G01Y1192823D02*
Y1192356D01*
G01X-35434Y1198985D02*
Y1203985D01*
G01X-35331Y1208124D02*
Y1206626D01*
G01Y1196313D02*
Y1194815D01*
G01Y1192376D02*
Y1190878D01*
G01X-34607Y1196681D02*
Y1194477D01*
G01Y1192744D02*
Y1190540D01*
G01Y1206288D02*
Y1208493D01*
G01X-34136Y1190865D02*
Y1192388D01*
G01Y1194802D02*
Y1196325D01*
G01Y1206613D02*
Y1208136D01*
G01X-33153Y1208147D02*
Y1206602D01*
G01Y1196336D02*
Y1194791D01*
G01Y1192399D02*
Y1190854D01*
G01X-31995Y1208160D02*
Y1206589D01*
G01Y1196349D02*
Y1194778D01*
G01Y1192412D02*
Y1190841D01*
G01X-31725Y1208163D02*
Y1206586D01*
G01Y1196352D02*
Y1194775D01*
G01Y1192415D02*
Y1190838D01*
G01X-39020Y1202726D02*
X-36561Y1204447D01*
G01Y1198719D02*
X-39020Y1200440D01*
G01X-36192Y1190959D02*
X-35351Y1190878D01*
G01X-36192Y1194896D02*
X-35351Y1194815D01*
G01X-36192Y1206707D02*
X-35351Y1206626D01*
G01Y1192374D02*
X-10631Y1192650D01*
G01X-35351Y1196311D02*
X-10631Y1196587D01*
G01X-35351Y1208122D02*
X-10631Y1208398D01*
G01X-35546Y1188807D02*
X-1D01*
G01X-24509Y1188886D02*
X-39607D01*
G01Y1190461D02*
X-24509D01*
G01X-35546Y1190540D02*
X-1D01*
G01X-35546Y1192744D02*
X-1D01*
G01X-24509Y1192823D02*
X-39607D01*
G01Y1194398D02*
X-24509D01*
G01X-35546Y1194477D02*
X-1D01*
G01X-35546Y1196681D02*
X-1D01*
G01X-24509Y1196760D02*
X-39607D01*
G01Y1198040D02*
X-27993D01*
G01X-9607Y1198178D02*
X-34845D01*
G01X-1Y1198985D02*
X-35434D01*
G01X-39607Y1201189D02*
X-24844D01*
G01X-35434Y1203985D02*
X-1D01*
G01X-34845Y1204989D02*
X-9607D01*
G01X-39607Y1205914D02*
X-24844D01*
G01X-39607Y1206209D02*
X-24509D01*
G01X-35546Y1206288D02*
X-1D01*
G01X-35546Y1208493D02*
X-1D01*
G01X-24509Y1208571D02*
X-39607D01*
G01X-35351Y1190878D02*
X-10631Y1190603D01*
G01X-35351Y1194815D02*
X-10631Y1194540D01*
G01X-35351Y1206626D02*
X-10631Y1206351D01*
G01X-36192Y1192294D02*
X-35341Y1192376D01*
G01X-36192Y1196231D02*
X-35341Y1196313D01*
G01X-36192Y1208042D02*
X-35341Y1208124D01*
G01X-34845Y1204989D02*
G03X-36561Y1204447I1J-2992D01*
G01Y1198719D02*
G03X-34845Y1198178I1716J2451D01*
G01X-39020Y1202726D02*
G03X-39607Y1201597I791J-1128D01*
G01Y1201569D02*
G03X-39020Y1200440I1378J-1D01*
G01X-38426Y1224319D02*
Y1221957D01*
G01Y1220382D02*
Y1218020D01*
G01Y1216445D02*
Y1214083D01*
G01Y1212508D02*
Y1210146D01*
G01X-36192Y1223790D02*
Y1222456D01*
G01Y1219853D02*
Y1218519D01*
G01Y1215916D02*
Y1214581D01*
G01Y1211979D02*
Y1210644D01*
G01X-35595Y1223847D02*
Y1222398D01*
G01Y1219910D02*
Y1218461D01*
G01Y1215973D02*
Y1214524D01*
G01Y1212036D02*
Y1210587D01*
G01X-35546Y1224319D02*
Y1223852D01*
G01Y1220382D02*
Y1219915D01*
G01Y1222393D02*
Y1221957D01*
G01Y1218456D02*
Y1218020D01*
G01Y1214519D02*
Y1214083D01*
G01Y1216445D02*
Y1215978D01*
G01Y1210582D02*
Y1210146D01*
G01Y1212508D02*
Y1212041D01*
G01X-35331Y1223872D02*
Y1222374D01*
G01Y1219935D02*
Y1218437D01*
G01Y1215998D02*
Y1214500D01*
G01Y1212061D02*
Y1210563D01*
G01X-34607Y1224241D02*
Y1222036D01*
G01Y1216367D02*
Y1214162D01*
G01Y1220304D02*
Y1218099D01*
G01Y1212430D02*
Y1210225D01*
G01X-34136Y1210550D02*
Y1212073D01*
G01Y1214487D02*
Y1216010D01*
G01Y1218424D02*
Y1219947D01*
G01Y1222361D02*
Y1223884D01*
G01X-33153Y1223895D02*
Y1222350D01*
G01Y1219958D02*
Y1218413D01*
G01Y1216021D02*
Y1214476D01*
G01Y1212084D02*
Y1210539D01*
G01X-31995Y1223908D02*
Y1222337D01*
G01Y1219971D02*
Y1218400D01*
G01Y1216034D02*
Y1214463D01*
G01Y1212097D02*
Y1210526D01*
G01X-31725Y1223911D02*
Y1222334D01*
G01Y1219974D02*
Y1218397D01*
G01Y1216037D02*
Y1214460D01*
G01Y1212100D02*
Y1210523D01*
G01X-36192Y1210644D02*
X-35351Y1210563D01*
G01Y1212059D02*
X-10631Y1212335D01*
G01X-35351Y1215996D02*
X-10631Y1216272D01*
G01X-35351Y1219933D02*
X-10631Y1220209D01*
G01X-35351Y1223870D02*
X-10631Y1224146D01*
G01X-27993Y1209063D02*
X-39607D01*
G01Y1210146D02*
X-24509D01*
G01X-35546Y1210225D02*
X-1D01*
G01X-35546Y1212430D02*
X-1D01*
G01X-24509Y1212508D02*
X-39607D01*
G01Y1214083D02*
X-24509D01*
G01X-35546Y1214162D02*
X-1D01*
G01X-35546Y1216367D02*
X-1D01*
G01X-24509Y1216445D02*
X-39607D01*
G01Y1218020D02*
X-24509D01*
G01X-35546Y1218099D02*
X-1D01*
G01X-39607Y1218512D02*
X-27993D01*
G01X-35546Y1220304D02*
X-1D01*
G01X-24509Y1220382D02*
X-39607D01*
G01Y1221662D02*
X-24844D01*
G01X-39607Y1221957D02*
X-24509D01*
G01X-35546Y1222036D02*
X-1D01*
G01X-35546Y1224241D02*
X-1D01*
G01X-24509Y1224319D02*
X-39607D01*
G01X-35351Y1210563D02*
X-10631Y1210288D01*
G01X-35351Y1214500D02*
X-10631Y1214225D01*
G01X-35351Y1218437D02*
X-10631Y1218162D01*
G01X-35351Y1222374D02*
X-10631Y1222099D01*
G01X-36192Y1214581D02*
X-35351Y1214500D01*
G01X-36192Y1218519D02*
X-35351Y1218437D01*
G01X-36192Y1222456D02*
X-35351Y1222374D01*
G01X-36192Y1211979D02*
X-35341Y1212061D01*
G01X-36192Y1215916D02*
X-35341Y1215998D01*
G01X-36192Y1219853D02*
X-35341Y1219935D01*
G01X-36192Y1223790D02*
X-35341Y1223872D01*
G01X-27993Y1160244D02*
Y1144496D01*
G01X-24844D02*
Y1160244D01*
G01X-27993Y1164969D02*
Y1180717D01*
G01X-27265Y1169201D02*
Y1166839D01*
G01Y1165264D02*
Y1162902D01*
G01Y1161327D02*
Y1158965D01*
G01Y1157390D02*
Y1155028D01*
G01X-26511Y1168851D02*
Y1167158D01*
G01Y1164914D02*
Y1163221D01*
G01Y1160977D02*
Y1159284D01*
G01Y1157040D02*
Y1155347D01*
G01X-26242Y1168854D02*
Y1167155D01*
G01Y1164917D02*
Y1163218D01*
G01Y1160980D02*
Y1159281D01*
G01Y1157043D02*
Y1155344D01*
G01X-24844Y1164969D02*
Y1180717D01*
G01X-24509Y1165264D02*
Y1162902D01*
G01Y1169201D02*
Y1166839D01*
G01Y1161327D02*
Y1158965D01*
G01Y1157390D02*
Y1155028D01*
G01X-23998Y1168879D02*
Y1167130D01*
G01Y1164942D02*
Y1163193D01*
G01Y1161005D02*
Y1159256D01*
G01Y1157068D02*
Y1155319D01*
G01X-23519Y1168885D02*
Y1167124D01*
G01Y1164948D02*
Y1163187D01*
G01Y1161011D02*
Y1159250D01*
G01Y1157074D02*
Y1155313D01*
G01X-12993Y1162981D02*
Y1162666D01*
G01Y1165500D02*
Y1165185D01*
G01Y1166918D02*
Y1166603D01*
G01Y1161563D02*
Y1161248D01*
G01Y1159044D02*
Y1158729D01*
G01Y1157626D02*
Y1157311D01*
G01Y1155107D02*
Y1154792D01*
G01X-12445Y1169008D02*
Y1167001D01*
G01Y1165071D02*
Y1163064D01*
G01Y1161134D02*
Y1159127D01*
G01Y1157197D02*
Y1155190D01*
G01X-11967Y1155185D02*
Y1157202D01*
G01Y1159122D02*
Y1161139D01*
G01Y1163059D02*
Y1165076D01*
G01Y1166996D02*
Y1169013D01*
G01X-12993Y1154792D02*
X-1D01*
G01Y1157626D02*
X-12993D01*
G01Y1158729D02*
X-1D01*
G01Y1161563D02*
X-12993D01*
G01Y1162666D02*
X-1D01*
G01Y1165500D02*
X-12993D01*
G01Y1166603D02*
X-1D01*
G01X-27993Y1185441D02*
Y1201189D01*
G01X-27265Y1188886D02*
Y1186524D01*
G01Y1181012D02*
Y1178650D01*
G01Y1184949D02*
Y1182587D01*
G01Y1177075D02*
Y1174713D01*
G01Y1173138D02*
Y1170776D01*
G01X-26511Y1188536D02*
Y1186843D01*
G01Y1184599D02*
Y1182906D01*
G01Y1180662D02*
Y1178969D01*
G01Y1176725D02*
Y1175032D01*
G01Y1172788D02*
Y1171095D01*
G01X-26242Y1188539D02*
Y1186840D01*
G01Y1184602D02*
Y1182903D01*
G01Y1180665D02*
Y1178966D01*
G01Y1176728D02*
Y1175029D01*
G01Y1172791D02*
Y1171092D01*
G01X-24844Y1185441D02*
Y1201189D01*
G01X-24509Y1188886D02*
Y1186524D01*
G01Y1184949D02*
Y1182587D01*
G01Y1181012D02*
Y1178650D01*
G01Y1177075D02*
Y1174713D01*
G01Y1173138D02*
Y1170776D01*
G01X-23998Y1188564D02*
Y1186815D01*
G01Y1184627D02*
Y1182878D01*
G01Y1176753D02*
Y1175004D01*
G01Y1180690D02*
Y1178941D01*
G01Y1172816D02*
Y1171067D01*
G01X-23519Y1188570D02*
Y1186809D01*
G01Y1184633D02*
Y1182872D01*
G01Y1176759D02*
Y1174998D01*
G01Y1180696D02*
Y1178935D01*
G01Y1172822D02*
Y1171061D01*
G01X-12993Y1186603D02*
Y1186288D01*
G01Y1181248D02*
Y1180933D01*
G01Y1182666D02*
Y1182351D01*
G01Y1185185D02*
Y1184870D01*
G01Y1177311D02*
Y1176996D01*
G01Y1178729D02*
Y1178414D01*
G01Y1173374D02*
Y1173059D01*
G01Y1174792D02*
Y1174477D01*
G01Y1169437D02*
Y1169122D01*
G01Y1170855D02*
Y1170540D01*
G01X-12445Y1188693D02*
Y1186686D01*
G01Y1184756D02*
Y1182749D01*
G01Y1180819D02*
Y1178812D01*
G01Y1176882D02*
Y1174875D01*
G01Y1172945D02*
Y1170938D01*
G01X-11967Y1170933D02*
Y1172950D01*
G01Y1174870D02*
Y1176887D01*
G01Y1178807D02*
Y1180824D01*
G01Y1182744D02*
Y1184761D01*
G01Y1186681D02*
Y1188698D01*
G01X-1Y1169437D02*
X-12993D01*
G01Y1170540D02*
X-1D01*
G01Y1173374D02*
X-12993D01*
G01Y1174477D02*
X-1D01*
G01Y1177311D02*
X-12993D01*
G01Y1178414D02*
X-1D01*
G01Y1181248D02*
X-12993D01*
G01Y1182351D02*
X-1D01*
G01Y1185185D02*
X-12993D01*
G01Y1186288D02*
X-1D01*
G01X-27993Y1205914D02*
Y1221662D01*
G01X-27265Y1208571D02*
Y1206209D01*
G01Y1196760D02*
Y1194398D01*
G01Y1192823D02*
Y1190461D01*
G01X-26511Y1208221D02*
Y1206528D01*
G01Y1196410D02*
Y1194717D01*
G01Y1192473D02*
Y1190780D01*
G01X-26242Y1208224D02*
Y1206525D01*
G01Y1196413D02*
Y1194714D01*
G01Y1192476D02*
Y1190777D01*
G01X-24844Y1205914D02*
Y1221662D01*
G01X-24509Y1208571D02*
Y1206209D01*
G01Y1196760D02*
Y1194398D01*
G01Y1192823D02*
Y1190461D01*
G01X-23998Y1208249D02*
Y1206500D01*
G01Y1196438D02*
Y1194689D01*
G01Y1192501D02*
Y1190752D01*
G01X-23519Y1208255D02*
Y1206494D01*
G01Y1196444D02*
Y1194683D01*
G01Y1192507D02*
Y1190746D01*
G01X-12993Y1208807D02*
Y1208493D01*
G01Y1206288D02*
Y1205973D01*
G01Y1196996D02*
Y1196681D01*
G01Y1194477D02*
Y1194162D01*
G01Y1193059D02*
Y1192744D01*
G01Y1190540D02*
Y1190225D01*
G01Y1189122D02*
Y1188807D01*
G01X-12445Y1208378D02*
Y1206371D01*
G01Y1196567D02*
Y1194560D01*
G01Y1192630D02*
Y1190623D01*
G01X-11967Y1190618D02*
Y1192635D01*
G01Y1194555D02*
Y1196572D01*
G01Y1206366D02*
Y1208383D01*
G01X-1Y1189122D02*
X-12993D01*
G01Y1190225D02*
X-1D01*
G01Y1193059D02*
X-12993D01*
G01Y1194162D02*
X-1D01*
G01Y1196996D02*
X-12993D01*
G01Y1205973D02*
X-1D01*
G01X-27265Y1224319D02*
Y1221957D01*
G01Y1220382D02*
Y1218020D01*
G01Y1216445D02*
Y1214083D01*
G01Y1212508D02*
Y1210146D01*
G01X-26511Y1223969D02*
Y1222276D01*
G01Y1220032D02*
Y1218339D01*
G01Y1216095D02*
Y1214402D01*
G01Y1212158D02*
Y1210465D01*
G01X-26242Y1223972D02*
Y1222273D01*
G01Y1220035D02*
Y1218336D01*
G01Y1216098D02*
Y1214399D01*
G01Y1212161D02*
Y1210462D01*
G01X-24509Y1224319D02*
Y1221957D01*
G01Y1220382D02*
Y1218020D01*
G01Y1216445D02*
Y1214083D01*
G01Y1212508D02*
Y1210146D01*
G01X-23998Y1223997D02*
Y1222248D01*
G01Y1220060D02*
Y1218311D01*
G01Y1216123D02*
Y1214374D01*
G01Y1212186D02*
Y1210437D01*
G01X-23519Y1224003D02*
Y1222243D01*
G01Y1220066D02*
Y1218306D01*
G01Y1216129D02*
Y1214369D01*
G01Y1212192D02*
Y1210431D01*
G01X-12993Y1224556D02*
Y1224241D01*
G01Y1222036D02*
Y1221721D01*
G01Y1220619D02*
Y1220304D01*
G01Y1218099D02*
Y1217784D01*
G01Y1214162D02*
Y1213847D01*
G01Y1216681D02*
Y1216367D01*
G01Y1210225D02*
Y1209910D01*
G01Y1212744D02*
Y1212430D01*
G01X-12445Y1224126D02*
Y1222119D01*
G01Y1220189D02*
Y1218182D01*
G01Y1216252D02*
Y1214245D01*
G01Y1212315D02*
Y1210308D01*
G01X-11967Y1210303D02*
Y1212320D01*
G01Y1214240D02*
Y1216257D01*
G01Y1218177D02*
Y1220194D01*
G01Y1222114D02*
Y1224131D01*
G01X-1Y1208807D02*
X-12993D01*
G01Y1209910D02*
X-1D01*
G01Y1212744D02*
X-12993D01*
G01Y1213847D02*
X-1D01*
G01Y1216681D02*
X-12993D01*
G01Y1217784D02*
X-1D01*
G01Y1220619D02*
X-12993D01*
G01Y1221721D02*
X-1D01*
G01Y1224556D02*
X-12993D01*
G01X-1Y1144496D02*
Y1242922D01*
G01X-10531Y1169073D02*
Y1166936D01*
G01Y1165136D02*
Y1162999D01*
G01Y1161199D02*
Y1159062D01*
G01Y1157262D02*
Y1155125D01*
G01X-9607Y1152370D02*
Y1198178D01*
G01X-6694Y1167217D02*
Y1166626D01*
G01Y1165445D02*
Y1164855D01*
G01Y1163280D02*
Y1162689D01*
G01Y1159343D02*
Y1158752D01*
G01Y1161508D02*
Y1160918D01*
G01Y1155406D02*
Y1154815D01*
G01Y1157571D02*
Y1156981D01*
G01X-6038Y1162981D02*
Y1162666D01*
G01Y1165500D02*
Y1165185D01*
G01Y1166918D02*
Y1166603D01*
G01Y1161563D02*
Y1161248D01*
G01Y1157626D02*
Y1157311D01*
G01Y1159044D02*
Y1158729D01*
G01Y1155107D02*
Y1154792D01*
G01X-4725D02*
Y1155406D01*
G01Y1160918D02*
Y1161563D01*
G01Y1156981D02*
Y1157626D01*
G01Y1158729D02*
Y1159343D01*
G01Y1162666D02*
Y1163280D01*
G01Y1164855D02*
Y1165500D01*
G01Y1166603D02*
Y1167217D01*
G01X-3757Y1169122D02*
Y1166918D01*
G01Y1165185D02*
Y1162981D01*
G01Y1161248D02*
Y1159044D01*
G01Y1157311D02*
Y1155107D01*
G01X8385Y1155491D02*
X8452Y1155819D01*
G01X8854Y1155754D02*
X8787Y1155557D01*
G01X-3346Y1166603D02*
X-3151Y1166941D01*
G01X-1983Y1165500D02*
X-2197Y1165130D01*
G01X-3346Y1162666D02*
X-3151Y1163004D01*
G01X-1983Y1161563D02*
X-2197Y1161193D01*
G01X-3346Y1158729D02*
X-3151Y1159067D01*
G01X-1983Y1157626D02*
X-2197Y1157256D01*
G01X-3346Y1154792D02*
X-3151Y1155130D01*
G01X-2521Y1169122D02*
Y1166918D01*
G01Y1165185D02*
Y1162981D01*
G01Y1161248D02*
Y1159044D01*
G01Y1157311D02*
Y1155107D01*
G01X-2251Y1165500D02*
Y1162666D01*
G01Y1169437D02*
Y1166603D01*
G01Y1161563D02*
Y1158729D01*
G01Y1157626D02*
Y1154792D01*
G01X-985Y1168674D02*
Y1167335D01*
G01Y1164737D02*
Y1163398D01*
G01Y1160800D02*
Y1159461D01*
G01Y1156863D02*
Y1155524D01*
G01X196Y1164737D02*
Y1163398D01*
G01Y1160800D02*
Y1159461D01*
G01Y1156863D02*
Y1155524D01*
G01Y1168674D02*
Y1167335D01*
G01X8385Y1153916D02*
Y1155491D01*
G01Y1157263D02*
Y1157656D01*
G01X8787Y1155557D02*
Y1154310D01*
G01X8452Y1155819D02*
X8653Y1156081D01*
G01D02*
X8921Y1156278D01*
G01X-10631Y1165091D02*
X-9844Y1165445D01*
G01X-2197Y1155130D02*
X-2001Y1154792D01*
G01X-3151Y1157256D02*
X-3364Y1157626D01*
G01X-2197Y1159067D02*
X-2001Y1158729D01*
G01X-10631Y1161154D02*
X-9844Y1161508D01*
G01X-10631Y1157217D02*
X-9844Y1157571D01*
G01X-3151Y1161193D02*
X-3364Y1161563D01*
G01X-2197Y1163004D02*
X-2001Y1162666D01*
G01X-3151Y1165130D02*
X-3364Y1165500D01*
G01X-2197Y1166941D02*
X-2001Y1166603D01*
G01X8854Y1156869D02*
X8385Y1157263D01*
G01X-10631Y1155170D02*
X-9844Y1154815D01*
G01X-10631Y1159107D02*
X-9844Y1158752D01*
G01X-10631Y1163044D02*
X-9844Y1162689D01*
G01X-10631Y1166981D02*
X-9844Y1166626D01*
G01X-6545Y1154792D02*
X-6694Y1154815D01*
G01X-6545Y1158729D02*
X-6694Y1158752D01*
G01X-6545Y1162666D02*
X-6694Y1162689D01*
G01X-6545Y1166603D02*
X-6694Y1166626D01*
G01X-4259Y1154973D02*
X-3582Y1154792D01*
G01X-4259Y1158910D02*
X-3582Y1158729D01*
G01X-4259Y1162847D02*
X-3582Y1162666D01*
G01X-4259Y1166784D02*
X-3582Y1166603D01*
G01X24802Y1150796D02*
X-1D01*
G01X11534Y1153916D02*
X8385D01*
G01X8787Y1154310D02*
X9725D01*
G01X-9844Y1154815D02*
X-6694D01*
G01X-4725Y1154973D02*
X-4259D01*
G01X-3151Y1155130D02*
X-2197D01*
G01X-4725Y1155406D02*
X-6694D01*
G01X9000Y1155524D02*
X-1D01*
G01D02*
X-985D01*
G01X-1Y1156863D02*
X9000D01*
G01X-985D02*
X-1D01*
G01X-4725Y1156981D02*
X-6694D01*
G01X-3151Y1157256D02*
X-2197D01*
G01X-4259Y1157414D02*
X-4725D01*
G01X-6694Y1157571D02*
X-9844D01*
G01X8385Y1157656D02*
X11534D01*
G01X-9844Y1158752D02*
X-6694D01*
G01X-4725Y1158910D02*
X-4259D01*
G01X-3151Y1159067D02*
X-2197D01*
G01X-4725Y1159343D02*
X-6694D01*
G01X9000Y1159461D02*
X-1D01*
G01D02*
X-985D01*
G01X-1Y1160800D02*
X9000D01*
G01X-985D02*
X-1D01*
G01X-4725Y1160918D02*
X-6694D01*
G01X-3151Y1161193D02*
X-2197D01*
G01X-4259Y1161351D02*
X-4725D01*
G01X-6694Y1161508D02*
X-9844D01*
G01Y1162689D02*
X-6694D01*
G01X-4725Y1162847D02*
X-4259D01*
G01X-3151Y1163004D02*
X-2197D01*
G01X-4725Y1163280D02*
X-6694D01*
G01X9000Y1163398D02*
X-1D01*
G01D02*
X-985D01*
G01X-1Y1164737D02*
X9000D01*
G01X-985D02*
X-1D01*
G01X-4725Y1164855D02*
X-6694D01*
G01X-3151Y1165130D02*
X-2197D01*
G01X-4259Y1165288D02*
X-4725D01*
G01X-6694Y1165445D02*
X-9844D01*
G01Y1166626D02*
X-6694D01*
G01X-4725Y1166784D02*
X-4259D01*
G01X-3151Y1166941D02*
X-2197D01*
G01X-4725Y1167217D02*
X-6694D01*
G01X9000Y1167335D02*
X-1D01*
G01D02*
X-985D01*
G01X-3467Y1157626D02*
X-4259Y1157414D01*
G01X-3467Y1161563D02*
X-4259Y1161351D01*
G01X-3467Y1165500D02*
X-4259Y1165288D01*
G01X-6351Y1157626D02*
X-6694Y1157571D01*
G01X-6351Y1161563D02*
X-6694Y1161508D01*
G01X-6351Y1165500D02*
X-6694Y1165445D01*
G01X-10531Y1188758D02*
Y1186621D01*
G01Y1184821D02*
Y1182684D01*
G01Y1176947D02*
Y1174810D01*
G01Y1180884D02*
Y1178747D01*
G01Y1173010D02*
Y1170873D01*
G01X-6694Y1186902D02*
Y1186311D01*
G01Y1189067D02*
Y1188477D01*
G01Y1181193D02*
Y1180603D01*
G01Y1185130D02*
Y1184540D01*
G01Y1182965D02*
Y1182374D01*
G01Y1177256D02*
Y1176666D01*
G01Y1179028D02*
Y1178437D01*
G01Y1173319D02*
Y1172729D01*
G01Y1175091D02*
Y1174500D01*
G01Y1169382D02*
Y1168792D01*
G01Y1171154D02*
Y1170563D01*
G01X-6038Y1186603D02*
Y1186288D01*
G01Y1181248D02*
Y1180933D01*
G01Y1182666D02*
Y1182351D01*
G01Y1185185D02*
Y1184870D01*
G01Y1177311D02*
Y1176996D01*
G01Y1178729D02*
Y1178414D01*
G01Y1173374D02*
Y1173059D01*
G01Y1174792D02*
Y1174477D01*
G01Y1169437D02*
Y1169122D01*
G01Y1170855D02*
Y1170540D01*
G01X-4725Y1168792D02*
Y1169437D01*
G01Y1170540D02*
Y1171154D01*
G01Y1172729D02*
Y1173374D01*
G01Y1174477D02*
Y1175091D01*
G01Y1176666D02*
Y1177311D01*
G01Y1178414D02*
Y1179028D01*
G01Y1180603D02*
Y1181248D01*
G01Y1182351D02*
Y1182965D01*
G01Y1184540D02*
Y1185185D01*
G01Y1188477D02*
Y1189122D01*
G01Y1186288D02*
Y1186902D01*
G01X-3757Y1188807D02*
Y1186603D01*
G01Y1184870D02*
Y1182666D01*
G01Y1180933D02*
Y1178729D01*
G01Y1176996D02*
Y1174792D01*
G01Y1173059D02*
Y1170855D01*
G01X-3346Y1186288D02*
X-3151Y1186626D01*
G01X-1983Y1185185D02*
X-2197Y1184815D01*
G01X-3346Y1182351D02*
X-3151Y1182689D01*
G01X-1983Y1181248D02*
X-2197Y1180878D01*
G01X-3346Y1178414D02*
X-3151Y1178752D01*
G01X-1983Y1177311D02*
X-2197Y1176941D01*
G01X-3346Y1174477D02*
X-3151Y1174815D01*
G01X-1983Y1173374D02*
X-2197Y1173004D01*
G01X-3346Y1170540D02*
X-3151Y1170878D01*
G01X-1983Y1169437D02*
X-2197Y1169067D01*
G01X-2521Y1188807D02*
Y1186603D01*
G01Y1184870D02*
Y1182666D01*
G01Y1180933D02*
Y1178729D01*
G01Y1176996D02*
Y1174792D01*
G01Y1173059D02*
Y1170855D01*
G01X-2251Y1189122D02*
Y1186288D01*
G01Y1185185D02*
Y1182351D01*
G01Y1181248D02*
Y1178414D01*
G01Y1177311D02*
Y1174477D01*
G01Y1173374D02*
Y1170540D01*
G01X-985Y1188359D02*
Y1187020D01*
G01Y1184422D02*
Y1183083D01*
G01Y1176548D02*
Y1175209D01*
G01Y1180485D02*
Y1179146D01*
G01Y1172611D02*
Y1171272D01*
G01X196Y1188359D02*
Y1187020D01*
G01Y1184422D02*
Y1183083D01*
G01Y1176548D02*
Y1175209D01*
G01Y1180485D02*
Y1179146D01*
G01Y1172611D02*
Y1171272D01*
G01X-10631Y1184776D02*
X-9844Y1185130D01*
G01X-10631Y1180839D02*
X-9844Y1181193D01*
G01X-10631Y1176902D02*
X-9844Y1177256D01*
G01X-10631Y1172965D02*
X-9844Y1173319D01*
G01X-10631Y1169028D02*
X-9844Y1169382D01*
G01X-3151Y1169067D02*
X-3364Y1169437D01*
G01X-2197Y1170878D02*
X-2001Y1170540D01*
G01X-3151Y1173004D02*
X-3364Y1173374D01*
G01X-2197Y1174815D02*
X-2001Y1174477D01*
G01X-3151Y1176941D02*
X-3364Y1177311D01*
G01X-2197Y1178752D02*
X-2001Y1178414D01*
G01X-3151Y1180878D02*
X-3364Y1181248D01*
G01X-2197Y1182689D02*
X-2001Y1182351D01*
G01X-3151Y1184815D02*
X-3364Y1185185D01*
G01X-2197Y1186626D02*
X-2001Y1186288D01*
G01X-10631Y1170918D02*
X-9844Y1170563D01*
G01X-10631Y1174855D02*
X-9844Y1174500D01*
G01X-10631Y1178792D02*
X-9844Y1178437D01*
G01X-10631Y1182729D02*
X-9844Y1182374D01*
G01X-10631Y1186666D02*
X-9844Y1186311D01*
G01X-4259Y1170721D02*
X-3582Y1170540D01*
G01X-4259Y1174658D02*
X-3582Y1174477D01*
G01X-4259Y1178595D02*
X-3582Y1178414D01*
G01X-4259Y1182532D02*
X-3582Y1182351D01*
G01X-4259Y1186469D02*
X-3582Y1186288D01*
G01X-6545Y1170540D02*
X-6694Y1170563D01*
G01X-6545Y1174477D02*
X-6694Y1174500D01*
G01X-6545Y1178414D02*
X-6694Y1178437D01*
G01X-6545Y1182351D02*
X-6694Y1182374D01*
G01X-6545Y1186288D02*
X-6694Y1186311D01*
G01X-1Y1168674D02*
X9000D01*
G01X-985D02*
X-1D01*
G01X-4725Y1168792D02*
X-6694D01*
G01X-3151Y1169067D02*
X-2197D01*
G01X-4259Y1169225D02*
X-4725D01*
G01X-6694Y1169382D02*
X-9844D01*
G01Y1170563D02*
X-6694D01*
G01X-4725Y1170721D02*
X-4259D01*
G01X-3151Y1170878D02*
X-2197D01*
G01X-4725Y1171154D02*
X-6694D01*
G01X9000Y1171272D02*
X-1D01*
G01D02*
X-985D01*
G01X-1Y1172611D02*
X9000D01*
G01X-985D02*
X-1D01*
G01X-4725Y1172729D02*
X-6694D01*
G01X-3151Y1173004D02*
X-2197D01*
G01X-4259Y1173162D02*
X-4725D01*
G01X-6694Y1173319D02*
X-9844D01*
G01Y1174500D02*
X-6694D01*
G01X-4725Y1174658D02*
X-4259D01*
G01X-3151Y1174815D02*
X-2197D01*
G01X-4725Y1175091D02*
X-6694D01*
G01X9000Y1175209D02*
X-1D01*
G01D02*
X-985D01*
G01X-1Y1176548D02*
X9000D01*
G01X-985D02*
X-1D01*
G01X-4725Y1176666D02*
X-6694D01*
G01X-3151Y1176941D02*
X-2197D01*
G01X-4259Y1177099D02*
X-4725D01*
G01X-6694Y1177256D02*
X-9844D01*
G01Y1178437D02*
X-6694D01*
G01X-4725Y1178595D02*
X-4259D01*
G01X-3151Y1178752D02*
X-2197D01*
G01X-4725Y1179028D02*
X-6694D01*
G01X9000Y1179146D02*
X-1D01*
G01D02*
X-985D01*
G01X-1Y1180485D02*
X9000D01*
G01X-985D02*
X-1D01*
G01X-4725Y1180603D02*
X-6694D01*
G01X-3151Y1180878D02*
X-2197D01*
G01X-4259Y1181036D02*
X-4725D01*
G01X-6694Y1181193D02*
X-9844D01*
G01Y1182374D02*
X-6694D01*
G01X-4725Y1182532D02*
X-4259D01*
G01X-3151Y1182689D02*
X-2197D01*
G01X-4725Y1182965D02*
X-6694D01*
G01X9000Y1183083D02*
X-1D01*
G01D02*
X-985D01*
G01X-1Y1184422D02*
X9000D01*
G01X-985D02*
X-1D01*
G01X-4725Y1184540D02*
X-6694D01*
G01X-3151Y1184815D02*
X-2197D01*
G01X-4259Y1184973D02*
X-4725D01*
G01X-6694Y1185130D02*
X-9844D01*
G01Y1186311D02*
X-6694D01*
G01X-4725Y1186469D02*
X-4259D01*
G01X-3151Y1186626D02*
X-2197D01*
G01X-4725Y1186902D02*
X-6694D01*
G01X9000Y1187020D02*
X-1D01*
G01D02*
X-985D01*
G01X-1Y1188359D02*
X9000D01*
G01X-985D02*
X-1D01*
G01X-4725Y1188477D02*
X-6694D01*
G01X-3467Y1169437D02*
X-4259Y1169225D01*
G01X-3467Y1173374D02*
X-4259Y1173162D01*
G01X-3467Y1177311D02*
X-4259Y1177099D01*
G01X-3467Y1181248D02*
X-4259Y1181036D01*
G01X-6351Y1169437D02*
X-6694Y1169382D01*
G01X-6351Y1173374D02*
X-6694Y1173319D01*
G01X-6351Y1177311D02*
X-6694Y1177256D01*
G01X-6351Y1181248D02*
X-6694Y1181193D01*
G01X-6351Y1185185D02*
X-6694Y1185130D01*
G01X-3467Y1185185D02*
X-4259Y1184973D01*
G01X-10531Y1208443D02*
Y1206306D01*
G01Y1196632D02*
Y1194495D01*
G01Y1192695D02*
Y1190558D01*
G01X-9607Y1204989D02*
Y1235107D01*
G01X-6694Y1208752D02*
Y1208162D01*
G01Y1206587D02*
Y1205996D01*
G01Y1196941D02*
Y1196351D01*
G01Y1194776D02*
Y1194185D01*
G01Y1190839D02*
Y1190248D01*
G01Y1193004D02*
Y1192414D01*
G01X-6038Y1206288D02*
Y1205973D01*
G01Y1208807D02*
Y1208493D01*
G01Y1196996D02*
Y1196681D01*
G01Y1194477D02*
Y1194162D01*
G01Y1193059D02*
Y1192744D01*
G01Y1190540D02*
Y1190225D01*
G01Y1189122D02*
Y1188807D01*
G01X-4725Y1194162D02*
Y1194776D01*
G01Y1192414D02*
Y1193059D01*
G01Y1190225D02*
Y1190839D01*
G01Y1196351D02*
Y1196996D01*
G01Y1205973D02*
Y1206587D01*
G01Y1208162D02*
Y1208807D01*
G01X-3757Y1208493D02*
Y1206288D01*
G01Y1196681D02*
Y1194477D01*
G01Y1192744D02*
Y1190540D01*
G01X-1983Y1208807D02*
X-2197Y1208437D01*
G01X-3346Y1205973D02*
X-3151Y1206311D01*
G01X-1983Y1196996D02*
X-2197Y1196626D01*
G01X-3346Y1194162D02*
X-3151Y1194500D01*
G01X-1983Y1193059D02*
X-2197Y1192689D01*
G01X-3346Y1190225D02*
X-3151Y1190563D01*
G01X-1983Y1189122D02*
X-2197Y1188752D01*
G01X-2521Y1208493D02*
Y1206288D01*
G01Y1196681D02*
Y1194477D01*
G01Y1192744D02*
Y1190540D01*
G01X-2251Y1208807D02*
Y1205973D01*
G01Y1196996D02*
Y1194162D01*
G01Y1193059D02*
Y1190225D01*
G01X-985Y1208044D02*
Y1206705D01*
G01Y1196233D02*
Y1194894D01*
G01Y1192296D02*
Y1190957D01*
G01X-1Y1207283D02*
Y1262213D01*
G01X196Y1208044D02*
Y1206705D01*
G01Y1196233D02*
Y1194894D01*
G01Y1192296D02*
Y1190957D01*
G01X-1Y1195866D02*
X281Y1196148D01*
G01D02*
X1968Y1197835D01*
G01X-10631Y1208398D02*
X-9844Y1208752D01*
G01X-10631Y1196587D02*
X-9844Y1196941D01*
G01X-10631Y1192650D02*
X-9844Y1193004D01*
G01X-10631Y1188713D02*
X-9844Y1189067D01*
G01X-3151Y1188752D02*
X-3364Y1189122D01*
G01X-2197Y1190563D02*
X-2001Y1190225D01*
G01X-3151Y1192689D02*
X-3364Y1193059D01*
G01X-2197Y1194500D02*
X-2001Y1194162D01*
G01X-3151Y1196626D02*
X-3364Y1196996D01*
G01X-2197Y1206311D02*
X-2001Y1205973D01*
G01X-3151Y1208437D02*
X-3364Y1208807D01*
G01X1968Y1205315D02*
X387Y1206896D01*
G01D02*
X-1Y1207283D01*
G01X-10631Y1190603D02*
X-9844Y1190248D01*
G01X-10631Y1194540D02*
X-9844Y1194185D01*
G01X-10631Y1206351D02*
X-9844Y1205996D01*
G01X-4259Y1190406D02*
X-3582Y1190225D01*
G01X-4259Y1194343D02*
X-3582Y1194162D01*
G01X-4259Y1206154D02*
X-3582Y1205973D01*
G01X-6545Y1190225D02*
X-6694Y1190248D01*
G01X-6545Y1194162D02*
X-6694Y1194185D01*
G01X-6545Y1205973D02*
X-6694Y1205996D01*
G01X-3151Y1188752D02*
X-2197D01*
G01X-4259Y1188910D02*
X-4725D01*
G01X-6694Y1189067D02*
X-9844D01*
G01Y1190248D02*
X-6694D01*
G01X-4725Y1190406D02*
X-4259D01*
G01X-3151Y1190563D02*
X-2197D01*
G01X-4725Y1190839D02*
X-6694D01*
G01X9000Y1190957D02*
X-1D01*
G01D02*
X-985D01*
G01X-1Y1192296D02*
X9000D01*
G01X-985D02*
X-1D01*
G01X-4725Y1192414D02*
X-6694D01*
G01X-3151Y1192689D02*
X-2197D01*
G01X-4259Y1192847D02*
X-4725D01*
G01X-6694Y1193004D02*
X-9844D01*
G01Y1194185D02*
X-6694D01*
G01X-4725Y1194343D02*
X-4259D01*
G01X-3151Y1194500D02*
X-2197D01*
G01X-4725Y1194776D02*
X-6694D01*
G01X9000Y1194894D02*
X-1D01*
G01D02*
X-985D01*
G01X-1Y1196233D02*
X9000D01*
G01X-985D02*
X-1D01*
G01X-4725Y1196351D02*
X-6694D01*
G01X-3151Y1196626D02*
X-2197D01*
G01X-4259Y1196784D02*
X-4725D01*
G01X-6694Y1196941D02*
X-9844D01*
G01X1968Y1197835D02*
X19881D01*
G01X-1Y1198089D02*
X15550D01*
G01X-1Y1205097D02*
X15550D01*
G01X19881Y1205315D02*
X1968D01*
G01X-9844Y1205996D02*
X-6694D01*
G01X-4725Y1206154D02*
X-4259D01*
G01X-3151Y1206311D02*
X-2197D01*
G01X-4725Y1206587D02*
X-6694D01*
G01X9000Y1206705D02*
X-1D01*
G01D02*
X-985D01*
G01X-1Y1208044D02*
X9000D01*
G01X-985D02*
X-1D01*
G01X-4725Y1208162D02*
X-6694D01*
G01X-3151Y1208437D02*
X-2197D01*
G01X-4259Y1208595D02*
X-4725D01*
G01X-6351Y1189122D02*
X-6694Y1189067D01*
G01X-6351Y1193059D02*
X-6694Y1193004D01*
G01X-6351Y1196996D02*
X-6694Y1196941D01*
G01X-3467Y1189122D02*
X-4259Y1188910D01*
G01X-3467Y1193059D02*
X-4259Y1192847D01*
G01X-3467Y1196996D02*
X-4259Y1196784D01*
G01X-3467Y1208807D02*
X-4259Y1208595D01*
G01X-10531Y1224191D02*
Y1222054D01*
G01Y1220254D02*
Y1218117D01*
G01Y1216317D02*
Y1214180D01*
G01Y1212380D02*
Y1210243D01*
G01X-6694Y1224500D02*
Y1223910D01*
G01Y1222335D02*
Y1221744D01*
G01Y1220563D02*
Y1219973D01*
G01Y1218398D02*
Y1217807D01*
G01Y1216626D02*
Y1216036D01*
G01Y1214461D02*
Y1213870D01*
G01Y1212689D02*
Y1212099D01*
G01Y1210524D02*
Y1209933D01*
G01X-6038Y1224556D02*
Y1224241D01*
G01Y1222036D02*
Y1221721D01*
G01Y1220619D02*
Y1220304D01*
G01Y1218099D02*
Y1217784D01*
G01Y1214162D02*
Y1213847D01*
G01Y1216681D02*
Y1216367D01*
G01Y1210225D02*
Y1209910D01*
G01Y1212744D02*
Y1212430D01*
G01X-4725Y1209910D02*
Y1210524D01*
G01Y1212099D02*
Y1212744D01*
G01Y1217784D02*
Y1218398D01*
G01Y1213847D02*
Y1214461D01*
G01Y1216036D02*
Y1216681D01*
G01Y1221721D02*
Y1222335D01*
G01Y1219973D02*
Y1220619D01*
G01Y1223910D02*
Y1224556D01*
G01X-3757Y1224241D02*
Y1222036D01*
G01Y1220304D02*
Y1218099D01*
G01Y1216367D02*
Y1214162D01*
G01Y1212430D02*
Y1210225D01*
G01X-1983Y1224556D02*
X-2197Y1224185D01*
G01X-3346Y1221721D02*
X-3151Y1222059D01*
G01X-1983Y1220619D02*
X-2197Y1220248D01*
G01X-3346Y1217784D02*
X-3151Y1218122D01*
G01X-1983Y1216681D02*
X-2197Y1216311D01*
G01X-3346Y1213847D02*
X-3151Y1214185D01*
G01X-1983Y1212744D02*
X-2197Y1212374D01*
G01X-3346Y1209910D02*
X-3151Y1210248D01*
G01X-2521Y1224241D02*
Y1222036D01*
G01Y1220304D02*
Y1218099D01*
G01Y1216367D02*
Y1214162D01*
G01Y1212430D02*
Y1210225D01*
G01X-2251Y1224556D02*
Y1221721D01*
G01Y1220619D02*
Y1217784D01*
G01Y1216681D02*
Y1213847D01*
G01Y1212744D02*
Y1209910D01*
G01X-985Y1223792D02*
Y1222453D01*
G01Y1219855D02*
Y1218516D01*
G01Y1215918D02*
Y1214579D01*
G01Y1211981D02*
Y1210642D01*
G01X196Y1223792D02*
Y1222453D01*
G01Y1219855D02*
Y1218516D01*
G01Y1215918D02*
Y1214579D01*
G01Y1211981D02*
Y1210642D01*
G01X-10631Y1224146D02*
X-9844Y1224500D01*
G01X-10631Y1220209D02*
X-9844Y1220563D01*
G01X-10631Y1216272D02*
X-9844Y1216626D01*
G01X-10631Y1212335D02*
X-9844Y1212689D01*
G01X-2197Y1210248D02*
X-2001Y1209910D01*
G01X-3151Y1212374D02*
X-3364Y1212744D01*
G01X-2197Y1214185D02*
X-2001Y1213847D01*
G01X-3151Y1216311D02*
X-3364Y1216681D01*
G01X-2197Y1218122D02*
X-2001Y1217784D01*
G01X-3151Y1220248D02*
X-3364Y1220619D01*
G01X-2197Y1222059D02*
X-2001Y1221721D01*
G01X-3151Y1224185D02*
X-3364Y1224556D01*
G01X-10631Y1210288D02*
X-9844Y1209933D01*
G01X-10631Y1214225D02*
X-9844Y1213870D01*
G01X-10631Y1218162D02*
X-9844Y1217807D01*
G01X-10631Y1222099D02*
X-9844Y1221744D01*
G01X-4259Y1210091D02*
X-3582Y1209910D01*
G01X-4259Y1214028D02*
X-3582Y1213847D01*
G01X-4259Y1217965D02*
X-3582Y1217784D01*
G01X-4259Y1221902D02*
X-3582Y1221721D01*
G01X-6545Y1209910D02*
X-6694Y1209933D01*
G01X-6545Y1213847D02*
X-6694Y1213870D01*
G01X-6545Y1217784D02*
X-6694Y1217807D01*
G01X-6545Y1221721D02*
X-6694Y1221744D01*
G01Y1208752D02*
X-9844D01*
G01Y1209933D02*
X-6694D01*
G01X-4725Y1210091D02*
X-4259D01*
G01X-3151Y1210248D02*
X-2197D01*
G01X-4725Y1210524D02*
X-6694D01*
G01X9000Y1210642D02*
X-1D01*
G01D02*
X-985D01*
G01X-1Y1211981D02*
X9000D01*
G01X-985D02*
X-1D01*
G01X-4725Y1212099D02*
X-6694D01*
G01X-3151Y1212374D02*
X-2197D01*
G01X-4259Y1212532D02*
X-4725D01*
G01X-6694Y1212689D02*
X-9844D01*
G01Y1213870D02*
X-6694D01*
G01X-4725Y1214028D02*
X-4259D01*
G01X-3151Y1214185D02*
X-2197D01*
G01X-4725Y1214461D02*
X-6694D01*
G01X9000Y1214579D02*
X-1D01*
G01D02*
X-985D01*
G01X-1Y1215918D02*
X9000D01*
G01X-985D02*
X-1D01*
G01X-4725Y1216036D02*
X-6694D01*
G01X-3151Y1216311D02*
X-2197D01*
G01X-4259Y1216469D02*
X-4725D01*
G01X-6694Y1216626D02*
X-9844D01*
G01Y1217807D02*
X-6694D01*
G01X-4725Y1217965D02*
X-4259D01*
G01X-3151Y1218122D02*
X-2197D01*
G01X-4725Y1218398D02*
X-6694D01*
G01X9000Y1218516D02*
X-1D01*
G01D02*
X-985D01*
G01X-1Y1219855D02*
X9000D01*
G01X-985D02*
X-1D01*
G01X-4725Y1219973D02*
X-6694D01*
G01X-3151Y1220248D02*
X-2197D01*
G01X-4259Y1220406D02*
X-4725D01*
G01X-6694Y1220563D02*
X-9844D01*
G01Y1221744D02*
X-6694D01*
G01X-4725Y1221902D02*
X-4259D01*
G01X-3151Y1222059D02*
X-2197D01*
G01X-4725Y1222335D02*
X-6694D01*
G01X9000Y1222453D02*
X-1D01*
G01D02*
X-985D01*
G01X-1Y1223792D02*
X9000D01*
G01X-985D02*
X-1D01*
G01X-4725Y1223910D02*
X-6694D01*
G01X-3151Y1224185D02*
X-2197D01*
G01X-4259Y1224343D02*
X-4725D01*
G01X-6694Y1224500D02*
X-9844D01*
G01X-6351Y1208807D02*
X-6694Y1208752D01*
G01X-6351Y1212744D02*
X-6694Y1212689D01*
G01X-6351Y1216681D02*
X-6694Y1216626D01*
G01X-6351Y1220619D02*
X-6694Y1220563D01*
G01X-6351Y1224556D02*
X-6694Y1224500D01*
G01X-3467Y1212744D02*
X-4259Y1212532D01*
G01X-3467Y1216681D02*
X-4259Y1216469D01*
G01X-3467Y1220619D02*
X-4259Y1220406D01*
G01X-3467Y1224556D02*
X-4259Y1224343D01*
G01X10127Y1155557D02*
X10194Y1155754D01*
G01X9926Y1155950D02*
X9993Y1156081D01*
G01X9000Y1168674D02*
Y1167335D01*
G01Y1164737D02*
Y1163398D01*
G01Y1160800D02*
Y1159461D01*
G01Y1156863D02*
Y1155524D01*
G01X9725Y1154310D02*
Y1155557D01*
G01X10127Y1154310D02*
Y1155557D01*
G01X11132D02*
Y1154310D01*
G01X11534Y1157656D02*
Y1157263D01*
G01Y1155491D02*
Y1153916D01*
G01X8988Y1155885D02*
X8854Y1155754D01*
G01X10194D02*
X10329Y1155885D01*
G01X11468Y1155819D02*
X11534Y1155491D01*
G01X9993Y1156081D02*
X10261Y1156278D01*
G01X9859Y1156081D02*
X9926Y1155950D01*
G01X9725Y1155557D02*
X9658Y1155754D01*
G01X11066D02*
X11132Y1155557D01*
G01X8921Y1156278D02*
X9122Y1156344D01*
G01X9189Y1155950D02*
X8988Y1155885D01*
G01X10261Y1156278D02*
X10462Y1156344D01*
G01X10329Y1155885D02*
X10529Y1155950D01*
G01X11267Y1156081D02*
X11468Y1155819D01*
G01X9658Y1155754D02*
X9524Y1155885D01*
G01X10931D02*
X11066Y1155754D01*
G01X9591Y1156278D02*
X9859Y1156081D01*
G01X10999Y1156278D02*
X11267Y1156081D01*
G01X8921Y1157263D02*
X9390Y1156869D01*
G01X9524Y1155885D02*
X9323Y1155950D01*
G01X9390Y1156344D02*
X9591Y1156278D01*
G01X10730Y1155950D02*
X10931Y1155885D01*
G01X10797Y1156344D02*
X10999Y1156278D01*
G01X11132Y1154310D02*
X10127D01*
G01X12829Y1155524D02*
X9000D01*
G01X9323Y1155950D02*
X9189D01*
G01X10529D02*
X10730D01*
G01X9122Y1156344D02*
X9390D01*
G01X10462D02*
X10797D01*
G01X9000Y1156863D02*
X12829D01*
G01X9390Y1156869D02*
X8854D01*
G01X11534Y1157263D02*
X8921D01*
G01X12829Y1159461D02*
X9000D01*
G01Y1160800D02*
X12829D01*
G01Y1163398D02*
X9000D01*
G01Y1164737D02*
X12829D01*
G01Y1167335D02*
X9000D01*
G01Y1188359D02*
Y1187020D01*
G01Y1184422D02*
Y1183083D01*
G01Y1176548D02*
Y1175209D01*
G01Y1180485D02*
Y1179146D01*
G01Y1172611D02*
Y1171272D01*
G01Y1168674D02*
X12829D01*
G01Y1171272D02*
X9000D01*
G01Y1172611D02*
X12829D01*
G01Y1175209D02*
X9000D01*
G01Y1176548D02*
X12829D01*
G01Y1179146D02*
X9000D01*
G01Y1180485D02*
X12829D01*
G01Y1183083D02*
X9000D01*
G01Y1184422D02*
X12829D01*
G01Y1187020D02*
X9000D01*
G01Y1188359D02*
X12829D01*
G01X9000Y1208044D02*
Y1206705D01*
G01Y1196233D02*
Y1194894D01*
G01Y1192296D02*
Y1190957D01*
G01X12829D02*
X9000D01*
G01Y1192296D02*
X12829D01*
G01Y1194894D02*
X9000D01*
G01Y1196233D02*
X12829D01*
G01Y1206705D02*
X9000D01*
G01Y1208044D02*
X12829D01*
G01X9000Y1223792D02*
Y1222453D01*
G01Y1219855D02*
Y1218516D01*
G01Y1215918D02*
Y1214579D01*
G01Y1211981D02*
Y1210642D01*
G01X12829D02*
X9000D01*
G01Y1211981D02*
X12829D01*
G01Y1214579D02*
X9000D01*
G01Y1215918D02*
X12829D01*
G01Y1218516D02*
X9000D01*
G01Y1219855D02*
X12829D01*
G01Y1222453D02*
X9000D01*
G01Y1223792D02*
X12829D01*
G01X-40595Y1294252D02*
G03I-4292J0D01*
G01X-38426Y1228256D02*
Y1225894D01*
G01X-36192Y1227727D02*
Y1226393D01*
G01X-35595Y1227784D02*
Y1226335D01*
G01X-35546Y1228256D02*
Y1227789D01*
G01Y1226330D02*
Y1225894D01*
G01X-35331Y1227809D02*
Y1226311D01*
G01X-34607Y1228178D02*
Y1225973D01*
G01X-34136Y1226298D02*
Y1227821D01*
G01X-33153Y1227832D02*
Y1226287D01*
G01X-31995Y1227845D02*
Y1226274D01*
G01X-31725Y1227848D02*
Y1226271D01*
G01X-35351Y1227807D02*
X-10631Y1228083D01*
G01X-39607Y1225894D02*
X-24509D01*
G01X-35546Y1225973D02*
X-1D01*
G01X-39607Y1226386D02*
X-24844D01*
G01X-35546Y1228178D02*
X-1D01*
G01X-24509Y1228256D02*
X-39607D01*
G01X-35351Y1226311D02*
X-10631Y1226036D01*
G01X-36192Y1226393D02*
X-35351Y1226311D01*
G01X-36192Y1227727D02*
X-35341Y1227809D01*
G01X-38426Y1232193D02*
Y1229831D01*
G01X-36192Y1231664D02*
Y1230330D01*
G01X-35595Y1231721D02*
Y1230272D01*
G01X-35546Y1230267D02*
Y1229831D01*
G01Y1232193D02*
Y1231726D01*
G01X-35331Y1231746D02*
Y1230248D01*
G01X-34607Y1232115D02*
Y1229910D01*
G01X-34136Y1230235D02*
Y1231758D01*
G01X-33153Y1231769D02*
Y1230224D01*
G01X-31995Y1231782D02*
Y1230211D01*
G01X-31725Y1231785D02*
Y1230208D01*
G01X-39607Y1237781D02*
X-36561Y1235648D01*
G01X-27993Y1229536D02*
X-39607D01*
G01Y1229831D02*
X-24509D01*
G01X-35546Y1229910D02*
X-1D01*
G01X-35546Y1232115D02*
X-1D01*
G01X-24509Y1232193D02*
X-39607D01*
G01X-35351Y1230248D02*
X-10631Y1229973D01*
G01X-36192Y1230330D02*
X-35351Y1230248D01*
G01X-36192Y1231664D02*
X-35341Y1231746D01*
G01X-35351Y1231744D02*
X-10631Y1232020D01*
G01X-9607Y1235107D02*
X-34845D01*
G01X-27993Y1239772D02*
X-39607D01*
G01Y1242922D02*
X-1D01*
G01X-36561Y1235648D02*
G03X-34845Y1235107I1716J2451D01*
G01X-27993Y1226386D02*
Y1242922D01*
G01X-27265Y1228256D02*
Y1225894D01*
G01X-26511Y1227906D02*
Y1226213D01*
G01X-26242Y1227909D02*
Y1226210D01*
G01X-24844Y1226386D02*
Y1242922D01*
G01X-24509Y1228256D02*
Y1225894D01*
G01X-23998Y1227934D02*
Y1226185D01*
G01X-23519Y1227940D02*
Y1226180D01*
G01X-12993Y1228493D02*
Y1228178D01*
G01Y1225973D02*
Y1225658D01*
G01X-12445Y1228063D02*
Y1226056D01*
G01X-11967Y1226051D02*
Y1228069D01*
G01X-12993Y1225658D02*
X-1D01*
G01Y1228493D02*
X-12993D01*
G01X-27265Y1232193D02*
Y1229831D01*
G01X-26511Y1231843D02*
Y1230150D01*
G01X-26242Y1231846D02*
Y1230147D01*
G01X-24509Y1232193D02*
Y1229831D01*
G01X-23998Y1231871D02*
Y1230122D01*
G01X-23519Y1231877D02*
Y1230117D01*
G01X-12993Y1229910D02*
Y1229595D01*
G01Y1232430D02*
Y1232115D01*
G01X-12445Y1232000D02*
Y1229993D01*
G01X-11967Y1229988D02*
Y1232006D01*
G01X-12993Y1229595D02*
X-1D01*
G01Y1232430D02*
X-12993D01*
G01X-10531Y1228128D02*
Y1225991D01*
G01X-6694Y1228437D02*
Y1227847D01*
G01Y1226272D02*
Y1225681D01*
G01X-6038Y1228493D02*
Y1228178D01*
G01Y1225973D02*
Y1225658D01*
G01X-4725D02*
Y1226272D01*
G01Y1227847D02*
Y1228493D01*
G01X-3757Y1228178D02*
Y1225973D01*
G01X-1983Y1228493D02*
X-2197Y1228122D01*
G01X-3346Y1225658D02*
X-3151Y1225996D01*
G01X-2521Y1228178D02*
Y1225973D01*
G01X-2251Y1228493D02*
Y1225658D01*
G01X-985Y1227729D02*
Y1226390D01*
G01X196Y1227729D02*
Y1226390D01*
G01X-10631Y1228083D02*
X-9844Y1228437D01*
G01X-2197Y1225996D02*
X-2001Y1225658D01*
G01X-3151Y1228122D02*
X-3364Y1228493D01*
G01X-10631Y1226036D02*
X-9844Y1225681D01*
G01X-4259Y1225839D02*
X-3582Y1225658D01*
G01X-6545D02*
X-6694Y1225681D01*
G01X-9844D02*
X-6694D01*
G01X-4725Y1225839D02*
X-4259D01*
G01X-3151Y1225996D02*
X-2197D01*
G01X-4725Y1226272D02*
X-6694D01*
G01X9000Y1226390D02*
X-1D01*
G01D02*
X-985D01*
G01X-1Y1227729D02*
X9000D01*
G01X-985D02*
X-1D01*
G01X-4725Y1227847D02*
X-6694D01*
G01X-3151Y1228122D02*
X-2197D01*
G01X-4259Y1228280D02*
X-4725D01*
G01X-6694Y1228437D02*
X-9844D01*
G01X-6351Y1228493D02*
X-6694Y1228437D01*
G01X-3467Y1228493D02*
X-4259Y1228280D01*
G01X-10531Y1232065D02*
Y1229928D01*
G01X-9056Y1262213D02*
Y1242922D01*
G01X-6694Y1230209D02*
Y1229619D01*
G01Y1232374D02*
Y1231784D01*
G01X-6038Y1229910D02*
Y1229595D01*
G01Y1232430D02*
Y1232115D01*
G01X-4725Y1231784D02*
Y1232430D01*
G01Y1229595D02*
Y1230209D01*
G01X-3757Y1232115D02*
Y1229910D01*
G01X-1983Y1232430D02*
X-2197Y1232059D01*
G01X-3346Y1229595D02*
X-3151Y1229933D01*
G01X-2521Y1232115D02*
Y1229910D01*
G01X-2251Y1232430D02*
Y1229595D01*
G01X-985Y1231666D02*
Y1230327D01*
G01X-1Y1242922D02*
Y1262213D01*
G01X196Y1231666D02*
Y1230327D01*
G01X-10631Y1232020D02*
X-9844Y1232374D01*
G01X-2197Y1229933D02*
X-2001Y1229595D01*
G01X-3151Y1232059D02*
X-3364Y1232430D01*
G01X-10631Y1229973D02*
X-9844Y1229619D01*
G01X-6545Y1229595D02*
X-6694Y1229619D01*
G01X-4259Y1229776D02*
X-3582Y1229595D01*
G01X-6694Y1229619D02*
X-9844D01*
G01X-4259Y1229776D02*
X-4725D01*
G01X-3151Y1229933D02*
X-2197D01*
G01X-4725Y1230209D02*
X-6694D01*
G01X9000Y1230327D02*
X-1D01*
G01D02*
X-985D01*
G01X-1Y1231666D02*
X9000D01*
G01X-985D02*
X-1D01*
G01X-4725Y1231784D02*
X-6694D01*
G01X-3151Y1232059D02*
X-2197D01*
G01X-4725Y1232217D02*
X-4259D01*
G01X-9844Y1232374D02*
X-6694D01*
G01X9842Y1246071D02*
X-9056Y1245284D01*
G01X24802Y1236622D02*
X-1D01*
G01X-3467Y1232430D02*
X-4259Y1232217D01*
G01X-6694Y1232374D02*
X-6351Y1232430D01*
G01X14369Y1250008D02*
G03I-4527J0D01*
G01X13779D02*
G03I-3937J0D01*
G01X-1Y1262213D02*
Y1325191D01*
G01X-9056Y1254733D02*
X9842Y1253945D01*
G01X24802Y1262213D02*
X-9056D01*
G01X-1Y1264181D02*
X26771D01*
G01X9000Y1227729D02*
Y1226390D01*
G01X12829D02*
X9000D01*
G01Y1227729D02*
X12829D01*
G01X9000Y1231666D02*
Y1230327D01*
G01X12829D02*
X9000D01*
G01Y1231666D02*
X12829D01*
G01X-17894Y1268118D02*
X-7875D01*
G01Y1278280D02*
Y1268118D01*
G01Y1280567D02*
Y1275992D01*
G01X-15749Y1268118D02*
X-63741D01*
G01X-7875Y1309889D02*
G03X-1I3937J0D01*
G01Y1280567D02*
G03X-7875I-3937J0D01*
G01Y1309889D02*
G03X-1I3937J0D01*
G01Y1280567D02*
G03X-7875I-3937J0D01*
G01X-39607Y1348853D02*
X-34603Y1352357D01*
G01X-39607Y1344522D02*
Y1694876D01*
G01X-33702Y1350388D02*
Y1346451D01*
G01X-24844Y1344483D02*
X-39607D01*
G01Y1344522D02*
X-24844D01*
G01X-33702Y1346451D02*
X-39607D01*
G01Y1347672D02*
X-27993D01*
G01X-38426Y1365250D02*
Y1362888D01*
G01Y1369187D02*
Y1366825D01*
G01Y1361313D02*
Y1358951D01*
G01Y1357376D02*
Y1355014D01*
G01X-38108Y1368489D02*
Y1367524D01*
G01Y1364552D02*
Y1363587D01*
G01Y1360615D02*
Y1359650D01*
G01Y1356678D02*
Y1355713D01*
G01X-37871Y1368511D02*
Y1367501D01*
G01Y1364574D02*
Y1363564D01*
G01Y1360637D02*
Y1359627D01*
G01Y1356700D02*
Y1355690D01*
G01X-36812Y1398880D02*
Y1350810D01*
G01X-35595Y1368731D02*
Y1367281D01*
G01Y1364794D02*
Y1363344D01*
G01Y1360857D02*
Y1359407D01*
G01Y1356920D02*
Y1355470D01*
G01X-35546Y1369187D02*
Y1366825D01*
G01Y1361313D02*
Y1358951D01*
G01Y1365250D02*
Y1362888D01*
G01Y1357376D02*
Y1355014D01*
G01X-35357Y1368754D02*
Y1367259D01*
G01Y1364817D02*
Y1363322D01*
G01Y1360880D02*
Y1359385D01*
G01Y1356943D02*
Y1355448D01*
G01X-34607Y1365172D02*
Y1362967D01*
G01Y1369109D02*
Y1366904D01*
G01Y1361235D02*
Y1359030D01*
G01Y1357298D02*
Y1355093D01*
G01X-34136Y1368768D02*
Y1367244D01*
G01Y1364831D02*
Y1363307D01*
G01Y1360894D02*
Y1359370D01*
G01Y1356957D02*
Y1355433D01*
G01X-33153Y1368779D02*
Y1367233D01*
G01Y1364842D02*
Y1363296D01*
G01Y1360905D02*
Y1359359D01*
G01Y1356968D02*
Y1355422D01*
G01X-32319Y1368788D02*
Y1367224D01*
G01Y1364851D02*
Y1363287D01*
G01Y1360914D02*
Y1359350D01*
G01Y1356977D02*
Y1355413D01*
G01X-31941Y1368792D02*
Y1367220D01*
G01Y1364855D02*
Y1363283D01*
G01Y1360918D02*
Y1359346D01*
G01Y1356981D02*
Y1355409D01*
G01X-38108Y1355713D02*
X-35351Y1355447D01*
G01X-38108Y1359650D02*
X-35351Y1359384D01*
G01X-38108Y1363587D02*
X-35351Y1363321D01*
G01Y1356943D02*
X-10631Y1357219D01*
G01X-35351Y1360880D02*
X-10631Y1361156D01*
G01X-35351Y1364817D02*
X-10631Y1365093D01*
G01X-35351Y1368754D02*
X-10631Y1369030D01*
G01X-39607Y1350388D02*
X-33702D01*
G01X-34603Y1352357D02*
X-8899D01*
G01X-39607Y1355014D02*
X-24509D01*
G01X-35546Y1355093D02*
X-1D01*
G01X-35546Y1357298D02*
X-1D01*
G01X-24509Y1357376D02*
X-39607D01*
G01Y1358951D02*
X-24509D01*
G01X-35546Y1359030D02*
X-1D01*
G01X-27993Y1361018D02*
X-39607D01*
G01X-35546Y1361235D02*
X-1D01*
G01X-24509Y1361313D02*
X-39607D01*
G01Y1362888D02*
X-24509D01*
G01X-35546Y1362967D02*
X-1D01*
G01X-39607Y1364168D02*
X-24844D01*
G01X-35546Y1365172D02*
X-1D01*
G01X-24509Y1365250D02*
X-39607D01*
G01Y1366825D02*
X-24509D01*
G01X-35546Y1366904D02*
X-1D01*
G01X-39607Y1368144D02*
X-24844D01*
G01X-35546Y1369109D02*
X-1D01*
G01X-24509Y1369187D02*
X-39607D01*
G01X-10631Y1355172D02*
X-35351Y1355447D01*
G01X-10631Y1359109D02*
X-35351Y1359384D01*
G01X-10631Y1363046D02*
X-35351Y1363321D01*
G01X-10631Y1366983D02*
X-35351Y1367258D01*
G01X-38108Y1367524D02*
X-35351Y1367258D01*
G01Y1356943D02*
X-38108Y1356678D01*
G01X-35351Y1360880D02*
X-38108Y1360615D01*
G01X-35351Y1364817D02*
X-38108Y1364552D01*
G01X-35351Y1368754D02*
X-38108Y1368489D01*
G01X-38426Y1388872D02*
Y1386510D01*
G01Y1384935D02*
Y1382573D01*
G01Y1380998D02*
Y1378636D01*
G01Y1377061D02*
Y1374699D01*
G01Y1373124D02*
Y1370762D01*
G01X-38108Y1388174D02*
Y1387209D01*
G01Y1384237D02*
Y1383272D01*
G01Y1380300D02*
Y1379335D01*
G01Y1376363D02*
Y1375398D01*
G01Y1372426D02*
Y1371461D01*
G01X-37871Y1388196D02*
Y1387186D01*
G01Y1384259D02*
Y1383249D01*
G01Y1380322D02*
Y1379312D01*
G01Y1376385D02*
Y1375375D01*
G01Y1372448D02*
Y1371438D01*
G01X-35595Y1388416D02*
Y1386967D01*
G01Y1384479D02*
Y1383030D01*
G01Y1380542D02*
Y1379093D01*
G01Y1376605D02*
Y1375156D01*
G01Y1372668D02*
Y1371219D01*
G01X-35546Y1384935D02*
Y1382573D01*
G01Y1388872D02*
Y1386510D01*
G01Y1380998D02*
Y1378636D01*
G01Y1377061D02*
Y1374699D01*
G01Y1373124D02*
Y1370762D01*
G01X-35357Y1388439D02*
Y1386944D01*
G01Y1384502D02*
Y1383007D01*
G01Y1380565D02*
Y1379070D01*
G01Y1376628D02*
Y1375133D01*
G01Y1372691D02*
Y1371196D01*
G01X-34607Y1388794D02*
Y1386589D01*
G01Y1384857D02*
Y1382652D01*
G01Y1380920D02*
Y1378715D01*
G01Y1376983D02*
Y1374778D01*
G01Y1373046D02*
Y1370841D01*
G01X-34136Y1388453D02*
Y1386930D01*
G01Y1384516D02*
Y1382993D01*
G01Y1380579D02*
Y1379056D01*
G01Y1376642D02*
Y1375119D01*
G01Y1372705D02*
Y1371181D01*
G01X-33153Y1388464D02*
Y1386919D01*
G01Y1384527D02*
Y1382981D01*
G01Y1380590D02*
Y1379044D01*
G01Y1376653D02*
Y1375107D01*
G01Y1372716D02*
Y1371170D01*
G01X-32319Y1388473D02*
Y1386909D01*
G01Y1384536D02*
Y1382972D01*
G01Y1380599D02*
Y1379035D01*
G01Y1376662D02*
Y1375098D01*
G01Y1372725D02*
Y1371161D01*
G01X-31941Y1388477D02*
Y1386905D01*
G01Y1384540D02*
Y1382968D01*
G01Y1380603D02*
Y1379031D01*
G01Y1376666D02*
Y1375094D01*
G01Y1372729D02*
Y1371157D01*
G01X-35351Y1372691D02*
X-10631Y1372967D01*
G01X-35351Y1376628D02*
X-10631Y1376904D01*
G01X-35351Y1380565D02*
X-10631Y1380841D01*
G01X-39607Y1370762D02*
X-24509D01*
G01X-35546Y1370841D02*
X-1D01*
G01X-39607Y1371294D02*
X-27993D01*
G01X-35546Y1373046D02*
X-1D01*
G01X-24509Y1373124D02*
X-39607D01*
G01Y1374699D02*
X-24509D01*
G01X-35546Y1374778D02*
X-1D01*
G01X-35546Y1376983D02*
X-1D01*
G01X-24509Y1377061D02*
X-39607D01*
G01Y1378636D02*
X-24509D01*
G01X-35546Y1378715D02*
X-1D01*
G01X-35546Y1380920D02*
X-1D01*
G01X-24509Y1380998D02*
X-39607D01*
G01Y1382573D02*
X-24509D01*
G01X-35546Y1382652D02*
X-1D01*
G01X-27993Y1384640D02*
X-39607D01*
G01X-35546Y1384857D02*
X-1D01*
G01X-24509Y1384935D02*
X-39607D01*
G01Y1386510D02*
X-24509D01*
G01X-35546Y1386589D02*
X-1D01*
G01X-10631Y1370920D02*
X-35351Y1371195D01*
G01X-10631Y1374857D02*
X-35351Y1375132D01*
G01X-10631Y1378794D02*
X-35351Y1379069D01*
G01X-10631Y1382731D02*
X-35351Y1383006D01*
G01X-10631Y1386668D02*
X-35351Y1386943D01*
G01X-38108Y1371461D02*
X-35351Y1371195D01*
G01X-38108Y1375398D02*
X-35351Y1375132D01*
G01X-38108Y1379335D02*
X-35351Y1379069D01*
G01X-38108Y1383272D02*
X-35351Y1383006D01*
G01X-38108Y1387209D02*
X-35351Y1386943D01*
G01Y1372691D02*
X-38108Y1372426D01*
G01X-35351Y1376628D02*
X-38108Y1376363D01*
G01X-35351Y1380565D02*
X-38108Y1380300D01*
G01X-35351Y1384502D02*
X-38108Y1384237D01*
G01X-35351Y1388439D02*
X-38108Y1388174D01*
G01X-35351Y1384502D02*
X-10631Y1384778D01*
G01X-35351Y1388439D02*
X-10631Y1388715D01*
G01X-39607Y1387790D02*
X-24844D01*
G01X-35546Y1388794D02*
X-1D01*
G01X-24509Y1388872D02*
X-39607D01*
G01X-38426Y1392809D02*
Y1390447D01*
G01X-38108Y1392111D02*
Y1391146D01*
G01X-37871Y1392133D02*
Y1391123D01*
G01X-35595Y1392353D02*
Y1390904D01*
G01X-35546Y1392809D02*
Y1390447D01*
G01X-35357Y1392376D02*
Y1390881D01*
G01X-34607Y1392731D02*
Y1390526D01*
G01X-34136Y1392390D02*
Y1390867D01*
G01X-33153Y1392401D02*
Y1390856D01*
G01X-32319Y1392410D02*
Y1390846D01*
G01X-31941Y1392414D02*
Y1390842D01*
G01X-10631Y1390605D02*
X-35351Y1390880D01*
G01X-38108Y1391146D02*
X-35351Y1390880D01*
G01X-39607Y1390447D02*
X-24509D01*
G01X-35546Y1390526D02*
X-1D01*
G01X-27993Y1344522D02*
Y1364168D01*
G01X-24844Y1344522D02*
Y1364168D01*
G01X-1Y1344483D02*
X-24844D01*
G01X-27993Y1368144D02*
Y1387790D01*
G01X-27265Y1369187D02*
Y1366825D01*
G01Y1365250D02*
Y1362888D01*
G01Y1361313D02*
Y1358951D01*
G01Y1357376D02*
Y1355014D01*
G01X-26943Y1368848D02*
Y1367164D01*
G01Y1364911D02*
Y1363227D01*
G01Y1360974D02*
Y1359290D01*
G01Y1357037D02*
Y1355353D01*
G01X-26566Y1368852D02*
Y1367160D01*
G01Y1364915D02*
Y1363223D01*
G01Y1360978D02*
Y1359286D01*
G01Y1357041D02*
Y1355349D01*
G01X-24844Y1368144D02*
Y1387790D01*
G01X-24509Y1369187D02*
Y1366825D01*
G01Y1361313D02*
Y1358951D01*
G01Y1365250D02*
Y1362888D01*
G01Y1357376D02*
Y1355014D01*
G01X-24122Y1368879D02*
Y1367133D01*
G01Y1364942D02*
Y1363196D01*
G01Y1361005D02*
Y1359259D01*
G01Y1357068D02*
Y1355322D01*
G01X-23684Y1368884D02*
Y1367128D01*
G01Y1364947D02*
Y1363191D01*
G01Y1361010D02*
Y1359254D01*
G01Y1357073D02*
Y1355317D01*
G01X-12993Y1369424D02*
Y1369109D01*
G01Y1365487D02*
Y1365172D01*
G01Y1366904D02*
Y1366589D01*
G01Y1359030D02*
Y1358715D01*
G01Y1361550D02*
Y1361235D01*
G01Y1362967D02*
Y1362652D01*
G01Y1355093D02*
Y1354778D01*
G01Y1357613D02*
Y1357298D01*
G01X-12280Y1369011D02*
Y1367001D01*
G01Y1365074D02*
Y1363064D01*
G01Y1361137D02*
Y1359127D01*
G01Y1357200D02*
Y1355190D01*
G01X-11843Y1369016D02*
Y1366996D01*
G01Y1365079D02*
Y1363059D01*
G01Y1361142D02*
Y1359122D01*
G01Y1357205D02*
Y1355185D01*
G01X-12993Y1354778D02*
X-1D01*
G01Y1357613D02*
X-12993D01*
G01Y1358715D02*
X-1D01*
G01Y1361550D02*
X-12993D01*
G01Y1362652D02*
X-1D01*
G01Y1365487D02*
X-12993D01*
G01Y1366589D02*
X-1D01*
G01Y1369424D02*
X-12993D01*
G01X-27265Y1388872D02*
Y1386510D01*
G01Y1384935D02*
Y1382573D01*
G01Y1380998D02*
Y1378636D01*
G01Y1373124D02*
Y1370762D01*
G01Y1377061D02*
Y1374699D01*
G01X-26943Y1388533D02*
Y1386849D01*
G01Y1384596D02*
Y1382912D01*
G01Y1380659D02*
Y1378975D01*
G01Y1376722D02*
Y1375038D01*
G01Y1372785D02*
Y1371101D01*
G01X-26566Y1388537D02*
Y1386845D01*
G01Y1384600D02*
Y1382908D01*
G01Y1380663D02*
Y1378971D01*
G01Y1376726D02*
Y1375034D01*
G01Y1372789D02*
Y1371097D01*
G01X-24509Y1384935D02*
Y1382573D01*
G01Y1388872D02*
Y1386510D01*
G01Y1380998D02*
Y1378636D01*
G01Y1377061D02*
Y1374699D01*
G01Y1373124D02*
Y1370762D01*
G01X-24122Y1388564D02*
Y1386818D01*
G01Y1384627D02*
Y1382881D01*
G01Y1380690D02*
Y1378944D01*
G01Y1376753D02*
Y1375007D01*
G01Y1372816D02*
Y1371070D01*
G01X-23684Y1388569D02*
Y1386813D01*
G01Y1384632D02*
Y1382876D01*
G01Y1380695D02*
Y1378939D01*
G01Y1376758D02*
Y1375002D01*
G01Y1372821D02*
Y1371065D01*
G01X-12993Y1389109D02*
Y1388794D01*
G01Y1382652D02*
Y1382337D01*
G01Y1385172D02*
Y1384857D01*
G01Y1386589D02*
Y1386274D01*
G01Y1378715D02*
Y1378400D01*
G01Y1381235D02*
Y1380920D01*
G01Y1373361D02*
Y1373046D01*
G01Y1374778D02*
Y1374463D01*
G01Y1377298D02*
Y1376983D01*
G01Y1370841D02*
Y1370526D01*
G01X-12280Y1388696D02*
Y1386686D01*
G01Y1384759D02*
Y1382749D01*
G01Y1380822D02*
Y1378812D01*
G01Y1376885D02*
Y1374875D01*
G01Y1372948D02*
Y1370938D01*
G01X-11843Y1388701D02*
Y1386681D01*
G01Y1384764D02*
Y1382744D01*
G01Y1380827D02*
Y1378807D01*
G01Y1376890D02*
Y1374870D01*
G01Y1372953D02*
Y1370933D01*
G01X-12993Y1370526D02*
X-1D01*
G01Y1373361D02*
X-12993D01*
G01Y1374463D02*
X-1D01*
G01Y1377298D02*
X-12993D01*
G01Y1378400D02*
X-1D01*
G01Y1381235D02*
X-12993D01*
G01Y1382337D02*
X-1D01*
G01Y1385172D02*
X-12993D01*
G01Y1386274D02*
X-1D01*
G01Y1389109D02*
X-12993D01*
G01X-27265Y1392809D02*
Y1390447D01*
G01X-26943Y1392470D02*
Y1390786D01*
G01X-26566Y1392474D02*
Y1390782D01*
G01X-24509Y1392809D02*
Y1390447D01*
G01X-24122Y1392501D02*
Y1390755D01*
G01X-23684Y1392506D02*
Y1390750D01*
G01X-12993Y1390526D02*
Y1390211D01*
G01X-12280Y1392633D02*
Y1390623D01*
G01X-11843Y1392638D02*
Y1390618D01*
G01X-12993Y1390211D02*
X-1D01*
G01X-9056Y1344483D02*
Y1325191D01*
G01X-1D02*
Y1344483D01*
G01Y1323223D02*
X26771D01*
G01X-9056Y1325191D02*
X24802D01*
G01X-1Y1344483D02*
Y1694876D01*
G01X-9056Y1342504D02*
X9842Y1341333D01*
G01Y1333459D02*
X-9056Y1333055D01*
G01X14369Y1337396D02*
G03I-4527J0D01*
G01X13779D02*
G03I-3937J0D01*
G01X-1970Y1369463D02*
X-2197Y1369069D01*
G01X-3378Y1366550D02*
X-3151Y1366943D01*
G01X-1970Y1365526D02*
X-2197Y1365132D01*
G01X-3378Y1362613D02*
X-3151Y1363006D01*
G01X-1970Y1361589D02*
X-2197Y1361195D01*
G01X-3378Y1358676D02*
X-3151Y1359069D01*
G01X-1970Y1357652D02*
X-2197Y1357258D01*
G01X-3378Y1354739D02*
X-3151Y1355132D01*
G01X-10531Y1369075D02*
Y1366937D01*
G01Y1365138D02*
Y1363000D01*
G01Y1361201D02*
Y1359063D01*
G01Y1357264D02*
Y1355126D01*
G01X-8899Y1352357D02*
Y1398164D01*
G01X-6694Y1369384D02*
Y1368794D01*
G01Y1367219D02*
Y1366628D01*
G01Y1365447D02*
Y1364857D01*
G01Y1363282D02*
Y1362691D01*
G01Y1361510D02*
Y1360920D01*
G01Y1359345D02*
Y1358754D01*
G01Y1357573D02*
Y1356983D01*
G01Y1355408D02*
Y1354817D01*
G01X-4725Y1369699D02*
Y1368794D01*
G01Y1367219D02*
Y1366313D01*
G01Y1365762D02*
Y1364857D01*
G01Y1363282D02*
Y1362376D01*
G01Y1361825D02*
Y1360920D01*
G01Y1359345D02*
Y1358439D01*
G01Y1357888D02*
Y1356983D01*
G01Y1355408D02*
Y1354502D01*
G01X-3757Y1369109D02*
Y1366904D01*
G01Y1365172D02*
Y1362967D01*
G01Y1361235D02*
Y1359030D01*
G01Y1357298D02*
Y1355093D01*
G01X-9844Y1369384D02*
X-10631Y1369030D01*
G01X-9844Y1365447D02*
X-10631Y1365093D01*
G01X-9844Y1361510D02*
X-10631Y1361156D01*
G01X-9844Y1357573D02*
X-10631Y1357219D01*
G01X-2521Y1369109D02*
Y1366904D01*
G01Y1365172D02*
Y1362967D01*
G01Y1361235D02*
Y1359030D01*
G01Y1357298D02*
Y1355093D01*
G01X-2251Y1369424D02*
Y1366589D01*
G01Y1365487D02*
Y1362652D01*
G01Y1361550D02*
Y1358715D01*
G01Y1357613D02*
Y1354778D01*
G01X-985Y1368676D02*
Y1367337D01*
G01Y1364739D02*
Y1363400D01*
G01Y1360802D02*
Y1359463D01*
G01Y1356865D02*
Y1355526D01*
G01X8523Y1368676D02*
Y1367337D01*
G01Y1364739D02*
Y1363400D01*
G01Y1360802D02*
Y1359463D01*
G01Y1356865D02*
Y1355526D01*
G01X-2197Y1355132D02*
X-1970Y1354739D01*
G01X-3151Y1357258D02*
X-3378Y1357652D01*
G01X-2197Y1359069D02*
X-1970Y1358676D01*
G01X-3151Y1361195D02*
X-3378Y1361589D01*
G01X-2197Y1363006D02*
X-1970Y1362613D01*
G01X-3151Y1365132D02*
X-3378Y1365526D01*
G01X-2197Y1366943D02*
X-1970Y1366550D01*
G01X-3151Y1369069D02*
X-3378Y1369463D01*
G01X-10631Y1355172D02*
X-9844Y1354817D01*
G01X-10631Y1359109D02*
X-9844Y1358754D01*
G01X-10631Y1363046D02*
X-9844Y1362691D01*
G01X-10631Y1366983D02*
X-9844Y1366628D01*
G01X-4259Y1354975D02*
X-3378Y1354739D01*
G01X-4259Y1358912D02*
X-3378Y1358676D01*
G01X-4259Y1362849D02*
X-3378Y1362613D01*
G01X-4259Y1366786D02*
X-3378Y1366550D01*
G01X-4725Y1354502D02*
X-6694Y1354817D01*
G01X-4725Y1358439D02*
X-6694Y1358754D01*
G01X-4725Y1362376D02*
X-6694Y1362691D01*
G01X-4725Y1366313D02*
X-6694Y1366628D01*
G01X24802Y1350782D02*
X-1D01*
G01Y1354739D02*
X-1970D01*
G01X-6694Y1354817D02*
X-9844D01*
G01X-4259Y1354975D02*
X-4725D01*
G01X-2197Y1355132D02*
X-3151D01*
G01X-4725Y1355408D02*
X-6694D01*
G01X15077Y1355526D02*
X8523D01*
G01D02*
X-1D01*
G01D02*
X-985D01*
G01Y1356865D02*
X-1D01*
G01D02*
X8523D01*
G01D02*
X12600D01*
G01X-4725Y1356983D02*
X-6694D01*
G01X-3151Y1357258D02*
X-2197D01*
G01X-4725Y1357416D02*
X-4259D01*
G01X-9844Y1357573D02*
X-6694D01*
G01X-1970Y1357652D02*
X-1D01*
G01Y1358676D02*
X-1970D01*
G01X-6694Y1358754D02*
X-9844D01*
G01X-4259Y1358912D02*
X-4725D01*
G01X-2197Y1359069D02*
X-3151D01*
G01X-4725Y1359345D02*
X-6694D01*
G01X15077Y1359463D02*
X8523D01*
G01D02*
X-1D01*
G01D02*
X-985D01*
G01Y1360802D02*
X-1D01*
G01D02*
X8523D01*
G01D02*
X12600D01*
G01X-4725Y1360920D02*
X-6694D01*
G01X-3151Y1361195D02*
X-2197D01*
G01X-4725Y1361353D02*
X-4259D01*
G01X-9844Y1361510D02*
X-6694D01*
G01X-1970Y1361589D02*
X-1D01*
G01Y1362613D02*
X-1970D01*
G01X-6694Y1362691D02*
X-9844D01*
G01X-4259Y1362849D02*
X-4725D01*
G01X-2197Y1363006D02*
X-3151D01*
G01X-4725Y1363282D02*
X-6694D01*
G01X15077Y1363400D02*
X8523D01*
G01D02*
X-1D01*
G01D02*
X-985D01*
G01Y1364739D02*
X-1D01*
G01D02*
X8523D01*
G01D02*
X12600D01*
G01X-4725Y1364857D02*
X-6694D01*
G01X-3151Y1365132D02*
X-2197D01*
G01X-4725Y1365290D02*
X-4259D01*
G01X-9844Y1365447D02*
X-6694D01*
G01X-1970Y1365526D02*
X-1D01*
G01Y1366550D02*
X-1970D01*
G01X-6694Y1366628D02*
X-9844D01*
G01X-4259Y1366786D02*
X-4725D01*
G01X-2197Y1366943D02*
X-3151D01*
G01X-4725Y1367219D02*
X-6694D01*
G01X15077Y1367337D02*
X8523D01*
G01D02*
X-1D01*
G01D02*
X-985D01*
G01Y1368676D02*
X-1D01*
G01D02*
X8523D01*
G01D02*
X12600D01*
G01X-4725Y1368794D02*
X-6694D01*
G01X-3151Y1369069D02*
X-2197D01*
G01X-4725Y1369227D02*
X-4259D01*
G01X-9844Y1369384D02*
X-6694D01*
G01Y1357573D02*
X-4725Y1357888D01*
G01X-6694Y1361510D02*
X-4725Y1361825D01*
G01X-6694Y1365447D02*
X-4725Y1365762D01*
G01X-6694Y1369384D02*
X-4725Y1369699D01*
G01X-3378Y1357652D02*
X-4259Y1357416D01*
G01X-3378Y1361589D02*
X-4259Y1361353D01*
G01X-3378Y1365526D02*
X-4259Y1365290D01*
G01X-3378Y1369463D02*
X-4259Y1369227D01*
G01X-1970Y1389148D02*
X-2197Y1388754D01*
G01X-3378Y1386235D02*
X-3151Y1386628D01*
G01X-1970Y1385211D02*
X-2197Y1384817D01*
G01X-3378Y1382298D02*
X-3151Y1382691D01*
G01X-1970Y1381274D02*
X-2197Y1380880D01*
G01X-3378Y1378361D02*
X-3151Y1378754D01*
G01X-1970Y1377337D02*
X-2197Y1376943D01*
G01X-3378Y1374424D02*
X-3151Y1374817D01*
G01X-1970Y1373400D02*
X-2197Y1373006D01*
G01X-3378Y1370487D02*
X-3151Y1370880D01*
G01X-10531Y1388760D02*
Y1386622D01*
G01Y1384823D02*
Y1382685D01*
G01Y1380886D02*
Y1378748D01*
G01Y1373012D02*
Y1370874D01*
G01Y1376949D02*
Y1374811D01*
G01X-6694Y1389069D02*
Y1388479D01*
G01Y1386904D02*
Y1386313D01*
G01Y1385132D02*
Y1384542D01*
G01Y1382967D02*
Y1382376D01*
G01Y1381195D02*
Y1380605D01*
G01Y1379030D02*
Y1378439D01*
G01Y1377258D02*
Y1376668D01*
G01Y1375093D02*
Y1374502D01*
G01Y1373321D02*
Y1372731D01*
G01Y1371156D02*
Y1370565D01*
G01X-4725Y1389384D02*
Y1388479D01*
G01Y1386904D02*
Y1385998D01*
G01Y1385447D02*
Y1384542D01*
G01Y1382967D02*
Y1382061D01*
G01Y1381510D02*
Y1380605D01*
G01Y1379030D02*
Y1378124D01*
G01Y1377573D02*
Y1376668D01*
G01Y1375093D02*
Y1374187D01*
G01Y1373636D02*
Y1372731D01*
G01Y1371156D02*
Y1370250D01*
G01X-3757Y1388794D02*
Y1386589D01*
G01Y1384857D02*
Y1382652D01*
G01Y1380920D02*
Y1378715D01*
G01Y1373046D02*
Y1370841D01*
G01Y1376983D02*
Y1374778D01*
G01X-9844Y1389069D02*
X-10631Y1388715D01*
G01X-9844Y1385132D02*
X-10631Y1384778D01*
G01X-9844Y1381195D02*
X-10631Y1380841D01*
G01X-9844Y1377258D02*
X-10631Y1376904D01*
G01X-9844Y1373321D02*
X-10631Y1372967D01*
G01X-2521Y1388794D02*
Y1386589D01*
G01Y1384857D02*
Y1382652D01*
G01Y1380920D02*
Y1378715D01*
G01Y1373046D02*
Y1370841D01*
G01Y1376983D02*
Y1374778D01*
G01X-2251Y1389109D02*
Y1386274D01*
G01Y1385172D02*
Y1382337D01*
G01Y1381235D02*
Y1378400D01*
G01Y1373361D02*
Y1370526D01*
G01Y1377298D02*
Y1374463D01*
G01X-985Y1388361D02*
Y1387022D01*
G01Y1384424D02*
Y1383085D01*
G01Y1380487D02*
Y1379148D01*
G01Y1376550D02*
Y1375211D01*
G01Y1372613D02*
Y1371274D01*
G01X8523Y1388361D02*
Y1387022D01*
G01Y1384424D02*
Y1383085D01*
G01Y1380487D02*
Y1379148D01*
G01Y1376550D02*
Y1375211D01*
G01Y1372613D02*
Y1371274D01*
G01X-2197Y1370880D02*
X-1970Y1370487D01*
G01X-3151Y1373006D02*
X-3378Y1373400D01*
G01X-2197Y1374817D02*
X-1970Y1374424D01*
G01X-3151Y1376943D02*
X-3378Y1377337D01*
G01X-2197Y1378754D02*
X-1970Y1378361D01*
G01X-3151Y1380880D02*
X-3378Y1381274D01*
G01X-2197Y1382691D02*
X-1970Y1382298D01*
G01X-3151Y1384817D02*
X-3378Y1385211D01*
G01X-2197Y1386628D02*
X-1970Y1386235D01*
G01X-3151Y1388754D02*
X-3378Y1389148D01*
G01X-10631Y1370920D02*
X-9844Y1370565D01*
G01X-10631Y1374857D02*
X-9844Y1374502D01*
G01X-10631Y1378794D02*
X-9844Y1378439D01*
G01X-10631Y1382731D02*
X-9844Y1382376D01*
G01X-10631Y1386668D02*
X-9844Y1386313D01*
G01X-4259Y1370723D02*
X-3378Y1370487D01*
G01X-4259Y1374660D02*
X-3378Y1374424D01*
G01X-4259Y1378597D02*
X-3378Y1378361D01*
G01X-4259Y1382534D02*
X-3378Y1382298D01*
G01X-4725Y1370250D02*
X-6694Y1370565D01*
G01X-4725Y1374187D02*
X-6694Y1374502D01*
G01X-4725Y1378124D02*
X-6694Y1378439D01*
G01X-4725Y1382061D02*
X-6694Y1382376D01*
G01X-4725Y1385998D02*
X-6694Y1386313D01*
G01X-4259Y1386471D02*
X-3378Y1386235D01*
G01X-1970Y1369463D02*
X-1D01*
G01Y1370487D02*
X-1970D01*
G01X-6694Y1370565D02*
X-9844D01*
G01X-4259Y1370723D02*
X-4725D01*
G01X-2197Y1370880D02*
X-3151D01*
G01X-4725Y1371156D02*
X-6694D01*
G01X15077Y1371274D02*
X8523D01*
G01D02*
X-1D01*
G01D02*
X-985D01*
G01Y1372613D02*
X-1D01*
G01D02*
X8523D01*
G01D02*
X12600D01*
G01X-4725Y1372731D02*
X-6694D01*
G01X-3151Y1373006D02*
X-2197D01*
G01X-4725Y1373164D02*
X-4259D01*
G01X-9844Y1373321D02*
X-6694D01*
G01X-1970Y1373400D02*
X-1D01*
G01Y1374424D02*
X-1970D01*
G01X-6694Y1374502D02*
X-9844D01*
G01X-4259Y1374660D02*
X-4725D01*
G01X-2197Y1374817D02*
X-3151D01*
G01X-4725Y1375093D02*
X-6694D01*
G01X15077Y1375211D02*
X8523D01*
G01D02*
X-1D01*
G01D02*
X-985D01*
G01Y1376550D02*
X-1D01*
G01D02*
X8523D01*
G01D02*
X12600D01*
G01X-4725Y1376668D02*
X-6694D01*
G01X-3151Y1376943D02*
X-2197D01*
G01X-4725Y1377101D02*
X-4259D01*
G01X-9844Y1377258D02*
X-6694D01*
G01X-1970Y1377337D02*
X-1D01*
G01Y1378361D02*
X-1970D01*
G01X-6694Y1378439D02*
X-9844D01*
G01X-4259Y1378597D02*
X-4725D01*
G01X-2197Y1378754D02*
X-3151D01*
G01X-4725Y1379030D02*
X-6694D01*
G01X15077Y1379148D02*
X8523D01*
G01D02*
X-1D01*
G01D02*
X-985D01*
G01Y1380487D02*
X-1D01*
G01D02*
X8523D01*
G01D02*
X12600D01*
G01X-4725Y1380605D02*
X-6694D01*
G01X-3151Y1380880D02*
X-2197D01*
G01X-4725Y1381038D02*
X-4259D01*
G01X-9844Y1381195D02*
X-6694D01*
G01X-1970Y1381274D02*
X-1D01*
G01Y1382298D02*
X-1970D01*
G01X-6694Y1382376D02*
X-9844D01*
G01X-4259Y1382534D02*
X-4725D01*
G01X-2197Y1382691D02*
X-3151D01*
G01X-4725Y1382967D02*
X-6694D01*
G01X15077Y1383085D02*
X8523D01*
G01D02*
X-1D01*
G01D02*
X-985D01*
G01Y1384424D02*
X-1D01*
G01D02*
X8523D01*
G01D02*
X12600D01*
G01X-4725Y1384542D02*
X-6694D01*
G01X-3151Y1384817D02*
X-2197D01*
G01X-4725Y1384975D02*
X-4259D01*
G01X-9844Y1385132D02*
X-6694D01*
G01X-1970Y1385211D02*
X-1D01*
G01Y1386235D02*
X-1970D01*
G01X-6694Y1386313D02*
X-9844D01*
G01X-4259Y1386471D02*
X-4725D01*
G01X-2197Y1386628D02*
X-3151D01*
G01X-4725Y1386904D02*
X-6694D01*
G01X15077Y1387022D02*
X8523D01*
G01D02*
X-1D01*
G01D02*
X-985D01*
G01X-6694Y1373321D02*
X-4725Y1373636D01*
G01X-6694Y1377258D02*
X-4725Y1377573D01*
G01X-6694Y1381195D02*
X-4725Y1381510D01*
G01X-985Y1388361D02*
X-1D01*
G01D02*
X8523D01*
G01D02*
X12600D01*
G01X-4725Y1388479D02*
X-6694D01*
G01X-3151Y1388754D02*
X-2197D01*
G01X-4725Y1388912D02*
X-4259D01*
G01X-9844Y1389069D02*
X-6694D01*
G01X-1970Y1389148D02*
X-1D01*
G01X-3378Y1373400D02*
X-4259Y1373164D01*
G01X-3378Y1377337D02*
X-4259Y1377101D01*
G01X-3378Y1381274D02*
X-4259Y1381038D01*
G01X-3378Y1385211D02*
X-4259Y1384975D01*
G01X-3378Y1389148D02*
X-4259Y1388912D01*
G01X-6694Y1385132D02*
X-4725Y1385447D01*
G01X-6694Y1389069D02*
X-4725Y1389384D01*
G01X-3378Y1390172D02*
X-3151Y1390565D01*
G01X-10531Y1392697D02*
Y1390559D01*
G01X-6694Y1390841D02*
Y1390250D01*
G01X-4725Y1390841D02*
Y1389935D01*
G01X-3757Y1392731D02*
Y1390526D01*
G01X-2521Y1392731D02*
Y1390526D01*
G01X-2251Y1393046D02*
Y1390211D01*
G01X-985Y1392298D02*
Y1390959D01*
G01X8523Y1392298D02*
Y1390959D01*
G01X-2197Y1390565D02*
X-1970Y1390172D01*
G01X-10631Y1390605D02*
X-9844Y1390250D01*
G01X-4725Y1389935D02*
X-6694Y1390250D01*
G01X-4259Y1390408D02*
X-3378Y1390172D01*
G01X-1D02*
X-1970D01*
G01X-6694Y1390250D02*
X-9844D01*
G01X-4259Y1390408D02*
X-4725D01*
G01X-2197Y1390565D02*
X-3151D01*
G01X-4725Y1390841D02*
X-6694D01*
G01X15077Y1390959D02*
X8523D01*
G01D02*
X-1D01*
G01D02*
X-985D01*
G01X10910Y1356202D02*
X10977Y1356333D01*
G01X9436Y1356070D02*
X9637Y1356333D01*
G01X9972Y1356136D02*
X9838Y1356005D01*
G01X11179D02*
X11313Y1356136D01*
G01X9369Y1355743D02*
X9436Y1356070D01*
G01X9838Y1356005D02*
X9771Y1355808D01*
G01X11112D02*
X11179Y1356005D01*
G01X9637Y1356333D02*
X9905Y1356530D01*
G01X10977Y1356333D02*
X11245Y1356530D01*
G01X9369Y1354168D02*
Y1355743D01*
G01Y1357514D02*
Y1357908D01*
G01X9771Y1355808D02*
Y1354561D01*
G01X10710D02*
Y1355808D01*
G01X11112Y1354561D02*
Y1355808D01*
G01X9905Y1356530D02*
X10106Y1356595D01*
G01X10173Y1356202D02*
X9972Y1356136D01*
G01X11245Y1356530D02*
X11447Y1356595D01*
G01X11313Y1356136D02*
X11514Y1356202D01*
G01X10710Y1355808D02*
X10642Y1356005D01*
G01X10843Y1356333D02*
X10910Y1356202D01*
G01X10642Y1356005D02*
X10508Y1356136D01*
G01X11916D02*
X12050Y1356005D01*
G01X10575Y1356530D02*
X10843Y1356333D01*
G01X11983Y1356530D02*
X12251Y1356333D01*
G01X9838Y1357120D02*
X9369Y1357514D01*
G01X9905D02*
X10375Y1357120D01*
G01X10508Y1356136D02*
X10307Y1356202D01*
G01X10375Y1356595D02*
X10575Y1356530D01*
G01X11715Y1356202D02*
X11916Y1356136D01*
G01X11782Y1356595D02*
X11983Y1356530D01*
G01X12519Y1354168D02*
X9369D01*
G01X12117Y1354561D02*
X11112D01*
G01X9771D02*
X10710D01*
G01X10307Y1356202D02*
X10173D01*
G01X11514D02*
X11715D01*
G01X10106Y1356595D02*
X10375D01*
G01X11447D02*
X11782D01*
G01X10375Y1357120D02*
X9838D01*
G01X12519Y1357514D02*
X9905D01*
G01X9369Y1357908D02*
X12519D01*
G01X-7875Y1309889D02*
Y1319285D01*
G01D02*
X-63741D01*
G01X-39020Y1402712D02*
X-36561Y1404433D01*
G01X-38426Y1408557D02*
Y1406195D01*
G01Y1396746D02*
Y1394384D01*
G01X-38108Y1407859D02*
Y1406894D01*
G01Y1396048D02*
Y1395083D01*
G01X-37871Y1407881D02*
Y1406871D01*
G01Y1396070D02*
Y1395060D01*
G01X-36812Y1687916D02*
Y1404258D01*
G01X-35595Y1408101D02*
Y1406652D01*
G01Y1396290D02*
Y1394841D01*
G01X-35546Y1408557D02*
Y1406195D01*
G01Y1396746D02*
Y1394384D01*
G01X-35434Y1403971D02*
Y1398971D01*
G01X-35357Y1408124D02*
Y1406629D01*
G01Y1396313D02*
Y1394818D01*
G01X-34607Y1394463D02*
Y1396668D01*
G01Y1406274D02*
Y1408479D01*
G01X-34136Y1408138D02*
Y1406615D01*
G01Y1396327D02*
Y1394804D01*
G01X-33153Y1408149D02*
Y1406604D01*
G01Y1396338D02*
Y1394793D01*
G01X-32319Y1408158D02*
Y1406594D01*
G01Y1396347D02*
Y1394783D01*
G01X-31941Y1408162D02*
Y1406590D01*
G01Y1396351D02*
Y1394779D01*
G01X-36561Y1398705D02*
X-39020Y1400426D01*
G01X-38108Y1395083D02*
X-35351Y1394817D01*
G01X-38108Y1406894D02*
X-35351Y1406628D01*
G01Y1392376D02*
X-38108Y1392111D01*
G01X-35351Y1396313D02*
X-38108Y1396048D01*
G01X-35351Y1408124D02*
X-38108Y1407859D01*
G01X-35351Y1392376D02*
X-10631Y1392652D01*
G01X-35351Y1396313D02*
X-10631Y1396589D01*
G01X-35351Y1408124D02*
X-10631Y1408400D01*
G01X-39607Y1391766D02*
X-24844D01*
G01X-35546Y1392731D02*
X-1D01*
G01X-24509Y1392809D02*
X-39607D01*
G01Y1394384D02*
X-24509D01*
G01X-35546Y1394463D02*
X-1D01*
G01X-39607Y1394916D02*
X-27993D01*
G01X-35546Y1396668D02*
X-1D01*
G01X-24509Y1396746D02*
X-39607D01*
G01X-8899Y1398164D02*
X-34845D01*
G01X-35434Y1398971D02*
X-1D01*
G01Y1403971D02*
X-35434D01*
G01X-34845Y1404975D02*
X-8899D01*
G01X-39607Y1406195D02*
X-24509D01*
G01X-35546Y1406274D02*
X-1D01*
G01X-27993Y1408262D02*
X-39607D01*
G01X-35546Y1408479D02*
X-1D01*
G01X-24509Y1408557D02*
X-39607D01*
G01X-10631Y1394542D02*
X-35351Y1394817D01*
G01X-10631Y1406353D02*
X-35351Y1406628D01*
G01X-36561Y1398705D02*
G03X-34845Y1398164I1716J2451D01*
G01Y1404975D02*
G03X-36561Y1404433I1J-2992D01*
G01X-39020Y1402684D02*
G03Y1400426I791J-1129D01*
G01X-38426Y1428243D02*
Y1425880D01*
G01Y1424306D02*
Y1421943D01*
G01Y1416431D02*
Y1414069D01*
G01Y1420369D02*
Y1418006D01*
G01Y1412494D02*
Y1410132D01*
G01X-38108Y1427544D02*
Y1426579D01*
G01Y1423607D02*
Y1422642D01*
G01Y1419670D02*
Y1418705D01*
G01Y1415733D02*
Y1414768D01*
G01Y1411796D02*
Y1410831D01*
G01X-37871Y1427567D02*
Y1426556D01*
G01Y1423630D02*
Y1422619D01*
G01Y1415756D02*
Y1414745D01*
G01Y1419693D02*
Y1418682D01*
G01Y1411819D02*
Y1410808D01*
G01X-35595Y1427786D02*
Y1426337D01*
G01Y1423849D02*
Y1422400D01*
G01Y1419912D02*
Y1418463D01*
G01Y1415975D02*
Y1414526D01*
G01Y1412038D02*
Y1410589D01*
G01X-35546Y1428243D02*
Y1425880D01*
G01Y1424306D02*
Y1421943D01*
G01Y1420369D02*
Y1418006D01*
G01Y1416431D02*
Y1414069D01*
G01Y1412494D02*
Y1410132D01*
G01X-35357Y1427809D02*
Y1426314D01*
G01Y1423872D02*
Y1422377D01*
G01Y1419935D02*
Y1418440D01*
G01Y1415998D02*
Y1414503D01*
G01Y1412061D02*
Y1410566D01*
G01X-34607Y1428164D02*
Y1425959D01*
G01Y1424227D02*
Y1422022D01*
G01Y1416353D02*
Y1414148D01*
G01Y1420290D02*
Y1418085D01*
G01Y1412416D02*
Y1410211D01*
G01X-34136Y1427823D02*
Y1426300D01*
G01Y1419949D02*
Y1418426D01*
G01Y1423886D02*
Y1422363D01*
G01Y1416012D02*
Y1414489D01*
G01Y1412075D02*
Y1410552D01*
G01X-33153Y1427834D02*
Y1426289D01*
G01Y1423897D02*
Y1422352D01*
G01Y1419960D02*
Y1418415D01*
G01Y1416023D02*
Y1414478D01*
G01Y1412086D02*
Y1410541D01*
G01X-32319Y1427843D02*
Y1426280D01*
G01Y1419969D02*
Y1418406D01*
G01Y1423906D02*
Y1422343D01*
G01Y1416032D02*
Y1414469D01*
G01Y1412095D02*
Y1410531D01*
G01X-31941Y1427847D02*
Y1426275D01*
G01Y1419973D02*
Y1418401D01*
G01Y1423910D02*
Y1422338D01*
G01Y1416036D02*
Y1414464D01*
G01Y1412099D02*
Y1410527D01*
G01X-38108Y1410831D02*
X-35351Y1410565D01*
G01X-38108Y1414768D02*
X-35351Y1414502D01*
G01X-38108Y1418705D02*
X-35351Y1418439D01*
G01X-38108Y1422642D02*
X-35351Y1422376D01*
G01X-38108Y1426579D02*
X-35351Y1426313D01*
G01Y1412061D02*
X-10631Y1412337D01*
G01X-35351Y1415998D02*
X-10631Y1416274D01*
G01X-35351Y1419935D02*
X-10631Y1420211D01*
G01X-35351Y1423872D02*
X-10631Y1424148D01*
G01X-35351Y1427809D02*
X-10631Y1428085D01*
G01X-39607Y1410132D02*
X-24509D01*
G01X-35546Y1410211D02*
X-1D01*
G01X-39607Y1411412D02*
X-24844D01*
G01X-35546Y1412416D02*
X-1D01*
G01X-24509Y1412494D02*
X-39607D01*
G01Y1414069D02*
X-24509D01*
G01X-35546Y1414148D02*
X-1D01*
G01X-39607Y1415388D02*
X-24844D01*
G01X-35546Y1416353D02*
X-1D01*
G01X-24509Y1416431D02*
X-39607D01*
G01Y1418006D02*
X-24509D01*
G01X-35546Y1418085D02*
X-1D01*
G01X-39607Y1418538D02*
X-27993D01*
G01X-35546Y1420290D02*
X-1D01*
G01X-24509Y1420369D02*
X-39607D01*
G01Y1421943D02*
X-24509D01*
G01X-35546Y1422022D02*
X-1D01*
G01X-35546Y1424227D02*
X-1D01*
G01X-24509Y1424306D02*
X-39607D01*
G01Y1425880D02*
X-24509D01*
G01X-35546Y1425959D02*
X-1D01*
G01X-35546Y1428164D02*
X-1D01*
G01X-24509Y1428243D02*
X-39607D01*
G01X-10631Y1410290D02*
X-35351Y1410565D01*
G01X-10631Y1414227D02*
X-35351Y1414502D01*
G01X-10631Y1418164D02*
X-35351Y1418439D01*
G01X-10631Y1422101D02*
X-35351Y1422376D01*
G01X-10631Y1426038D02*
X-35351Y1426313D01*
G01Y1412061D02*
X-38108Y1411796D01*
G01X-35351Y1415998D02*
X-38108Y1415733D01*
G01X-35351Y1419935D02*
X-38108Y1419670D01*
G01X-35351Y1423872D02*
X-38108Y1423607D01*
G01X-35351Y1427809D02*
X-38108Y1427544D01*
G01X-38426Y1447928D02*
Y1445565D01*
G01Y1451865D02*
Y1449502D01*
G01Y1440054D02*
Y1437691D01*
G01Y1443991D02*
Y1441628D01*
G01Y1436117D02*
Y1433754D01*
G01Y1432180D02*
Y1429817D01*
G01X-38108Y1443292D02*
Y1442327D01*
G01Y1447229D02*
Y1446264D01*
G01Y1439355D02*
Y1438390D01*
G01Y1435418D02*
Y1434453D01*
G01Y1431481D02*
Y1430516D01*
G01X-37871Y1443315D02*
Y1442304D01*
G01Y1447252D02*
Y1446241D01*
G01Y1439378D02*
Y1438367D01*
G01Y1435441D02*
Y1434430D01*
G01Y1431504D02*
Y1430493D01*
G01X-35595Y1447471D02*
Y1446022D01*
G01Y1439597D02*
Y1438148D01*
G01Y1443534D02*
Y1442085D01*
G01Y1435660D02*
Y1434211D01*
G01Y1431723D02*
Y1430274D01*
G01X-35546Y1451865D02*
Y1449502D01*
G01Y1447928D02*
Y1445565D01*
G01Y1443991D02*
Y1441628D01*
G01Y1440054D02*
Y1437691D01*
G01Y1436117D02*
Y1433754D01*
G01Y1432180D02*
Y1429817D01*
G01X-35357Y1447494D02*
Y1445999D01*
G01Y1443557D02*
Y1442062D01*
G01Y1439620D02*
Y1438125D01*
G01Y1435683D02*
Y1434188D01*
G01Y1431746D02*
Y1430251D01*
G01X-34607Y1447849D02*
Y1445644D01*
G01Y1451786D02*
Y1449581D01*
G01Y1439975D02*
Y1437770D01*
G01Y1443912D02*
Y1441707D01*
G01Y1436038D02*
Y1433833D01*
G01Y1432101D02*
Y1429896D01*
G01X-34136Y1443571D02*
Y1442048D01*
G01Y1447508D02*
Y1445985D01*
G01Y1439634D02*
Y1438111D01*
G01Y1435697D02*
Y1434174D01*
G01Y1431760D02*
Y1430237D01*
G01X-33153Y1447519D02*
Y1445974D01*
G01Y1439645D02*
Y1438100D01*
G01Y1443582D02*
Y1442037D01*
G01Y1435708D02*
Y1434163D01*
G01Y1431771D02*
Y1430226D01*
G01X-32319Y1443591D02*
Y1442028D01*
G01Y1447528D02*
Y1445965D01*
G01Y1439654D02*
Y1438091D01*
G01Y1435717D02*
Y1434154D01*
G01Y1431780D02*
Y1430217D01*
G01X-31941Y1443595D02*
Y1442023D01*
G01Y1447532D02*
Y1445960D01*
G01Y1439658D02*
Y1438086D01*
G01Y1435721D02*
Y1434149D01*
G01Y1431784D02*
Y1430212D01*
G01X-38108Y1430516D02*
X-35351Y1430250D01*
G01X-38108Y1434453D02*
X-35351Y1434187D01*
G01X-38108Y1438390D02*
X-35351Y1438124D01*
G01X-38108Y1442327D02*
X-35351Y1442061D01*
G01Y1431746D02*
X-10631Y1432022D01*
G01X-35351Y1435683D02*
X-10631Y1435959D01*
G01X-35351Y1439620D02*
X-10631Y1439896D01*
G01X-35351Y1443557D02*
X-10631Y1443833D01*
G01X-35351Y1447494D02*
X-10631Y1447770D01*
G01X-39607Y1429817D02*
X-24509D01*
G01X-35546Y1429896D02*
X-1D01*
G01X-27993Y1431884D02*
X-39607D01*
G01X-35546Y1432101D02*
X-1D01*
G01X-24509Y1432180D02*
X-39607D01*
G01Y1433754D02*
X-24509D01*
G01X-35546Y1433833D02*
X-1D01*
G01X-39607Y1435034D02*
X-24844D01*
G01X-35546Y1436038D02*
X-1D01*
G01X-24509Y1436117D02*
X-39607D01*
G01Y1437691D02*
X-24509D01*
G01X-35546Y1437770D02*
X-1D01*
G01X-39607Y1439010D02*
X-24844D01*
G01X-35546Y1439975D02*
X-1D01*
G01X-24509Y1440054D02*
X-39607D01*
G01Y1441628D02*
X-24509D01*
G01X-35546Y1441707D02*
X-1D01*
G01X-39607Y1442160D02*
X-27993D01*
G01X-35546Y1443912D02*
X-1D01*
G01X-24509Y1443991D02*
X-39607D01*
G01Y1445565D02*
X-24509D01*
G01X-35546Y1445644D02*
X-1D01*
G01X-35546Y1447849D02*
X-1D01*
G01X-24509Y1447928D02*
X-39607D01*
G01Y1449502D02*
X-24509D01*
G01X-35546Y1449581D02*
X-1D01*
G01X-10631Y1429975D02*
X-35351Y1430250D01*
G01X-10631Y1433912D02*
X-35351Y1434187D01*
G01X-10631Y1437849D02*
X-35351Y1438124D01*
G01X-10631Y1441786D02*
X-35351Y1442061D01*
G01X-10631Y1445723D02*
X-35351Y1445998D01*
G01X-38108Y1446264D02*
X-35351Y1445998D01*
G01Y1431746D02*
X-38108Y1431481D01*
G01X-35351Y1435683D02*
X-38108Y1435418D01*
G01X-35351Y1439620D02*
X-38108Y1439355D01*
G01X-35351Y1443557D02*
X-38108Y1443292D01*
G01X-35351Y1447494D02*
X-38108Y1447229D01*
G01X-38426Y1471550D02*
Y1469187D01*
G01Y1463676D02*
Y1461313D01*
G01Y1467613D02*
Y1465250D01*
G01Y1459739D02*
Y1457376D01*
G01Y1455802D02*
Y1453439D01*
G01X-38108Y1466914D02*
Y1465949D01*
G01Y1470851D02*
Y1469886D01*
G01Y1462977D02*
Y1462012D01*
G01Y1459040D02*
Y1458075D01*
G01Y1455103D02*
Y1454138D01*
G01Y1451166D02*
Y1450201D01*
G01X-37871Y1466937D02*
Y1465926D01*
G01Y1470874D02*
Y1469863D01*
G01Y1463000D02*
Y1461989D01*
G01Y1459063D02*
Y1458052D01*
G01Y1455126D02*
Y1454115D01*
G01Y1451189D02*
Y1450178D01*
G01X-35595Y1471093D02*
Y1469644D01*
G01Y1463219D02*
Y1461770D01*
G01Y1467156D02*
Y1465707D01*
G01Y1459282D02*
Y1457833D01*
G01Y1455345D02*
Y1453896D01*
G01Y1451408D02*
Y1449959D01*
G01X-35546Y1471550D02*
Y1469187D01*
G01Y1467613D02*
Y1465250D01*
G01Y1463676D02*
Y1461313D01*
G01Y1459739D02*
Y1457376D01*
G01Y1455802D02*
Y1453439D01*
G01X-35357Y1471116D02*
Y1469621D01*
G01Y1467179D02*
Y1465684D01*
G01Y1463242D02*
Y1461747D01*
G01Y1459305D02*
Y1457810D01*
G01Y1455368D02*
Y1453873D01*
G01Y1451431D02*
Y1449936D01*
G01X-34607Y1471471D02*
Y1469266D01*
G01Y1463597D02*
Y1461392D01*
G01Y1467534D02*
Y1465329D01*
G01Y1459660D02*
Y1457455D01*
G01Y1455723D02*
Y1453518D01*
G01X-34136Y1467193D02*
Y1465670D01*
G01Y1471130D02*
Y1469607D01*
G01Y1463256D02*
Y1461733D01*
G01Y1459319D02*
Y1457796D01*
G01Y1455382D02*
Y1453859D01*
G01Y1451445D02*
Y1449922D01*
G01X-33153Y1471141D02*
Y1469596D01*
G01Y1463267D02*
Y1461722D01*
G01Y1467204D02*
Y1465659D01*
G01Y1459330D02*
Y1457785D01*
G01Y1455393D02*
Y1453848D01*
G01Y1451456D02*
Y1449911D01*
G01X-32319Y1467213D02*
Y1465650D01*
G01Y1471150D02*
Y1469587D01*
G01Y1463276D02*
Y1461713D01*
G01Y1459339D02*
Y1457776D01*
G01Y1455402D02*
Y1453839D01*
G01Y1451465D02*
Y1449902D01*
G01X-31941Y1467217D02*
Y1465645D01*
G01Y1471154D02*
Y1469582D01*
G01Y1463280D02*
Y1461708D01*
G01Y1459343D02*
Y1457771D01*
G01Y1455406D02*
Y1453834D01*
G01Y1451469D02*
Y1449897D01*
G01X-35351Y1451431D02*
X-10631Y1451707D01*
G01X-35351Y1455369D02*
X-10631Y1455644D01*
G01X-35546Y1451786D02*
X-1D01*
G01X-24509Y1451865D02*
X-39607D01*
G01Y1453439D02*
X-24509D01*
G01X-35546Y1453518D02*
X-1D01*
G01X-27993Y1455506D02*
X-39607D01*
G01X-35546Y1455723D02*
X-1D01*
G01X-24509Y1455802D02*
X-39607D01*
G01Y1457376D02*
X-24509D01*
G01X-35546Y1457455D02*
X-1D01*
G01X-39607Y1458656D02*
X-24844D01*
G01X-35546Y1459660D02*
X-1D01*
G01X-24509Y1459739D02*
X-39607D01*
G01Y1461313D02*
X-24509D01*
G01X-35546Y1461392D02*
X-1D01*
G01X-39607Y1462632D02*
X-24844D01*
G01X-10631Y1449660D02*
X-35351Y1449935D01*
G01X-10631Y1453597D02*
X-35351Y1453872D01*
G01X-10631Y1457534D02*
X-35351Y1457809D01*
G01X-10631Y1461471D02*
X-35351Y1461746D01*
G01X-10631Y1465408D02*
X-35351Y1465683D01*
G01X-38108Y1450201D02*
X-35351Y1449935D01*
G01X-38108Y1454138D02*
X-35351Y1453872D01*
G01X-38108Y1458075D02*
X-35351Y1457809D01*
G01X-38108Y1462012D02*
X-35351Y1461746D01*
G01X-38108Y1465949D02*
X-35351Y1465683D01*
G01X-38108Y1469886D02*
X-35351Y1469620D01*
G01Y1451431D02*
X-38108Y1451166D01*
G01X-35351Y1455369D02*
X-38108Y1455103D01*
G01X-35351Y1459306D02*
X-38108Y1459040D01*
G01X-35351Y1463243D02*
X-38108Y1462977D01*
G01X-35351Y1467180D02*
X-38108Y1466914D01*
G01X-35351Y1459306D02*
X-10631Y1459581D01*
G01X-35351Y1463243D02*
X-10631Y1463518D01*
G01X-35351Y1467180D02*
X-10631Y1467455D01*
G01X-35546Y1463597D02*
X-1D01*
G01X-24509Y1463676D02*
X-39607D01*
G01Y1465250D02*
X-24509D01*
G01X-35546Y1465329D02*
X-1D01*
G01X-39607Y1465782D02*
X-27993D01*
G01X-35546Y1467534D02*
X-1D01*
G01X-24509Y1467613D02*
X-39607D01*
G01Y1469187D02*
X-24509D01*
G01X-35546Y1469266D02*
X-1D01*
G01X-10631Y1469345D02*
X-35351Y1469620D01*
G01X-38426Y1475487D02*
Y1473124D01*
G01X-38108Y1474788D02*
Y1473823D01*
G01X-37871Y1474811D02*
Y1473800D01*
G01X-35595Y1475030D02*
Y1473581D01*
G01X-35546Y1475487D02*
Y1473124D01*
G01X-35357Y1475053D02*
Y1473558D01*
G01X-34607Y1475408D02*
Y1473203D01*
G01X-34136Y1475067D02*
Y1473544D01*
G01X-33153Y1475078D02*
Y1473533D01*
G01X-32319Y1475087D02*
Y1473524D01*
G01X-31941Y1475091D02*
Y1473519D01*
G01X-38108Y1473823D02*
X-35351Y1473557D01*
G01Y1471117D02*
X-38108Y1470851D01*
G01X-35351Y1471117D02*
X-10631Y1471392D01*
G01X-35546Y1471471D02*
X-1D01*
G01X-24509Y1471550D02*
X-39607D01*
G01Y1473124D02*
X-24509D01*
G01X-35546Y1473203D02*
X-1D01*
G01X-10631Y1473282D02*
X-35351Y1473557D01*
G01X-27993Y1391766D02*
Y1411412D01*
G01X-27265Y1408557D02*
Y1406195D01*
G01Y1396746D02*
Y1394384D01*
G01X-26943Y1408218D02*
Y1406534D01*
G01Y1396407D02*
Y1394723D01*
G01X-26566Y1408222D02*
Y1406530D01*
G01Y1396411D02*
Y1394719D01*
G01X-24844Y1391766D02*
Y1411412D01*
G01X-24509Y1408557D02*
Y1406195D01*
G01Y1396746D02*
Y1394384D01*
G01X-24122Y1408249D02*
Y1406503D01*
G01Y1396438D02*
Y1394692D01*
G01X-23684Y1408254D02*
Y1406498D01*
G01Y1396443D02*
Y1394687D01*
G01X-12993Y1408794D02*
Y1408479D01*
G01Y1406274D02*
Y1405959D01*
G01Y1396983D02*
Y1396668D01*
G01Y1393046D02*
Y1392731D01*
G01Y1394463D02*
Y1394148D01*
G01X-12280Y1408381D02*
Y1406371D01*
G01Y1396570D02*
Y1394560D01*
G01X-11843Y1408386D02*
Y1406366D01*
G01Y1396575D02*
Y1394555D01*
G01X-1Y1393046D02*
X-12993D01*
G01Y1394148D02*
X-1D01*
G01Y1396983D02*
X-12993D01*
G01Y1405959D02*
X-1D01*
G01Y1408794D02*
X-12993D01*
G01X-27993Y1415388D02*
Y1435034D01*
G01X-27265Y1428243D02*
Y1425880D01*
G01Y1424306D02*
Y1421943D01*
G01Y1420369D02*
Y1418006D01*
G01Y1416431D02*
Y1414069D01*
G01Y1412494D02*
Y1410132D01*
G01X-26943Y1427903D02*
Y1426219D01*
G01Y1423966D02*
Y1422282D01*
G01Y1420029D02*
Y1418345D01*
G01Y1416092D02*
Y1414408D01*
G01Y1412155D02*
Y1410471D01*
G01X-26566Y1427907D02*
Y1426215D01*
G01Y1423970D02*
Y1422278D01*
G01Y1420033D02*
Y1418341D01*
G01Y1416096D02*
Y1414404D01*
G01Y1412159D02*
Y1410467D01*
G01X-24844Y1415388D02*
Y1435034D01*
G01X-24509Y1428243D02*
Y1425880D01*
G01Y1424306D02*
Y1421943D01*
G01Y1420369D02*
Y1418006D01*
G01Y1416431D02*
Y1414069D01*
G01Y1412494D02*
Y1410132D01*
G01X-24122Y1427934D02*
Y1426188D01*
G01Y1420060D02*
Y1418314D01*
G01Y1423997D02*
Y1422251D01*
G01Y1416123D02*
Y1414377D01*
G01Y1412186D02*
Y1410440D01*
G01X-23684Y1427939D02*
Y1426183D01*
G01Y1420065D02*
Y1418309D01*
G01Y1424002D02*
Y1422246D01*
G01Y1416128D02*
Y1414372D01*
G01Y1412191D02*
Y1410435D01*
G01X-12993Y1429896D02*
Y1429581D01*
G01Y1425959D02*
Y1425644D01*
G01Y1428479D02*
Y1428164D01*
G01Y1424542D02*
Y1424227D01*
G01Y1422022D02*
Y1421707D01*
G01Y1420605D02*
Y1420290D01*
G01Y1418085D02*
Y1417770D01*
G01Y1416668D02*
Y1416353D01*
G01Y1414148D02*
Y1413833D01*
G01Y1412731D02*
Y1412416D01*
G01Y1410211D02*
Y1409896D01*
G01X-12280Y1428067D02*
Y1426056D01*
G01Y1424130D02*
Y1422119D01*
G01Y1420193D02*
Y1418182D01*
G01Y1416256D02*
Y1414245D01*
G01Y1412319D02*
Y1410308D01*
G01X-11843Y1428071D02*
Y1426051D01*
G01Y1424134D02*
Y1422114D01*
G01Y1420197D02*
Y1418177D01*
G01Y1416260D02*
Y1414240D01*
G01Y1412323D02*
Y1410303D01*
G01X-12993Y1409896D02*
X-1D01*
G01Y1412731D02*
X-12993D01*
G01Y1413833D02*
X-1D01*
G01Y1416668D02*
X-12993D01*
G01Y1417770D02*
X-1D01*
G01Y1420605D02*
X-12993D01*
G01Y1421707D02*
X-1D01*
G01Y1424542D02*
X-12993D01*
G01Y1425644D02*
X-1D01*
G01Y1428479D02*
X-12993D01*
G01Y1429581D02*
X-1D01*
G01X-27993Y1439010D02*
Y1458656D01*
G01X-27265Y1451865D02*
Y1449502D01*
G01Y1447928D02*
Y1445565D01*
G01Y1443991D02*
Y1441628D01*
G01Y1440054D02*
Y1437691D01*
G01Y1436117D02*
Y1433754D01*
G01Y1432180D02*
Y1429817D01*
G01X-26943Y1447588D02*
Y1445904D01*
G01Y1443651D02*
Y1441967D01*
G01Y1439714D02*
Y1438030D01*
G01Y1435777D02*
Y1434093D01*
G01Y1431840D02*
Y1430156D01*
G01X-26566Y1443655D02*
Y1441963D01*
G01Y1447592D02*
Y1445900D01*
G01Y1439718D02*
Y1438026D01*
G01Y1435781D02*
Y1434089D01*
G01Y1431844D02*
Y1430152D01*
G01X-24844Y1439010D02*
Y1458656D01*
G01X-24509Y1451865D02*
Y1449502D01*
G01Y1447928D02*
Y1445565D01*
G01Y1443991D02*
Y1441628D01*
G01Y1440054D02*
Y1437691D01*
G01Y1436117D02*
Y1433754D01*
G01Y1432180D02*
Y1429817D01*
G01X-24122Y1451556D02*
Y1449810D01*
G01Y1443682D02*
Y1441936D01*
G01Y1447619D02*
Y1445873D01*
G01Y1439745D02*
Y1437999D01*
G01Y1435808D02*
Y1434062D01*
G01Y1431871D02*
Y1430125D01*
G01X-23684Y1451561D02*
Y1449805D01*
G01Y1443687D02*
Y1441931D01*
G01Y1447624D02*
Y1445868D01*
G01Y1439750D02*
Y1437994D01*
G01Y1435813D02*
Y1434057D01*
G01Y1431876D02*
Y1430120D01*
G01X-12993Y1449581D02*
Y1449266D01*
G01Y1448164D02*
Y1447849D01*
G01Y1445644D02*
Y1445329D01*
G01Y1444227D02*
Y1443912D01*
G01Y1441707D02*
Y1441392D01*
G01Y1440290D02*
Y1439975D01*
G01Y1437770D02*
Y1437455D01*
G01Y1433833D02*
Y1433518D01*
G01Y1436353D02*
Y1436038D01*
G01Y1432416D02*
Y1432101D01*
G01X-12280Y1451689D02*
Y1449678D01*
G01Y1443815D02*
Y1441804D01*
G01Y1447752D02*
Y1445741D01*
G01Y1439878D02*
Y1437867D01*
G01Y1435941D02*
Y1433930D01*
G01Y1432004D02*
Y1429993D01*
G01X-11843Y1451693D02*
Y1449673D01*
G01Y1447756D02*
Y1445736D01*
G01Y1443819D02*
Y1441799D01*
G01Y1439882D02*
Y1437862D01*
G01Y1435945D02*
Y1433925D01*
G01Y1432008D02*
Y1429988D01*
G01X-1Y1432416D02*
X-12993D01*
G01Y1433518D02*
X-1D01*
G01Y1436353D02*
X-12993D01*
G01Y1437455D02*
X-1D01*
G01Y1440290D02*
X-12993D01*
G01Y1441392D02*
X-1D01*
G01Y1444227D02*
X-12993D01*
G01Y1445329D02*
X-1D01*
G01Y1448164D02*
X-12993D01*
G01Y1449266D02*
X-1D01*
G01X-27993Y1462632D02*
Y1482278D01*
G01X-27265Y1471550D02*
Y1469187D01*
G01Y1467613D02*
Y1465250D01*
G01Y1463676D02*
Y1461313D01*
G01Y1459739D02*
Y1457376D01*
G01Y1455802D02*
Y1453439D01*
G01X-26943Y1471210D02*
Y1469526D01*
G01Y1467273D02*
Y1465589D01*
G01Y1463336D02*
Y1461652D01*
G01Y1459399D02*
Y1457715D01*
G01Y1455462D02*
Y1453778D01*
G01Y1451525D02*
Y1449841D01*
G01X-26566Y1467277D02*
Y1465585D01*
G01Y1471214D02*
Y1469522D01*
G01Y1463340D02*
Y1461648D01*
G01Y1459403D02*
Y1457711D01*
G01Y1455466D02*
Y1453774D01*
G01Y1451529D02*
Y1449837D01*
G01X-24844Y1462632D02*
Y1482278D01*
G01X-24509Y1471550D02*
Y1469187D01*
G01Y1467613D02*
Y1465250D01*
G01Y1463676D02*
Y1461313D01*
G01Y1459739D02*
Y1457376D01*
G01Y1455802D02*
Y1453439D01*
G01X-24122Y1471241D02*
Y1469495D01*
G01Y1467304D02*
Y1465558D01*
G01Y1463367D02*
Y1461621D01*
G01Y1459430D02*
Y1457684D01*
G01Y1455493D02*
Y1453747D01*
G01X-23684Y1471246D02*
Y1469490D01*
G01Y1467309D02*
Y1465553D01*
G01Y1463372D02*
Y1461616D01*
G01Y1459435D02*
Y1457679D01*
G01Y1455498D02*
Y1453742D01*
G01X-12993Y1469266D02*
Y1468951D01*
G01Y1467849D02*
Y1467534D01*
G01Y1465329D02*
Y1465014D01*
G01Y1463912D02*
Y1463597D01*
G01Y1461392D02*
Y1461077D01*
G01Y1457455D02*
Y1457140D01*
G01Y1459975D02*
Y1459660D01*
G01Y1453518D02*
Y1453203D01*
G01Y1456038D02*
Y1455723D01*
G01Y1452101D02*
Y1451786D01*
G01X-12280Y1471374D02*
Y1469363D01*
G01Y1467437D02*
Y1465426D01*
G01Y1463500D02*
Y1461489D01*
G01Y1459563D02*
Y1457552D01*
G01Y1455626D02*
Y1453615D01*
G01X-11843Y1471378D02*
Y1469358D01*
G01Y1467441D02*
Y1465421D01*
G01Y1463504D02*
Y1461484D01*
G01Y1459567D02*
Y1457547D01*
G01Y1455630D02*
Y1453610D01*
G01X-1Y1452101D02*
X-12993D01*
G01Y1453203D02*
X-1D01*
G01Y1456038D02*
X-12993D01*
G01Y1457140D02*
X-1D01*
G01Y1459975D02*
X-12993D01*
G01Y1461077D02*
X-1D01*
G01Y1463912D02*
X-12993D01*
G01Y1465014D02*
X-1D01*
G01Y1467849D02*
X-12993D01*
G01Y1468951D02*
X-1D01*
G01X-27265Y1475487D02*
Y1473124D01*
G01X-26943Y1475147D02*
Y1473463D01*
G01X-26566Y1475151D02*
Y1473459D01*
G01X-24509Y1475487D02*
Y1473124D01*
G01X-24122Y1475178D02*
Y1473432D01*
G01X-23684Y1475183D02*
Y1473427D01*
G01X-12993Y1473203D02*
Y1472888D01*
G01Y1471786D02*
Y1471471D01*
G01X-12280Y1475311D02*
Y1473300D01*
G01X-11843Y1475315D02*
Y1473295D01*
G01X-1Y1471786D02*
X-12993D01*
G01Y1472888D02*
X-1D01*
G01X-1970Y1408833D02*
X-2197Y1408439D01*
G01X-3378Y1405920D02*
X-3151Y1406313D01*
G01X-1970Y1397022D02*
X-2197Y1396628D01*
G01X-3378Y1394109D02*
X-3151Y1394502D01*
G01X-1970Y1393085D02*
X-2197Y1392691D01*
G01X1968Y1397835D02*
X368Y1396235D01*
G01X-1Y1395866D02*
X368Y1396235D01*
G01X-10531Y1408445D02*
Y1406307D01*
G01Y1396634D02*
Y1394496D01*
G01X-8899Y1404975D02*
Y1687199D01*
G01X-6694Y1408754D02*
Y1408164D01*
G01Y1406589D02*
Y1405998D01*
G01Y1396943D02*
Y1396353D01*
G01Y1394778D02*
Y1394187D01*
G01Y1393006D02*
Y1392416D01*
G01X-4725Y1410526D02*
Y1409620D01*
G01Y1409069D02*
Y1408164D01*
G01Y1406589D02*
Y1405683D01*
G01Y1397258D02*
Y1396353D01*
G01Y1394778D02*
Y1393872D01*
G01Y1393321D02*
Y1392416D01*
G01X-3757Y1408479D02*
Y1406274D01*
G01Y1396668D02*
Y1394463D01*
G01X-9844Y1408754D02*
X-10631Y1408400D01*
G01X-9844Y1396943D02*
X-10631Y1396589D01*
G01X-9844Y1393006D02*
X-10631Y1392652D01*
G01X-2521Y1408479D02*
Y1406274D01*
G01Y1396668D02*
Y1394463D01*
G01X-2251Y1408794D02*
Y1405959D01*
G01Y1396983D02*
Y1394148D01*
G01X-985Y1408046D02*
Y1406707D01*
G01Y1396235D02*
Y1394896D01*
G01X8523Y1408046D02*
Y1406707D01*
G01Y1396235D02*
Y1394896D01*
G01X-3151Y1392691D02*
X-3378Y1393085D01*
G01X-2197Y1394502D02*
X-1970Y1394109D01*
G01X-3151Y1396628D02*
X-3378Y1397022D01*
G01X-2197Y1406313D02*
X-1970Y1405920D01*
G01X-3151Y1408439D02*
X-3378Y1408833D01*
G01X576Y1406707D02*
X1968Y1405315D01*
G01X576Y1406707D02*
X-1Y1407283D01*
G01X-10631Y1394542D02*
X-9844Y1394187D01*
G01X-10631Y1406353D02*
X-9844Y1405998D01*
G01X-4725Y1393872D02*
X-6694Y1394187D01*
G01X-4259Y1394345D02*
X-3378Y1394109D01*
G01X-4259Y1406156D02*
X-3378Y1405920D01*
G01X-4725Y1405683D02*
X-6694Y1405998D01*
G01X-4725Y1409620D02*
X-6694Y1409935D01*
G01X-985Y1392298D02*
X-1D01*
G01D02*
X8523D01*
G01D02*
X12600D01*
G01X-4725Y1392416D02*
X-6694D01*
G01X-3151Y1392691D02*
X-2197D01*
G01X-4725Y1392849D02*
X-4259D01*
G01X-9844Y1393006D02*
X-6694D01*
G01X-1970Y1393085D02*
X-1D01*
G01Y1394109D02*
X-1970D01*
G01X-6694Y1394187D02*
X-9844D01*
G01X-4259Y1394345D02*
X-4725D01*
G01X-2197Y1394502D02*
X-3151D01*
G01X-4725Y1394778D02*
X-6694D01*
G01X15077Y1394896D02*
X8523D01*
G01D02*
X-1D01*
G01D02*
X-985D01*
G01Y1396235D02*
X-1D01*
G01D02*
X8523D01*
G01D02*
X12600D01*
G01X-4725Y1396353D02*
X-6694D01*
G01X-3151Y1396628D02*
X-2197D01*
G01X-4725Y1396786D02*
X-4259D01*
G01X-9844Y1396943D02*
X-6694D01*
G01X-1970Y1397022D02*
X-1D01*
G01X1968Y1397835D02*
X19881D01*
G01X15550Y1397947D02*
X1968D01*
G01D02*
X-1D01*
G01Y1404955D02*
X15550D01*
G01X1968Y1405315D02*
X19881D01*
G01X-1Y1405920D02*
X-1970D01*
G01X-6694Y1405998D02*
X-9844D01*
G01X-4259Y1406156D02*
X-4725D01*
G01X-2197Y1406313D02*
X-3151D01*
G01X-4725Y1406589D02*
X-6694D01*
G01X15077Y1406707D02*
X8523D01*
G01D02*
X-1D01*
G01D02*
X-985D01*
G01Y1408046D02*
X-1D01*
G01D02*
X8523D01*
G01D02*
X12600D01*
G01X-4725Y1408164D02*
X-6694D01*
G01X-3151Y1408439D02*
X-2197D01*
G01X-4725Y1408597D02*
X-4259D01*
G01X-9844Y1408754D02*
X-6694D01*
G01X-1970Y1408833D02*
X-1D01*
G01X-3378Y1393085D02*
X-4259Y1392849D01*
G01X-3378Y1397022D02*
X-4259Y1396786D01*
G01X-3378Y1408833D02*
X-4259Y1408597D01*
G01X-6694Y1393006D02*
X-4725Y1393321D01*
G01X-6694Y1396943D02*
X-4725Y1397258D01*
G01X-6694Y1408754D02*
X-4725Y1409069D01*
G01X-3378Y1429542D02*
X-3151Y1429935D01*
G01X-1970Y1428518D02*
X-2197Y1428124D01*
G01X-3378Y1425605D02*
X-3151Y1425998D01*
G01X-1970Y1424581D02*
X-2197Y1424187D01*
G01X-3378Y1421668D02*
X-3151Y1422061D01*
G01X-1970Y1420644D02*
X-2197Y1420250D01*
G01X-3378Y1417731D02*
X-3151Y1418124D01*
G01X-1970Y1416707D02*
X-2197Y1416313D01*
G01X-3378Y1413794D02*
X-3151Y1414187D01*
G01X-1970Y1412770D02*
X-2197Y1412376D01*
G01X-3378Y1409857D02*
X-3151Y1410250D01*
G01X-9844Y1428439D02*
X-10631Y1428085D01*
G01X-9844Y1424502D02*
X-10631Y1424148D01*
G01X-9844Y1420565D02*
X-10631Y1420211D01*
G01X-9844Y1416628D02*
X-10631Y1416274D01*
G01X-10531Y1428130D02*
Y1425993D01*
G01Y1420256D02*
Y1418119D01*
G01Y1424193D02*
Y1422056D01*
G01Y1416319D02*
Y1414181D01*
G01Y1412382D02*
Y1410244D01*
G01X-6694Y1430211D02*
Y1429620D01*
G01Y1428439D02*
Y1427849D01*
G01Y1426274D02*
Y1425683D01*
G01Y1424502D02*
Y1423912D01*
G01Y1422337D02*
Y1421746D01*
G01Y1420565D02*
Y1419975D01*
G01Y1418400D02*
Y1417809D01*
G01Y1416628D02*
Y1416038D01*
G01Y1414463D02*
Y1413872D01*
G01Y1412691D02*
Y1412101D01*
G01Y1410526D02*
Y1409935D01*
G01X-4725Y1430211D02*
Y1429306D01*
G01Y1428754D02*
Y1427849D01*
G01Y1426274D02*
Y1425369D01*
G01Y1424817D02*
Y1423912D01*
G01Y1422337D02*
Y1421431D01*
G01Y1420880D02*
Y1419975D01*
G01Y1418400D02*
Y1417494D01*
G01Y1416943D02*
Y1416038D01*
G01Y1414463D02*
Y1413557D01*
G01Y1413006D02*
Y1412101D01*
G01X-3757Y1428164D02*
Y1425959D01*
G01Y1420290D02*
Y1418085D01*
G01Y1424227D02*
Y1422022D01*
G01Y1416353D02*
Y1414148D01*
G01Y1412416D02*
Y1410211D01*
G01X-9844Y1412691D02*
X-10631Y1412337D01*
G01X-2521Y1428164D02*
Y1425959D01*
G01Y1420290D02*
Y1418085D01*
G01Y1424227D02*
Y1422022D01*
G01Y1416353D02*
Y1414148D01*
G01Y1412416D02*
Y1410211D01*
G01X-2251Y1432416D02*
Y1429581D01*
G01Y1428479D02*
Y1425644D01*
G01Y1424542D02*
Y1421707D01*
G01Y1420605D02*
Y1417770D01*
G01Y1416668D02*
Y1413833D01*
G01Y1412731D02*
Y1409896D01*
G01X-985Y1427731D02*
Y1426392D01*
G01Y1419857D02*
Y1418518D01*
G01Y1423794D02*
Y1422455D01*
G01Y1415920D02*
Y1414581D01*
G01Y1411983D02*
Y1410644D01*
G01X8523Y1427731D02*
Y1426392D01*
G01Y1423794D02*
Y1422455D01*
G01Y1419857D02*
Y1418518D01*
G01Y1415920D02*
Y1414581D01*
G01Y1411983D02*
Y1410644D01*
G01X-2197Y1410250D02*
X-1970Y1409857D01*
G01X-3151Y1412376D02*
X-3378Y1412770D01*
G01X-2197Y1414187D02*
X-1970Y1413794D01*
G01X-3151Y1416313D02*
X-3378Y1416707D01*
G01X-2197Y1418124D02*
X-1970Y1417731D01*
G01X-3151Y1420250D02*
X-3378Y1420644D01*
G01X-2197Y1422061D02*
X-1970Y1421668D01*
G01X-3151Y1424187D02*
X-3378Y1424581D01*
G01X-2197Y1425998D02*
X-1970Y1425605D01*
G01X-3151Y1428124D02*
X-3378Y1428518D01*
G01X-2197Y1429935D02*
X-1970Y1429542D01*
G01X-10631Y1410290D02*
X-9844Y1409935D01*
G01X-10631Y1414227D02*
X-9844Y1413872D01*
G01X-10631Y1418164D02*
X-9844Y1417809D01*
G01X-10631Y1422101D02*
X-9844Y1421746D01*
G01X-10631Y1426038D02*
X-9844Y1425683D01*
G01X-10631Y1429975D02*
X-9844Y1429620D01*
G01X-4259Y1410093D02*
X-3378Y1409857D01*
G01X-4259Y1414030D02*
X-3378Y1413794D01*
G01X-4259Y1417967D02*
X-3378Y1417731D01*
G01X-4259Y1421904D02*
X-3378Y1421668D01*
G01X-4259Y1425841D02*
X-3378Y1425605D01*
G01X-4259Y1429778D02*
X-3378Y1429542D01*
G01X-4725Y1413557D02*
X-6694Y1413872D01*
G01X-4725Y1417494D02*
X-6694Y1417809D01*
G01X-4725Y1421431D02*
X-6694Y1421746D01*
G01X-4725Y1425369D02*
X-6694Y1425683D01*
G01X-4725Y1429306D02*
X-6694Y1429620D01*
G01X-1Y1409857D02*
X-1970D01*
G01X-6694Y1409935D02*
X-9844D01*
G01X-4259Y1410093D02*
X-4725D01*
G01X-2197Y1410250D02*
X-3151D01*
G01X-4725Y1410526D02*
X-6694D01*
G01X15077Y1410644D02*
X8523D01*
G01D02*
X-1D01*
G01D02*
X-985D01*
G01Y1411983D02*
X-1D01*
G01D02*
X8523D01*
G01D02*
X12600D01*
G01X-4725Y1412101D02*
X-6694D01*
G01X-3151Y1412376D02*
X-2197D01*
G01X-4725Y1412534D02*
X-4259D01*
G01X-9844Y1412691D02*
X-6694D01*
G01X-1970Y1412770D02*
X-1D01*
G01Y1413794D02*
X-1970D01*
G01X-6694Y1413872D02*
X-9844D01*
G01X-4259Y1414030D02*
X-4725D01*
G01X-2197Y1414187D02*
X-3151D01*
G01X-4725Y1414463D02*
X-6694D01*
G01X15077Y1414581D02*
X8523D01*
G01D02*
X-1D01*
G01D02*
X-985D01*
G01Y1415920D02*
X-1D01*
G01D02*
X8523D01*
G01D02*
X12600D01*
G01X-4725Y1416038D02*
X-6694D01*
G01X-3151Y1416313D02*
X-2197D01*
G01X-4725Y1416471D02*
X-4259D01*
G01X-9844Y1416628D02*
X-6694D01*
G01X-1970Y1416707D02*
X-1D01*
G01Y1417731D02*
X-1970D01*
G01X-6694Y1417809D02*
X-9844D01*
G01X-4259Y1417967D02*
X-4725D01*
G01X-2197Y1418124D02*
X-3151D01*
G01X-4725Y1418400D02*
X-6694D01*
G01X15077Y1418518D02*
X8523D01*
G01D02*
X-1D01*
G01D02*
X-985D01*
G01Y1419857D02*
X-1D01*
G01D02*
X8523D01*
G01D02*
X12600D01*
G01X-4725Y1419975D02*
X-6694D01*
G01X-3151Y1420250D02*
X-2197D01*
G01X-4725Y1420408D02*
X-4259D01*
G01X-9844Y1420565D02*
X-6694D01*
G01X-1970Y1420644D02*
X-1D01*
G01Y1421668D02*
X-1970D01*
G01X-6694Y1421746D02*
X-9844D01*
G01X-4259Y1421904D02*
X-4725D01*
G01X-2197Y1422061D02*
X-3151D01*
G01X-4725Y1422337D02*
X-6694D01*
G01X15077Y1422455D02*
X8523D01*
G01D02*
X-1D01*
G01D02*
X-985D01*
G01Y1423794D02*
X-1D01*
G01D02*
X8523D01*
G01D02*
X12600D01*
G01X-4725Y1423912D02*
X-6694D01*
G01X-3151Y1424187D02*
X-2197D01*
G01X-4725Y1424345D02*
X-4259D01*
G01X-9844Y1424502D02*
X-6694D01*
G01X-1970Y1424581D02*
X-1D01*
G01Y1425605D02*
X-1970D01*
G01X-6694Y1425683D02*
X-9844D01*
G01X-4259Y1425841D02*
X-4725D01*
G01X-2197Y1425998D02*
X-3151D01*
G01X-4725Y1426274D02*
X-6694D01*
G01X15077Y1426392D02*
X8523D01*
G01D02*
X-1D01*
G01D02*
X-985D01*
G01Y1427731D02*
X-1D01*
G01D02*
X8523D01*
G01D02*
X12600D01*
G01X-4725Y1427849D02*
X-6694D01*
G01X-3151Y1428124D02*
X-2197D01*
G01X-4725Y1428282D02*
X-4259D01*
G01X-9844Y1428439D02*
X-6694D01*
G01X-1970Y1428518D02*
X-1D01*
G01Y1429542D02*
X-1970D01*
G01X-6694Y1429620D02*
X-9844D01*
G01X-3378Y1412770D02*
X-4259Y1412534D01*
G01X-3378Y1416707D02*
X-4259Y1416471D01*
G01X-6694Y1412691D02*
X-4725Y1413006D01*
G01X-6694Y1416628D02*
X-4725Y1416943D01*
G01X-6694Y1420565D02*
X-4725Y1420880D01*
G01X-6694Y1424502D02*
X-4725Y1424817D01*
G01X-6694Y1428439D02*
X-4725Y1428754D01*
G01X-3378Y1420644D02*
X-4259Y1420408D01*
G01X-3378Y1424581D02*
X-4259Y1424345D01*
G01X-3378Y1428518D02*
X-4259Y1428282D01*
G01X-3378Y1449227D02*
X-3151Y1449620D01*
G01X-1970Y1448203D02*
X-2197Y1447809D01*
G01X-3378Y1445290D02*
X-3151Y1445683D01*
G01X-1970Y1444266D02*
X-2197Y1443872D01*
G01X-3378Y1441353D02*
X-3151Y1441746D01*
G01X-1970Y1440329D02*
X-2197Y1439935D01*
G01X-3378Y1437416D02*
X-3151Y1437809D01*
G01X-1970Y1436392D02*
X-2197Y1435998D01*
G01X-3378Y1433479D02*
X-3151Y1433872D01*
G01X-1970Y1432455D02*
X-2197Y1432061D01*
G01X-9844Y1448124D02*
X-10631Y1447770D01*
G01X-9844Y1444187D02*
X-10631Y1443833D01*
G01X-9844Y1440250D02*
X-10631Y1439896D01*
G01X-9844Y1436313D02*
X-10631Y1435959D01*
G01X-9844Y1432376D02*
X-10631Y1432022D01*
G01X-10531Y1451752D02*
Y1449615D01*
G01Y1443878D02*
Y1441741D01*
G01Y1447815D02*
Y1445678D01*
G01Y1439941D02*
Y1437804D01*
G01Y1436004D02*
Y1433867D01*
G01Y1432067D02*
Y1429930D01*
G01X-6694Y1449896D02*
Y1449306D01*
G01Y1448124D02*
Y1447534D01*
G01Y1445959D02*
Y1445369D01*
G01Y1444187D02*
Y1443597D01*
G01Y1440250D02*
Y1439660D01*
G01Y1442022D02*
Y1441431D01*
G01Y1438085D02*
Y1437494D01*
G01Y1436313D02*
Y1435723D01*
G01Y1434148D02*
Y1433557D01*
G01Y1432376D02*
Y1431786D01*
G01X-4725Y1449896D02*
Y1448991D01*
G01Y1448439D02*
Y1447534D01*
G01Y1444502D02*
Y1443597D01*
G01Y1445959D02*
Y1445054D01*
G01Y1440565D02*
Y1439660D01*
G01Y1442022D02*
Y1441117D01*
G01Y1438085D02*
Y1437180D01*
G01Y1436628D02*
Y1435723D01*
G01Y1434148D02*
Y1433243D01*
G01Y1432691D02*
Y1431786D01*
G01X-3757Y1447849D02*
Y1445644D01*
G01Y1451786D02*
Y1449581D01*
G01Y1443912D02*
Y1441707D01*
G01Y1439975D02*
Y1437770D01*
G01Y1436038D02*
Y1433833D01*
G01Y1432101D02*
Y1429896D01*
G01X-2521Y1447849D02*
Y1445644D01*
G01Y1451786D02*
Y1449581D01*
G01Y1443912D02*
Y1441707D01*
G01Y1439975D02*
Y1437770D01*
G01Y1436038D02*
Y1433833D01*
G01Y1432101D02*
Y1429896D01*
G01X-2251Y1452101D02*
Y1449266D01*
G01Y1448164D02*
Y1445329D01*
G01Y1444227D02*
Y1441392D01*
G01Y1440290D02*
Y1437455D01*
G01Y1436353D02*
Y1433518D01*
G01X-985Y1443479D02*
Y1442140D01*
G01Y1447416D02*
Y1446077D01*
G01Y1439542D02*
Y1438203D01*
G01Y1435605D02*
Y1434266D01*
G01Y1431668D02*
Y1430329D01*
G01X8523Y1447416D02*
Y1446077D01*
G01Y1443479D02*
Y1442140D01*
G01Y1439542D02*
Y1438203D01*
G01Y1435605D02*
Y1434266D01*
G01Y1431668D02*
Y1430329D01*
G01X-3151Y1432061D02*
X-3378Y1432455D01*
G01X-2197Y1433872D02*
X-1970Y1433479D01*
G01X-3151Y1435998D02*
X-3378Y1436392D01*
G01X-2197Y1437809D02*
X-1970Y1437416D01*
G01X-3151Y1439935D02*
X-3378Y1440329D01*
G01X-2197Y1441746D02*
X-1970Y1441353D01*
G01X-3151Y1443872D02*
X-3378Y1444266D01*
G01X-2197Y1445683D02*
X-1970Y1445290D01*
G01X-3151Y1447809D02*
X-3378Y1448203D01*
G01X-2197Y1449620D02*
X-1970Y1449227D01*
G01X-10631Y1433912D02*
X-9844Y1433557D01*
G01X-10631Y1437849D02*
X-9844Y1437494D01*
G01X-10631Y1441786D02*
X-9844Y1441431D01*
G01X-10631Y1445723D02*
X-9844Y1445369D01*
G01X-10631Y1449660D02*
X-9844Y1449306D01*
G01X-4259Y1433715D02*
X-3378Y1433479D01*
G01X-4259Y1437652D02*
X-3378Y1437416D01*
G01X-4259Y1441589D02*
X-3378Y1441353D01*
G01X-4259Y1445526D02*
X-3378Y1445290D01*
G01X-4259Y1449463D02*
X-3378Y1449227D01*
G01X-4725Y1433243D02*
X-6694Y1433557D01*
G01X-4725Y1437180D02*
X-6694Y1437494D01*
G01X-4725Y1441117D02*
X-6694Y1441431D01*
G01X-4725Y1445054D02*
X-6694Y1445369D01*
G01X-4725Y1448991D02*
X-6694Y1449306D01*
G01X-4259Y1429778D02*
X-4725D01*
G01X-2197Y1429935D02*
X-3151D01*
G01X-4725Y1430211D02*
X-6694D01*
G01X15077Y1430329D02*
X8523D01*
G01D02*
X-1D01*
G01D02*
X-985D01*
G01Y1431668D02*
X-1D01*
G01D02*
X8523D01*
G01D02*
X12600D01*
G01X-4725Y1431786D02*
X-6694D01*
G01X-3151Y1432061D02*
X-2197D01*
G01X-4725Y1432219D02*
X-4259D01*
G01X-9844Y1432376D02*
X-6694D01*
G01X-1970Y1432455D02*
X-1D01*
G01Y1433479D02*
X-1970D01*
G01X-6694Y1433557D02*
X-9844D01*
G01X-4259Y1433715D02*
X-4725D01*
G01X-2197Y1433872D02*
X-3151D01*
G01X-4725Y1434148D02*
X-6694D01*
G01X15077Y1434266D02*
X8523D01*
G01D02*
X-1D01*
G01D02*
X-985D01*
G01Y1435605D02*
X-1D01*
G01D02*
X8523D01*
G01D02*
X12600D01*
G01X-4725Y1435723D02*
X-6694D01*
G01X-3151Y1435998D02*
X-2197D01*
G01X-4725Y1436156D02*
X-4259D01*
G01X-9844Y1436313D02*
X-6694D01*
G01X-1970Y1436392D02*
X-1D01*
G01Y1437416D02*
X-1970D01*
G01X-6694Y1437494D02*
X-9844D01*
G01X-4259Y1437652D02*
X-4725D01*
G01X-2197Y1437809D02*
X-3151D01*
G01X-4725Y1438085D02*
X-6694D01*
G01X15077Y1438203D02*
X8523D01*
G01D02*
X-1D01*
G01D02*
X-985D01*
G01Y1439542D02*
X-1D01*
G01D02*
X8523D01*
G01D02*
X12600D01*
G01X-4725Y1439660D02*
X-6694D01*
G01X-3151Y1439935D02*
X-2197D01*
G01X-4725Y1440093D02*
X-4259D01*
G01X-9844Y1440250D02*
X-6694D01*
G01X-1970Y1440329D02*
X-1D01*
G01Y1441353D02*
X-1970D01*
G01X-6694Y1441431D02*
X-9844D01*
G01X-4259Y1441589D02*
X-4725D01*
G01X-2197Y1441746D02*
X-3151D01*
G01X-4725Y1442022D02*
X-6694D01*
G01X15077Y1442140D02*
X8523D01*
G01D02*
X-1D01*
G01D02*
X-985D01*
G01Y1443479D02*
X-1D01*
G01D02*
X8523D01*
G01D02*
X12600D01*
G01X-4725Y1443597D02*
X-6694D01*
G01X-3151Y1443872D02*
X-2197D01*
G01X-4725Y1444030D02*
X-4259D01*
G01X-9844Y1444187D02*
X-6694D01*
G01X-1970Y1444266D02*
X-1D01*
G01Y1445290D02*
X-1970D01*
G01X-6694Y1445369D02*
X-9844D01*
G01X-4259Y1445526D02*
X-4725D01*
G01X-2197Y1445683D02*
X-3151D01*
G01X-4725Y1445959D02*
X-6694D01*
G01X15077Y1446077D02*
X8523D01*
G01D02*
X-1D01*
G01D02*
X-985D01*
G01Y1447416D02*
X-1D01*
G01D02*
X8523D01*
G01D02*
X12600D01*
G01X-4725Y1447534D02*
X-6694D01*
G01X-3151Y1447809D02*
X-2197D01*
G01X-4725Y1447967D02*
X-4259D01*
G01X-9844Y1448124D02*
X-6694D01*
G01X-1970Y1448203D02*
X-1D01*
G01Y1449227D02*
X-1970D01*
G01X-6694Y1449306D02*
X-9844D01*
G01X-4259Y1449463D02*
X-4725D01*
G01X-2197Y1449620D02*
X-3151D01*
G01X-6694Y1432376D02*
X-4725Y1432691D01*
G01X-6694Y1436313D02*
X-4725Y1436628D01*
G01X-6694Y1440250D02*
X-4725Y1440565D01*
G01X-6694Y1444187D02*
X-4725Y1444502D01*
G01X-6694Y1448124D02*
X-4725Y1448439D01*
G01X-3378Y1432455D02*
X-4259Y1432219D01*
G01X-3378Y1436392D02*
X-4259Y1436156D01*
G01X-3378Y1440329D02*
X-4259Y1440093D01*
G01X-3378Y1444266D02*
X-4259Y1444030D01*
G01X-3378Y1448203D02*
X-4259Y1447967D01*
G01X-3378Y1468912D02*
X-3151Y1469306D01*
G01X-1970Y1467888D02*
X-2197Y1467494D01*
G01X-3378Y1464975D02*
X-3151Y1465369D01*
G01X-1970Y1463951D02*
X-2197Y1463557D01*
G01X-3378Y1461038D02*
X-3151Y1461431D01*
G01X-1970Y1460014D02*
X-2197Y1459620D01*
G01X-3378Y1457101D02*
X-3151Y1457494D01*
G01X-1970Y1456077D02*
X-2197Y1455683D01*
G01X-3378Y1453164D02*
X-3151Y1453557D01*
G01X-1970Y1452140D02*
X-2197Y1451746D01*
G01X-9844Y1467809D02*
X-10631Y1467455D01*
G01X-9844Y1463872D02*
X-10631Y1463518D01*
G01X-9844Y1459935D02*
X-10631Y1459581D01*
G01X-9844Y1455998D02*
X-10631Y1455644D01*
G01X-9844Y1452061D02*
X-10631Y1451707D01*
G01X-10531Y1471437D02*
Y1469300D01*
G01Y1467500D02*
Y1465363D01*
G01Y1463563D02*
Y1461426D01*
G01Y1459626D02*
Y1457489D01*
G01Y1455689D02*
Y1453552D01*
G01X-6694Y1469581D02*
Y1468991D01*
G01Y1467809D02*
Y1467219D01*
G01Y1465644D02*
Y1465054D01*
G01Y1463872D02*
Y1463282D01*
G01Y1461707D02*
Y1461117D01*
G01Y1459935D02*
Y1459345D01*
G01Y1457770D02*
Y1457180D01*
G01Y1455998D02*
Y1455408D01*
G01Y1453833D02*
Y1453243D01*
G01Y1452061D02*
Y1451471D01*
G01X-4725Y1468124D02*
Y1467219D01*
G01Y1469581D02*
Y1468676D01*
G01Y1464187D02*
Y1463282D01*
G01Y1465644D02*
Y1464739D01*
G01Y1460250D02*
Y1459345D01*
G01Y1457770D02*
Y1456865D01*
G01Y1461707D02*
Y1460802D01*
G01Y1456313D02*
Y1455408D01*
G01Y1453833D02*
Y1452928D01*
G01Y1452376D02*
Y1451471D01*
G01X-3757Y1471471D02*
Y1469266D01*
G01Y1467534D02*
Y1465329D01*
G01Y1463597D02*
Y1461392D01*
G01Y1459660D02*
Y1457455D01*
G01Y1455723D02*
Y1453518D01*
G01X-2521Y1471471D02*
Y1469266D01*
G01Y1467534D02*
Y1465329D01*
G01Y1463597D02*
Y1461392D01*
G01Y1459660D02*
Y1457455D01*
G01Y1455723D02*
Y1453518D01*
G01X-2251Y1471786D02*
Y1468951D01*
G01Y1467849D02*
Y1465014D01*
G01Y1463912D02*
Y1461077D01*
G01Y1459975D02*
Y1457140D01*
G01Y1456038D02*
Y1453203D01*
G01X-985Y1467101D02*
Y1465762D01*
G01Y1471038D02*
Y1469699D01*
G01Y1463164D02*
Y1461825D01*
G01Y1459227D02*
Y1457888D01*
G01Y1455290D02*
Y1453951D01*
G01Y1451353D02*
Y1450014D01*
G01X8523Y1471038D02*
Y1469699D01*
G01Y1467101D02*
Y1465762D01*
G01Y1463164D02*
Y1461825D01*
G01Y1459227D02*
Y1457888D01*
G01Y1455290D02*
Y1453951D01*
G01Y1451353D02*
Y1450014D01*
G01X-3151Y1451746D02*
X-3378Y1452140D01*
G01X-2197Y1453557D02*
X-1970Y1453164D01*
G01X-3151Y1455683D02*
X-3378Y1456077D01*
G01X-2197Y1457494D02*
X-1970Y1457101D01*
G01X-3151Y1459620D02*
X-3378Y1460014D01*
G01X-2197Y1461431D02*
X-1970Y1461038D01*
G01X-3151Y1463557D02*
X-3378Y1463951D01*
G01X-2197Y1465369D02*
X-1970Y1464975D01*
G01X-3151Y1467494D02*
X-3378Y1467888D01*
G01X-2197Y1469306D02*
X-1970Y1468912D01*
G01X-10631Y1453597D02*
X-9844Y1453243D01*
G01X-10631Y1457534D02*
X-9844Y1457180D01*
G01X-10631Y1461471D02*
X-9844Y1461117D01*
G01X-10631Y1465408D02*
X-9844Y1465054D01*
G01X-10631Y1469345D02*
X-9844Y1468991D01*
G01X-4259Y1453400D02*
X-3378Y1453164D01*
G01X-4259Y1457337D02*
X-3378Y1457101D01*
G01X-4259Y1461274D02*
X-3378Y1461038D01*
G01X-4725Y1452928D02*
X-6694Y1453243D01*
G01X-4725Y1456865D02*
X-6694Y1457180D01*
G01X-4725Y1460802D02*
X-6694Y1461117D01*
G01X-4725Y1464739D02*
X-6694Y1465054D01*
G01X-4725Y1468676D02*
X-6694Y1468991D01*
G01X-4259Y1465211D02*
X-3378Y1464975D01*
G01X-4259Y1469148D02*
X-3378Y1468912D01*
G01X-4725Y1449896D02*
X-6694D01*
G01X15077Y1450014D02*
X8523D01*
G01D02*
X-1D01*
G01D02*
X-985D01*
G01Y1451353D02*
X-1D01*
G01D02*
X8523D01*
G01D02*
X12600D01*
G01X-4725Y1451471D02*
X-6694D01*
G01X-3151Y1451746D02*
X-2197D01*
G01X-4725Y1451904D02*
X-4259D01*
G01X-9844Y1452061D02*
X-6694D01*
G01X-1970Y1452140D02*
X-1D01*
G01Y1453164D02*
X-1970D01*
G01X-6694Y1453243D02*
X-9844D01*
G01X-4259Y1453400D02*
X-4725D01*
G01X-2197Y1453557D02*
X-3151D01*
G01X-4725Y1453833D02*
X-6694D01*
G01X15077Y1453951D02*
X8523D01*
G01D02*
X-1D01*
G01D02*
X-985D01*
G01Y1455290D02*
X-1D01*
G01D02*
X8523D01*
G01D02*
X12600D01*
G01X-4725Y1455408D02*
X-6694D01*
G01X-3151Y1455683D02*
X-2197D01*
G01X-4725Y1455841D02*
X-4259D01*
G01X-9844Y1455998D02*
X-6694D01*
G01X-1970Y1456077D02*
X-1D01*
G01Y1457101D02*
X-1970D01*
G01X-6694Y1457180D02*
X-9844D01*
G01X-4259Y1457337D02*
X-4725D01*
G01X-2197Y1457494D02*
X-3151D01*
G01X-4725Y1457770D02*
X-6694D01*
G01X15077Y1457888D02*
X8523D01*
G01D02*
X-1D01*
G01D02*
X-985D01*
G01Y1459227D02*
X-1D01*
G01D02*
X8523D01*
G01D02*
X12600D01*
G01X-4725Y1459345D02*
X-6694D01*
G01X-3151Y1459620D02*
X-2197D01*
G01X-4725Y1459778D02*
X-4259D01*
G01X-9844Y1459935D02*
X-6694D01*
G01X-1970Y1460014D02*
X-1D01*
G01Y1461038D02*
X-1970D01*
G01X-6694Y1461117D02*
X-9844D01*
G01X-4259Y1461274D02*
X-4725D01*
G01X-2197Y1461431D02*
X-3151D01*
G01X-4725Y1461707D02*
X-6694D01*
G01X15077Y1461825D02*
X8523D01*
G01D02*
X-1D01*
G01D02*
X-985D01*
G01Y1463164D02*
X-1D01*
G01D02*
X8523D01*
G01D02*
X12600D01*
G01X-6694Y1452061D02*
X-4725Y1452376D01*
G01X-6694Y1455998D02*
X-4725Y1456313D01*
G01X-6694Y1459935D02*
X-4725Y1460250D01*
G01Y1463282D02*
X-6694D01*
G01X-3151Y1463557D02*
X-2197D01*
G01X-4725Y1463715D02*
X-4259D01*
G01X-9844Y1463872D02*
X-6694D01*
G01X-1970Y1463951D02*
X-1D01*
G01Y1464975D02*
X-1970D01*
G01X-6694Y1465054D02*
X-9844D01*
G01X-4259Y1465211D02*
X-4725D01*
G01X-2197Y1465369D02*
X-3151D01*
G01X-4725Y1465644D02*
X-6694D01*
G01X15077Y1465762D02*
X8523D01*
G01D02*
X-1D01*
G01D02*
X-985D01*
G01Y1467101D02*
X-1D01*
G01D02*
X8523D01*
G01D02*
X12600D01*
G01X-4725Y1467219D02*
X-6694D01*
G01X-3151Y1467494D02*
X-2197D01*
G01X-4725Y1467652D02*
X-4259D01*
G01X-9844Y1467809D02*
X-6694D01*
G01X-1970Y1467888D02*
X-1D01*
G01Y1468912D02*
X-1970D01*
G01X-6694Y1468991D02*
X-9844D01*
G01X-4259Y1469148D02*
X-4725D01*
G01X-2197Y1469306D02*
X-3151D01*
G01X-4725Y1469581D02*
X-6694D01*
G01X15077Y1469699D02*
X8523D01*
G01D02*
X-1D01*
G01D02*
X-985D01*
G01X-3378Y1452140D02*
X-4259Y1451904D01*
G01X-3378Y1456077D02*
X-4259Y1455841D01*
G01X-3378Y1460014D02*
X-4259Y1459778D01*
G01X-3378Y1463951D02*
X-4259Y1463715D01*
G01X-3378Y1467888D02*
X-4259Y1467652D01*
G01X-6694Y1463872D02*
X-4725Y1464187D01*
G01X-6694Y1467809D02*
X-4725Y1468124D01*
G01X-3378Y1472849D02*
X-3151Y1473243D01*
G01X-1970Y1471825D02*
X-2197Y1471431D01*
G01X-9844Y1471746D02*
X-10631Y1471392D01*
G01X-10531Y1475374D02*
Y1473237D01*
G01X-6694Y1473518D02*
Y1472928D01*
G01Y1471746D02*
Y1471156D01*
G01X-4725Y1472061D02*
Y1471156D01*
G01Y1473518D02*
Y1472613D01*
G01X-3757Y1475408D02*
Y1473203D01*
G01X-2521Y1475408D02*
Y1473203D01*
G01X-2251Y1475723D02*
Y1472888D01*
G01X-985Y1474975D02*
Y1473636D01*
G01X8523Y1474975D02*
Y1473636D01*
G01X-3151Y1471431D02*
X-3378Y1471825D01*
G01X-2197Y1473243D02*
X-1970Y1472849D01*
G01X-10631Y1473282D02*
X-9844Y1472928D01*
G01X-4725Y1472613D02*
X-6694Y1472928D01*
G01X-4259Y1473085D02*
X-3378Y1472849D01*
G01X-985Y1471038D02*
X-1D01*
G01D02*
X8523D01*
G01D02*
X12600D01*
G01X-4725Y1471156D02*
X-6694D01*
G01X-3151Y1471431D02*
X-2197D01*
G01X-4725Y1471589D02*
X-4259D01*
G01X-9844Y1471746D02*
X-6694D01*
G01X-1970Y1471825D02*
X-1D01*
G01Y1472849D02*
X-1970D01*
G01X-6694Y1472928D02*
X-9844D01*
G01X-4259Y1473085D02*
X-4725D01*
G01X-2197Y1473243D02*
X-3151D01*
G01X-4725Y1473518D02*
X-6694D01*
G01X15077Y1473636D02*
X8523D01*
G01D02*
X-1D01*
G01D02*
X-985D01*
G01X-3378Y1471825D02*
X-4259Y1471589D01*
G01X-6694Y1471746D02*
X-4725Y1472061D01*
G01X-38426Y1487298D02*
Y1484935D01*
G01Y1491235D02*
Y1488872D01*
G01Y1483361D02*
Y1480998D01*
G01Y1479424D02*
Y1477061D01*
G01X-38108Y1490536D02*
Y1489571D01*
G01Y1486599D02*
Y1485634D01*
G01Y1482662D02*
Y1481697D01*
G01Y1478725D02*
Y1477760D01*
G01X-37871Y1490559D02*
Y1489548D01*
G01Y1486622D02*
Y1485611D01*
G01Y1482685D02*
Y1481674D01*
G01Y1478748D02*
Y1477737D01*
G01X-35595Y1490778D02*
Y1489329D01*
G01Y1486841D02*
Y1485392D01*
G01Y1482904D02*
Y1481455D01*
G01Y1478967D02*
Y1477518D01*
G01X-35546Y1491235D02*
Y1488872D01*
G01Y1487298D02*
Y1484935D01*
G01Y1483361D02*
Y1480998D01*
G01Y1479424D02*
Y1477061D01*
G01X-35357Y1490801D02*
Y1489306D01*
G01Y1486864D02*
Y1485369D01*
G01Y1482927D02*
Y1481432D01*
G01Y1478990D02*
Y1477495D01*
G01X-34607Y1487219D02*
Y1485014D01*
G01Y1491156D02*
Y1488951D01*
G01Y1483282D02*
Y1481077D01*
G01Y1479345D02*
Y1477140D01*
G01X-34136Y1490815D02*
Y1489292D01*
G01Y1486878D02*
Y1485355D01*
G01Y1482941D02*
Y1481418D01*
G01Y1479004D02*
Y1477481D01*
G01X-33153Y1490826D02*
Y1489281D01*
G01Y1486889D02*
Y1485344D01*
G01Y1482952D02*
Y1481407D01*
G01Y1479015D02*
Y1477470D01*
G01X-32319Y1490835D02*
Y1489272D01*
G01Y1486898D02*
Y1485335D01*
G01Y1482961D02*
Y1481398D01*
G01Y1479024D02*
Y1477461D01*
G01X-31941Y1490839D02*
Y1489267D01*
G01Y1486902D02*
Y1485330D01*
G01Y1482965D02*
Y1481393D01*
G01Y1479028D02*
Y1477456D01*
G01X-38108Y1477760D02*
X-35351Y1477494D01*
G01X-38108Y1481697D02*
X-35351Y1481431D01*
G01X-38108Y1485634D02*
X-35351Y1485369D01*
G01X-38108Y1489571D02*
X-35351Y1489306D01*
G01Y1475054D02*
X-38108Y1474788D01*
G01X-35351Y1478991D02*
X-38108Y1478725D01*
G01X-35351Y1482928D02*
X-38108Y1482662D01*
G01X-35351Y1486865D02*
X-38108Y1486599D01*
G01X-35351Y1475054D02*
X-10631Y1475329D01*
G01X-35351Y1478991D02*
X-10631Y1479266D01*
G01X-35351Y1482928D02*
X-10631Y1483203D01*
G01X-35351Y1486865D02*
X-10631Y1487140D01*
G01X-35546Y1475408D02*
X-1D01*
G01X-24509Y1475487D02*
X-39607D01*
G01Y1477061D02*
X-24509D01*
G01X-35546Y1477140D02*
X-1D01*
G01X-27993Y1479128D02*
X-39607D01*
G01X-35546Y1479345D02*
X-1D01*
G01X-24509Y1479424D02*
X-39607D01*
G01Y1480998D02*
X-24509D01*
G01X-35546Y1481077D02*
X-1D01*
G01X-39607Y1482278D02*
X-24844D01*
G01X-35546Y1483282D02*
X-1D01*
G01X-24509Y1483361D02*
X-39607D01*
G01Y1484935D02*
X-24509D01*
G01X-35546Y1485014D02*
X-1D01*
G01X-39607Y1486254D02*
X-24844D01*
G01X-35546Y1487219D02*
X-1D01*
G01X-24509Y1487298D02*
X-39607D01*
G01Y1488872D02*
X-24509D01*
G01X-35546Y1488951D02*
X-1D01*
G01X-39607Y1489404D02*
X-27993D01*
G01X-10631Y1477219D02*
X-35351Y1477494D01*
G01X-10631Y1481156D02*
X-35351Y1481431D01*
G01X-10631Y1485093D02*
X-35351Y1485369D01*
G01X-10631Y1489030D02*
X-35351Y1489306D01*
G01X-38426Y1510920D02*
Y1508557D01*
G01Y1506983D02*
Y1504620D01*
G01Y1503046D02*
Y1500683D01*
G01Y1495172D02*
Y1492809D01*
G01Y1499109D02*
Y1496746D01*
G01X-38108Y1510221D02*
Y1509256D01*
G01Y1506284D02*
Y1505319D01*
G01Y1502347D02*
Y1501382D01*
G01Y1498410D02*
Y1497445D01*
G01Y1494473D02*
Y1493508D01*
G01X-37871Y1510244D02*
Y1509233D01*
G01Y1506307D02*
Y1505296D01*
G01Y1502370D02*
Y1501359D01*
G01Y1498433D02*
Y1497422D01*
G01Y1494496D02*
Y1493485D01*
G01X-35595Y1510463D02*
Y1509014D01*
G01Y1506526D02*
Y1505077D01*
G01Y1502589D02*
Y1501140D01*
G01Y1498652D02*
Y1497203D01*
G01Y1494715D02*
Y1493266D01*
G01X-35546Y1510920D02*
Y1508557D01*
G01Y1506983D02*
Y1504620D01*
G01Y1503046D02*
Y1500683D01*
G01Y1499109D02*
Y1496746D01*
G01Y1495172D02*
Y1492809D01*
G01X-35357Y1510486D02*
Y1508991D01*
G01Y1506549D02*
Y1505054D01*
G01Y1502612D02*
Y1501117D01*
G01Y1498675D02*
Y1497180D01*
G01Y1494738D02*
Y1493243D01*
G01X-34607Y1510841D02*
Y1508636D01*
G01Y1506904D02*
Y1504699D01*
G01Y1502967D02*
Y1500762D01*
G01Y1495093D02*
Y1492888D01*
G01Y1499030D02*
Y1496825D01*
G01X-34136Y1510500D02*
Y1508977D01*
G01Y1506563D02*
Y1505040D01*
G01Y1502626D02*
Y1501103D01*
G01Y1494752D02*
Y1493229D01*
G01Y1498689D02*
Y1497166D01*
G01X-33153Y1510511D02*
Y1508966D01*
G01Y1506574D02*
Y1505029D01*
G01Y1502637D02*
Y1501092D01*
G01Y1498700D02*
Y1497155D01*
G01Y1494763D02*
Y1493218D01*
G01X-32319Y1510520D02*
Y1508957D01*
G01Y1506583D02*
Y1505020D01*
G01Y1502646D02*
Y1501083D01*
G01Y1494772D02*
Y1493209D01*
G01Y1498709D02*
Y1497146D01*
G01X-31941Y1510524D02*
Y1508952D01*
G01Y1506587D02*
Y1505015D01*
G01Y1502650D02*
Y1501078D01*
G01Y1494776D02*
Y1493204D01*
G01Y1498713D02*
Y1497141D01*
G01X-38108Y1493508D02*
X-35351Y1493243D01*
G01X-38108Y1497445D02*
X-35351Y1497180D01*
G01X-38108Y1501382D02*
X-35351Y1501117D01*
G01X-38108Y1505319D02*
X-35351Y1505054D01*
G01X-38108Y1509256D02*
X-35351Y1508991D01*
G01Y1490802D02*
X-10631Y1491077D01*
G01X-35351Y1494739D02*
X-10631Y1495014D01*
G01X-35351Y1498676D02*
X-10631Y1498951D01*
G01X-35351Y1502613D02*
X-10631Y1502888D01*
G01X-35351Y1506550D02*
X-10631Y1506825D01*
G01X-35546Y1491156D02*
X-1D01*
G01X-24509Y1491235D02*
X-39607D01*
G01Y1492809D02*
X-24509D01*
G01X-35546Y1492888D02*
X-1D01*
G01X-35546Y1495093D02*
X-1D01*
G01X-24509Y1495172D02*
X-39607D01*
G01Y1496746D02*
X-24509D01*
G01X-35546Y1496825D02*
X-1D01*
G01X-35546Y1499030D02*
X-1D01*
G01X-24509Y1499109D02*
X-39607D01*
G01Y1500683D02*
X-24509D01*
G01X-35546Y1500762D02*
X-1D01*
G01X-27993Y1502750D02*
X-39607D01*
G01X-35546Y1502967D02*
X-1D01*
G01X-24509Y1503046D02*
X-39607D01*
G01Y1504620D02*
X-24509D01*
G01X-35546Y1504699D02*
X-1D01*
G01X-39607Y1505900D02*
X-24844D01*
G01X-35546Y1506904D02*
X-1D01*
G01X-24509Y1506983D02*
X-39607D01*
G01Y1508557D02*
X-24509D01*
G01X-35546Y1508636D02*
X-1D01*
G01X-39607Y1509876D02*
X-24844D01*
G01X-10631Y1492967D02*
X-35351Y1493243D01*
G01X-10631Y1496904D02*
X-35351Y1497180D01*
G01X-10631Y1500841D02*
X-35351Y1501117D01*
G01X-10631Y1504778D02*
X-35351Y1505054D01*
G01X-10631Y1508715D02*
X-35351Y1508991D01*
G01Y1490802D02*
X-38108Y1490536D01*
G01X-35351Y1494739D02*
X-38108Y1494473D01*
G01X-35351Y1498676D02*
X-38108Y1498410D01*
G01X-35351Y1502613D02*
X-38108Y1502347D01*
G01X-35351Y1506550D02*
X-38108Y1506284D01*
G01X-38426Y1530605D02*
Y1528243D01*
G01Y1522731D02*
Y1520369D01*
G01Y1526668D02*
Y1524306D01*
G01Y1518794D02*
Y1516431D01*
G01Y1514857D02*
Y1512494D01*
G01X-38108Y1529906D02*
Y1528941D01*
G01Y1525969D02*
Y1525004D01*
G01Y1522032D02*
Y1521067D01*
G01Y1518095D02*
Y1517130D01*
G01Y1514158D02*
Y1513193D01*
G01X-37871Y1529929D02*
Y1528918D01*
G01Y1525992D02*
Y1524981D01*
G01Y1518118D02*
Y1517107D01*
G01Y1522055D02*
Y1521044D01*
G01Y1514181D02*
Y1513170D01*
G01X-35595Y1530148D02*
Y1528699D01*
G01Y1526211D02*
Y1524762D01*
G01Y1522274D02*
Y1520825D01*
G01Y1518337D02*
Y1516888D01*
G01Y1514400D02*
Y1512951D01*
G01X-35546Y1530605D02*
Y1528243D01*
G01Y1526668D02*
Y1524306D01*
G01Y1522731D02*
Y1520369D01*
G01Y1518794D02*
Y1516431D01*
G01Y1514857D02*
Y1512494D01*
G01X-35357Y1530171D02*
Y1528676D01*
G01Y1526234D02*
Y1524739D01*
G01Y1522297D02*
Y1520802D01*
G01Y1518360D02*
Y1516865D01*
G01Y1514423D02*
Y1512928D01*
G01X-34607Y1530526D02*
Y1528321D01*
G01Y1526589D02*
Y1524384D01*
G01Y1518715D02*
Y1516510D01*
G01Y1522652D02*
Y1520447D01*
G01Y1514778D02*
Y1512573D01*
G01X-34136Y1530185D02*
Y1528662D01*
G01Y1526248D02*
Y1524725D01*
G01Y1518374D02*
Y1516851D01*
G01Y1522311D02*
Y1520788D01*
G01Y1514437D02*
Y1512914D01*
G01X-33153Y1530196D02*
Y1528651D01*
G01Y1526259D02*
Y1524714D01*
G01Y1522322D02*
Y1520777D01*
G01Y1518385D02*
Y1516840D01*
G01Y1514448D02*
Y1512903D01*
G01X-32319Y1530205D02*
Y1528642D01*
G01Y1526268D02*
Y1524705D01*
G01Y1518394D02*
Y1516831D01*
G01Y1522331D02*
Y1520768D01*
G01Y1514457D02*
Y1512894D01*
G01X-31941Y1530209D02*
Y1528637D01*
G01Y1526272D02*
Y1524700D01*
G01Y1518398D02*
Y1516826D01*
G01Y1522335D02*
Y1520763D01*
G01Y1514461D02*
Y1512889D01*
G01X-38108Y1513193D02*
X-35351Y1512928D01*
G01X-38108Y1517130D02*
X-35351Y1516865D01*
G01Y1510487D02*
X-10631Y1510762D01*
G01X-35351Y1514424D02*
X-10631Y1514699D01*
G01X-35351Y1518361D02*
X-10631Y1518636D01*
G01X-35351Y1522298D02*
X-10631Y1522573D01*
G01X-35351Y1526235D02*
X-10631Y1526510D01*
G01X-35351Y1530172D02*
X-10631Y1530447D01*
G01X-35546Y1510841D02*
X-1D01*
G01X-24509Y1510920D02*
X-39607D01*
G01Y1512494D02*
X-24509D01*
G01X-35546Y1512573D02*
X-1D01*
G01X-39607Y1513026D02*
X-27993D01*
G01X-35546Y1514778D02*
X-1D01*
G01X-24509Y1514857D02*
X-39607D01*
G01Y1516431D02*
X-24509D01*
G01X-35546Y1516510D02*
X-1D01*
G01X-35546Y1518715D02*
X-1D01*
G01X-24509Y1518794D02*
X-39607D01*
G01Y1520369D02*
X-24509D01*
G01X-35546Y1520447D02*
X-1D01*
G01X-35546Y1522652D02*
X-1D01*
G01X-24509Y1522731D02*
X-39607D01*
G01Y1524306D02*
X-24509D01*
G01X-35546Y1524384D02*
X-1D01*
G01X-27993Y1526372D02*
X-39607D01*
G01X-35546Y1526589D02*
X-1D01*
G01X-24509Y1526668D02*
X-39607D01*
G01Y1528243D02*
X-24509D01*
G01X-35546Y1528321D02*
X-1D01*
G01X-39607Y1529522D02*
X-24844D01*
G01X-10631Y1512652D02*
X-35351Y1512928D01*
G01X-10631Y1516589D02*
X-35351Y1516865D01*
G01X-10631Y1520526D02*
X-35351Y1520802D01*
G01X-10631Y1524463D02*
X-35351Y1524739D01*
G01X-10631Y1528400D02*
X-35351Y1528676D01*
G01X-38108Y1521067D02*
X-35351Y1520802D01*
G01X-38108Y1525004D02*
X-35351Y1524739D01*
G01X-38108Y1528941D02*
X-35351Y1528676D01*
G01Y1510487D02*
X-38108Y1510221D01*
G01X-35351Y1514424D02*
X-38108Y1514158D01*
G01X-35351Y1518361D02*
X-38108Y1518095D01*
G01X-35351Y1522298D02*
X-38108Y1522032D01*
G01X-35351Y1526235D02*
X-38108Y1525969D01*
G01X-35351Y1530172D02*
X-38108Y1529906D01*
G01X-38426Y1546353D02*
Y1543991D01*
G01Y1550290D02*
Y1547928D01*
G01Y1542416D02*
Y1540054D01*
G01Y1534542D02*
Y1532180D01*
G01Y1538479D02*
Y1536117D01*
G01X-38108Y1549591D02*
Y1548626D01*
G01Y1541717D02*
Y1540752D01*
G01Y1545654D02*
Y1544689D01*
G01Y1537780D02*
Y1536815D01*
G01Y1533843D02*
Y1532878D01*
G01X-37871Y1549614D02*
Y1548603D01*
G01Y1541740D02*
Y1540729D01*
G01Y1545677D02*
Y1544666D01*
G01Y1537803D02*
Y1536792D01*
G01Y1533866D02*
Y1532855D01*
G01X-35595Y1549833D02*
Y1548384D01*
G01Y1541959D02*
Y1540510D01*
G01Y1545896D02*
Y1544447D01*
G01Y1534085D02*
Y1532636D01*
G01Y1538022D02*
Y1536573D01*
G01X-35546Y1550290D02*
Y1547928D01*
G01Y1546353D02*
Y1543991D01*
G01Y1542416D02*
Y1540054D01*
G01Y1538479D02*
Y1536117D01*
G01Y1534542D02*
Y1532180D01*
G01X-35357Y1549856D02*
Y1548361D01*
G01Y1545919D02*
Y1544424D01*
G01Y1541982D02*
Y1540487D01*
G01Y1538045D02*
Y1536550D01*
G01Y1534108D02*
Y1532613D01*
G01X-34607Y1546274D02*
Y1544069D01*
G01Y1550211D02*
Y1548006D01*
G01Y1542337D02*
Y1540132D01*
G01Y1534463D02*
Y1532258D01*
G01Y1538400D02*
Y1536195D01*
G01X-34136Y1549870D02*
Y1548347D01*
G01Y1541996D02*
Y1540473D01*
G01Y1545933D02*
Y1544410D01*
G01Y1538059D02*
Y1536536D01*
G01Y1534122D02*
Y1532599D01*
G01X-33153Y1549881D02*
Y1548336D01*
G01Y1542007D02*
Y1540462D01*
G01Y1545944D02*
Y1544399D01*
G01Y1534133D02*
Y1532588D01*
G01Y1538070D02*
Y1536525D01*
G01X-32319Y1549890D02*
Y1548327D01*
G01Y1542016D02*
Y1540453D01*
G01Y1545953D02*
Y1544390D01*
G01Y1538079D02*
Y1536516D01*
G01Y1534142D02*
Y1532579D01*
G01X-31941Y1549894D02*
Y1548322D01*
G01Y1542020D02*
Y1540448D01*
G01Y1545957D02*
Y1544385D01*
G01Y1538083D02*
Y1536511D01*
G01Y1534146D02*
Y1532574D01*
G01X-35546Y1530526D02*
X-1D01*
G01X-24509Y1530605D02*
X-39607D01*
G01Y1532180D02*
X-24509D01*
G01X-35546Y1532258D02*
X-1D01*
G01X-39607Y1533498D02*
X-24844D01*
G01X-35546Y1534463D02*
X-1D01*
G01X-24509Y1534542D02*
X-39607D01*
G01Y1536117D02*
X-24509D01*
G01X-35546Y1536195D02*
X-1D01*
G01X-39607Y1536648D02*
X-27993D01*
G01X-35546Y1538400D02*
X-1D01*
G01X-24509Y1538479D02*
X-39607D01*
G01X-10631Y1532337D02*
X-35351Y1532613D01*
G01X-10631Y1536274D02*
X-35351Y1536550D01*
G01X-10631Y1540211D02*
X-35351Y1540487D01*
G01X-10631Y1544148D02*
X-35351Y1544424D01*
G01X-38108Y1532878D02*
X-35351Y1532613D01*
G01X-38108Y1536815D02*
X-35351Y1536550D01*
G01X-38108Y1540752D02*
X-35351Y1540487D01*
G01X-38108Y1544689D02*
X-35351Y1544424D01*
G01X-38108Y1548626D02*
X-35351Y1548361D01*
G01Y1534109D02*
X-38108Y1533843D01*
G01X-35351Y1538046D02*
X-38108Y1537780D01*
G01X-35351Y1541983D02*
X-38108Y1541717D01*
G01X-35351Y1545920D02*
X-38108Y1545654D01*
G01X-35351Y1549857D02*
X-38108Y1549591D01*
G01X-35351Y1534109D02*
X-10631Y1534384D01*
G01X-35351Y1538046D02*
X-10631Y1538321D01*
G01X-35351Y1541983D02*
X-10631Y1542258D01*
G01X-35351Y1545920D02*
X-10631Y1546195D01*
G01X-35351Y1549857D02*
X-10631Y1550132D01*
G01X-39607Y1540054D02*
X-24509D01*
G01X-35546Y1540132D02*
X-1D01*
G01X-35546Y1542337D02*
X-1D01*
G01X-24509Y1542416D02*
X-39607D01*
G01Y1543991D02*
X-24509D01*
G01X-35546Y1544069D02*
X-1D01*
G01X-35546Y1546274D02*
X-1D01*
G01X-24509Y1546353D02*
X-39607D01*
G01Y1547928D02*
X-24509D01*
G01X-35546Y1548006D02*
X-1D01*
G01X-27993Y1549994D02*
X-39607D01*
G01X-35546Y1550211D02*
X-1D01*
G01X-24509Y1550290D02*
X-39607D01*
G01X-10631Y1548085D02*
X-35351Y1548361D01*
G01X-38426Y1558164D02*
Y1555802D01*
G01Y1554227D02*
Y1551865D01*
G01X-38108Y1557465D02*
Y1556500D01*
G01Y1553528D02*
Y1552563D01*
G01X-37871Y1557488D02*
Y1556477D01*
G01Y1553551D02*
Y1552540D01*
G01X-35595Y1557707D02*
Y1556258D01*
G01Y1553770D02*
Y1552321D01*
G01X-35546Y1558164D02*
Y1555802D01*
G01Y1554227D02*
Y1551865D01*
G01X-35357Y1557730D02*
Y1556235D01*
G01Y1553793D02*
Y1552298D01*
G01X-34607Y1558085D02*
Y1555880D01*
G01Y1554148D02*
Y1551943D01*
G01X-34136Y1557744D02*
Y1556221D01*
G01Y1553807D02*
Y1552284D01*
G01X-33153Y1557755D02*
Y1556210D01*
G01Y1553818D02*
Y1552273D01*
G01X-32319Y1557764D02*
Y1556201D01*
G01Y1553827D02*
Y1552264D01*
G01X-31941Y1557769D02*
Y1556196D01*
G01Y1553831D02*
Y1552259D01*
G01X-38108Y1552563D02*
X-35351Y1552298D01*
G01X-38108Y1556500D02*
X-35351Y1556235D01*
G01Y1553794D02*
X-38108Y1553528D01*
G01X-35351Y1553794D02*
X-10631Y1554069D01*
G01X-39607Y1551865D02*
X-24509D01*
G01X-35546Y1551943D02*
X-1D01*
G01X-39607Y1553144D02*
X-24844D01*
G01X-35546Y1554148D02*
X-1D01*
G01X-24509Y1554227D02*
X-39607D01*
G01Y1555802D02*
X-24509D01*
G01X-35546Y1555880D02*
X-1D01*
G01X-10631Y1552022D02*
X-35351Y1552298D01*
G01X-10631Y1555959D02*
X-35351Y1556235D01*
G01X-27993Y1486254D02*
Y1505900D01*
G01X-27265Y1491235D02*
Y1488872D01*
G01Y1487298D02*
Y1484935D01*
G01Y1483361D02*
Y1480998D01*
G01Y1479424D02*
Y1477061D01*
G01X-26943Y1490895D02*
Y1489211D01*
G01Y1486958D02*
Y1485274D01*
G01Y1483021D02*
Y1481337D01*
G01Y1479084D02*
Y1477400D01*
G01X-26566Y1490899D02*
Y1489207D01*
G01Y1486962D02*
Y1485270D01*
G01Y1483025D02*
Y1481333D01*
G01Y1479088D02*
Y1477396D01*
G01X-24844Y1486254D02*
Y1505900D01*
G01X-24509Y1491235D02*
Y1488872D01*
G01Y1487298D02*
Y1484935D01*
G01Y1483361D02*
Y1480998D01*
G01Y1479424D02*
Y1477061D01*
G01X-24122Y1490926D02*
Y1489180D01*
G01Y1486989D02*
Y1485243D01*
G01Y1483052D02*
Y1481306D01*
G01Y1479115D02*
Y1477369D01*
G01X-23684Y1490931D02*
Y1489175D01*
G01Y1486994D02*
Y1485238D01*
G01Y1483057D02*
Y1481301D01*
G01Y1479120D02*
Y1477364D01*
G01X-12993Y1488951D02*
Y1488636D01*
G01Y1487534D02*
Y1487219D01*
G01Y1485014D02*
Y1484699D01*
G01Y1481077D02*
Y1480762D01*
G01Y1483597D02*
Y1483282D01*
G01Y1477140D02*
Y1476825D01*
G01Y1479660D02*
Y1479345D01*
G01Y1475723D02*
Y1475408D01*
G01X-12280Y1491059D02*
Y1489048D01*
G01Y1487122D02*
Y1485111D01*
G01Y1483185D02*
Y1481174D01*
G01Y1479248D02*
Y1477237D01*
G01X-11843Y1491063D02*
Y1489043D01*
G01Y1487126D02*
Y1485106D01*
G01Y1483189D02*
Y1481169D01*
G01Y1479252D02*
Y1477232D01*
G01X-1Y1475723D02*
X-12993D01*
G01Y1476825D02*
X-1D01*
G01Y1479660D02*
X-12993D01*
G01Y1480762D02*
X-1D01*
G01Y1483597D02*
X-12993D01*
G01Y1484699D02*
X-1D01*
G01Y1487534D02*
X-12993D01*
G01Y1488636D02*
X-1D01*
G01X-27993Y1509876D02*
Y1529522D01*
G01X-27265Y1510920D02*
Y1508557D01*
G01Y1506983D02*
Y1504620D01*
G01Y1503046D02*
Y1500683D01*
G01Y1499109D02*
Y1496746D01*
G01Y1495172D02*
Y1492809D01*
G01X-26943Y1510580D02*
Y1508896D01*
G01Y1506643D02*
Y1504959D01*
G01Y1502706D02*
Y1501022D01*
G01Y1498769D02*
Y1497085D01*
G01Y1494832D02*
Y1493148D01*
G01X-26566Y1510584D02*
Y1508893D01*
G01Y1506647D02*
Y1504956D01*
G01Y1502710D02*
Y1501019D01*
G01Y1498773D02*
Y1497081D01*
G01Y1494836D02*
Y1493144D01*
G01X-24844Y1509876D02*
Y1529522D01*
G01X-24509Y1510920D02*
Y1508557D01*
G01Y1506983D02*
Y1504620D01*
G01Y1503046D02*
Y1500683D01*
G01Y1499109D02*
Y1496746D01*
G01Y1495172D02*
Y1492809D01*
G01X-24122Y1510611D02*
Y1508865D01*
G01Y1506674D02*
Y1504928D01*
G01Y1502737D02*
Y1500991D01*
G01Y1494863D02*
Y1493117D01*
G01Y1498800D02*
Y1497054D01*
G01X-23684Y1510617D02*
Y1508860D01*
G01Y1506680D02*
Y1504923D01*
G01Y1502743D02*
Y1500986D01*
G01Y1494869D02*
Y1493112D01*
G01Y1498806D02*
Y1497049D01*
G01X-12993Y1508636D02*
Y1508321D01*
G01Y1504699D02*
Y1504384D01*
G01Y1507219D02*
Y1506904D01*
G01Y1500762D02*
Y1500447D01*
G01Y1503282D02*
Y1502967D01*
G01Y1499345D02*
Y1499030D01*
G01Y1496825D02*
Y1496510D01*
G01Y1495408D02*
Y1495093D01*
G01Y1492888D02*
Y1492573D01*
G01Y1491471D02*
Y1491156D01*
G01X-12280Y1510744D02*
Y1508733D01*
G01Y1506807D02*
Y1504796D01*
G01Y1502870D02*
Y1500859D01*
G01Y1498933D02*
Y1496922D01*
G01Y1494996D02*
Y1492985D01*
G01X-11843Y1510748D02*
Y1508728D01*
G01Y1506811D02*
Y1504791D01*
G01Y1502874D02*
Y1500854D01*
G01Y1498937D02*
Y1496917D01*
G01Y1495000D02*
Y1492980D01*
G01X-1Y1491471D02*
X-12993D01*
G01Y1492573D02*
X-1D01*
G01Y1495408D02*
X-12993D01*
G01Y1496510D02*
X-1D01*
G01Y1499345D02*
X-12993D01*
G01Y1500447D02*
X-1D01*
G01Y1503282D02*
X-12993D01*
G01Y1504384D02*
X-1D01*
G01Y1507219D02*
X-12993D01*
G01Y1508321D02*
X-1D01*
G01X-27265Y1530605D02*
Y1528243D01*
G01Y1526668D02*
Y1524306D01*
G01Y1522731D02*
Y1520369D01*
G01Y1518794D02*
Y1516431D01*
G01Y1514857D02*
Y1512494D01*
G01X-26943Y1530265D02*
Y1528581D01*
G01Y1526328D02*
Y1524644D01*
G01Y1522391D02*
Y1520707D01*
G01Y1518454D02*
Y1516770D01*
G01Y1514517D02*
Y1512833D01*
G01X-26566Y1530269D02*
Y1528578D01*
G01Y1526332D02*
Y1524641D01*
G01Y1522395D02*
Y1520704D01*
G01Y1518458D02*
Y1516767D01*
G01Y1514521D02*
Y1512830D01*
G01X-24509Y1530605D02*
Y1528243D01*
G01Y1526668D02*
Y1524306D01*
G01Y1522731D02*
Y1520369D01*
G01Y1518794D02*
Y1516431D01*
G01Y1514857D02*
Y1512494D01*
G01X-24122Y1530296D02*
Y1528550D01*
G01Y1526359D02*
Y1524613D01*
G01Y1518485D02*
Y1516739D01*
G01Y1522422D02*
Y1520676D01*
G01Y1514548D02*
Y1512802D01*
G01X-23684Y1530302D02*
Y1528545D01*
G01Y1526365D02*
Y1524608D01*
G01Y1518491D02*
Y1516734D01*
G01Y1522428D02*
Y1520671D01*
G01Y1514554D02*
Y1512797D01*
G01X-12993Y1528321D02*
Y1528006D01*
G01Y1524384D02*
Y1524069D01*
G01Y1526904D02*
Y1526589D01*
G01Y1522967D02*
Y1522652D01*
G01Y1520447D02*
Y1520132D01*
G01Y1519030D02*
Y1518715D01*
G01Y1516510D02*
Y1516195D01*
G01Y1515093D02*
Y1514778D01*
G01Y1512573D02*
Y1512258D01*
G01Y1511156D02*
Y1510841D01*
G01X-12280Y1530429D02*
Y1528418D01*
G01Y1526492D02*
Y1524481D01*
G01Y1522555D02*
Y1520544D01*
G01Y1518618D02*
Y1516607D01*
G01Y1514681D02*
Y1512670D01*
G01X-11843Y1530433D02*
Y1528413D01*
G01Y1526496D02*
Y1524476D01*
G01Y1522559D02*
Y1520539D01*
G01Y1518622D02*
Y1516602D01*
G01Y1514685D02*
Y1512665D01*
G01X-1Y1511156D02*
X-12993D01*
G01Y1512258D02*
X-1D01*
G01Y1515093D02*
X-12993D01*
G01Y1516195D02*
X-1D01*
G01Y1519030D02*
X-12993D01*
G01Y1520132D02*
X-1D01*
G01Y1522967D02*
X-12993D01*
G01Y1524069D02*
X-1D01*
G01Y1526904D02*
X-12993D01*
G01Y1528006D02*
X-1D01*
G01X-27993Y1533498D02*
Y1553144D01*
G01X-27265Y1550290D02*
Y1547928D01*
G01Y1546353D02*
Y1543991D01*
G01Y1542416D02*
Y1540054D01*
G01Y1538479D02*
Y1536117D01*
G01Y1534542D02*
Y1532180D01*
G01X-26943Y1549950D02*
Y1548267D01*
G01Y1546013D02*
Y1544330D01*
G01Y1542076D02*
Y1540393D01*
G01Y1538139D02*
Y1536456D01*
G01Y1534202D02*
Y1532519D01*
G01X-26566Y1549954D02*
Y1548263D01*
G01Y1542080D02*
Y1540389D01*
G01Y1546017D02*
Y1544326D01*
G01Y1538143D02*
Y1536452D01*
G01Y1534206D02*
Y1532515D01*
G01X-24844Y1533498D02*
Y1553144D01*
G01X-24509Y1550290D02*
Y1547928D01*
G01Y1546353D02*
Y1543991D01*
G01Y1542416D02*
Y1540054D01*
G01Y1538479D02*
Y1536117D01*
G01Y1534542D02*
Y1532180D01*
G01X-24122Y1549981D02*
Y1548235D01*
G01Y1542107D02*
Y1540361D01*
G01Y1546044D02*
Y1544298D01*
G01Y1538170D02*
Y1536424D01*
G01Y1534233D02*
Y1532487D01*
G01X-23684Y1549987D02*
Y1548230D01*
G01Y1542113D02*
Y1540356D01*
G01Y1546050D02*
Y1544293D01*
G01Y1538176D02*
Y1536419D01*
G01Y1534239D02*
Y1532482D01*
G01X-12993Y1548006D02*
Y1547691D01*
G01Y1550526D02*
Y1550211D01*
G01Y1546589D02*
Y1546274D01*
G01Y1544069D02*
Y1543754D01*
G01Y1542652D02*
Y1542337D01*
G01Y1540132D02*
Y1539817D01*
G01Y1538715D02*
Y1538400D01*
G01Y1536195D02*
Y1535880D01*
G01Y1532258D02*
Y1531943D01*
G01Y1534778D02*
Y1534463D01*
G01Y1530841D02*
Y1530526D01*
G01X-12280Y1546177D02*
Y1544166D01*
G01Y1550114D02*
Y1548103D01*
G01Y1542240D02*
Y1540229D01*
G01Y1538303D02*
Y1536292D01*
G01Y1534366D02*
Y1532355D01*
G01X-11843Y1550119D02*
Y1548098D01*
G01Y1546181D02*
Y1544161D01*
G01Y1542244D02*
Y1540224D01*
G01Y1538307D02*
Y1536287D01*
G01Y1534370D02*
Y1532350D01*
G01X-1Y1530841D02*
X-12993D01*
G01Y1531943D02*
X-1D01*
G01Y1534778D02*
X-12993D01*
G01Y1535880D02*
X-1D01*
G01Y1538715D02*
X-12993D01*
G01Y1539817D02*
X-1D01*
G01Y1542652D02*
X-12993D01*
G01Y1543754D02*
X-1D01*
G01Y1546589D02*
X-12993D01*
G01Y1547691D02*
X-1D01*
G01X-27265Y1558164D02*
Y1555802D01*
G01Y1554227D02*
Y1551865D01*
G01X-26943Y1557824D02*
Y1556141D01*
G01Y1553887D02*
Y1552204D01*
G01X-26566Y1557828D02*
Y1556137D01*
G01Y1553891D02*
Y1552200D01*
G01X-24509Y1558164D02*
Y1555802D01*
G01Y1554227D02*
Y1551865D01*
G01X-24122Y1557856D02*
Y1556109D01*
G01Y1553919D02*
Y1552172D01*
G01X-23684Y1557861D02*
Y1556104D01*
G01Y1553924D02*
Y1552167D01*
G01X-12993Y1555880D02*
Y1555565D01*
G01Y1551943D02*
Y1551628D01*
G01Y1554463D02*
Y1554148D01*
G01X-12280Y1557988D02*
Y1555977D01*
G01Y1554051D02*
Y1552040D01*
G01X-11843Y1557993D02*
Y1555972D01*
G01Y1554056D02*
Y1552035D01*
G01X-1Y1550526D02*
X-12993D01*
G01Y1551628D02*
X-1D01*
G01Y1554463D02*
X-12993D01*
G01Y1555565D02*
X-1D01*
G01X-3378Y1488597D02*
X-3151Y1488991D01*
G01X-1970Y1487573D02*
X-2197Y1487180D01*
G01X-3378Y1484660D02*
X-3151Y1485054D01*
G01X-1970Y1483636D02*
X-2197Y1483243D01*
G01X-3378Y1480723D02*
X-3151Y1481117D01*
G01X-1970Y1479699D02*
X-2197Y1479306D01*
G01X-3378Y1476786D02*
X-3151Y1477180D01*
G01X-1970Y1475762D02*
X-2197Y1475369D01*
G01X-9844Y1487494D02*
X-10631Y1487140D01*
G01X-9844Y1483557D02*
X-10631Y1483203D01*
G01X-9844Y1479620D02*
X-10631Y1479266D01*
G01X-9844Y1475683D02*
X-10631Y1475329D01*
G01X-10531Y1491122D02*
Y1488985D01*
G01Y1487185D02*
Y1485048D01*
G01Y1483248D02*
Y1481111D01*
G01Y1479311D02*
Y1477174D01*
G01X-6694Y1489266D02*
Y1488676D01*
G01Y1487494D02*
Y1486904D01*
G01Y1485329D02*
Y1484739D01*
G01Y1483557D02*
Y1482967D01*
G01Y1481392D02*
Y1480802D01*
G01Y1479620D02*
Y1479030D01*
G01Y1477455D02*
Y1476865D01*
G01Y1475683D02*
Y1475093D01*
G01X-4725Y1489266D02*
Y1488361D01*
G01Y1487809D02*
Y1486904D01*
G01Y1485329D02*
Y1484424D01*
G01Y1483872D02*
Y1482967D01*
G01Y1481392D02*
Y1480487D01*
G01Y1479935D02*
Y1479030D01*
G01Y1477455D02*
Y1476550D01*
G01Y1475998D02*
Y1475093D01*
G01X-3757Y1491156D02*
Y1488951D01*
G01Y1487219D02*
Y1485014D01*
G01Y1483282D02*
Y1481077D01*
G01Y1479345D02*
Y1477140D01*
G01X-2521Y1491156D02*
Y1488951D01*
G01Y1487219D02*
Y1485014D01*
G01Y1483282D02*
Y1481077D01*
G01Y1479345D02*
Y1477140D01*
G01X-2251Y1491471D02*
Y1488636D01*
G01Y1487534D02*
Y1484699D01*
G01Y1483597D02*
Y1480762D01*
G01Y1479660D02*
Y1476825D01*
G01X-985Y1490723D02*
Y1489384D01*
G01Y1486786D02*
Y1485447D01*
G01Y1482849D02*
Y1481510D01*
G01Y1478912D02*
Y1477573D01*
G01X8523Y1490723D02*
Y1489384D01*
G01Y1486786D02*
Y1485447D01*
G01Y1482849D02*
Y1481510D01*
G01Y1478912D02*
Y1477573D01*
G01X-3151Y1475369D02*
X-3378Y1475762D01*
G01X-2197Y1477180D02*
X-1970Y1476786D01*
G01X-3151Y1479306D02*
X-3378Y1479699D01*
G01X-2197Y1481117D02*
X-1970Y1480723D01*
G01X-3151Y1483243D02*
X-3378Y1483636D01*
G01X-2197Y1485054D02*
X-1970Y1484660D01*
G01X-3151Y1487180D02*
X-3378Y1487573D01*
G01X-2197Y1488991D02*
X-1970Y1488597D01*
G01X-10631Y1477219D02*
X-9844Y1476865D01*
G01X-10631Y1481156D02*
X-9844Y1480802D01*
G01X-10631Y1485093D02*
X-9844Y1484739D01*
G01X-10631Y1489030D02*
X-9844Y1488676D01*
G01X-4259Y1477022D02*
X-3378Y1476786D01*
G01X-4259Y1480959D02*
X-3378Y1480723D01*
G01X-4259Y1484896D02*
X-3378Y1484660D01*
G01X-4259Y1488833D02*
X-3378Y1488597D01*
G01X-4725Y1476550D02*
X-6694Y1476865D01*
G01X-4725Y1480487D02*
X-6694Y1480802D01*
G01X-4725Y1484424D02*
X-6694Y1484739D01*
G01X-4725Y1488361D02*
X-6694Y1488676D01*
G01X-985Y1474975D02*
X-1D01*
G01D02*
X8523D01*
G01D02*
X12600D01*
G01X-4725Y1475093D02*
X-6694D01*
G01X-3151Y1475369D02*
X-2197D01*
G01X-4725Y1475526D02*
X-4259D01*
G01X-9844Y1475683D02*
X-6694D01*
G01X-1970Y1475762D02*
X-1D01*
G01Y1476786D02*
X-1970D01*
G01X-6694Y1476865D02*
X-9844D01*
G01X-4259Y1477022D02*
X-4725D01*
G01X-2197Y1477180D02*
X-3151D01*
G01X-4725Y1477455D02*
X-6694D01*
G01X15077Y1477573D02*
X8523D01*
G01D02*
X-1D01*
G01D02*
X-985D01*
G01Y1478912D02*
X-1D01*
G01D02*
X8523D01*
G01D02*
X12600D01*
G01X-4725Y1479030D02*
X-6694D01*
G01X-3151Y1479306D02*
X-2197D01*
G01X-4725Y1479463D02*
X-4259D01*
G01X-9844Y1479620D02*
X-6694D01*
G01X-1970Y1479699D02*
X-1D01*
G01Y1480723D02*
X-1970D01*
G01X-6694Y1480802D02*
X-9844D01*
G01X-4259Y1480959D02*
X-4725D01*
G01X-2197Y1481117D02*
X-3151D01*
G01X-4725Y1481392D02*
X-6694D01*
G01X15077Y1481510D02*
X8523D01*
G01D02*
X-1D01*
G01D02*
X-985D01*
G01Y1482849D02*
X-1D01*
G01D02*
X8523D01*
G01D02*
X12600D01*
G01X-4725Y1482967D02*
X-6694D01*
G01X-3151Y1483243D02*
X-2197D01*
G01X-4725Y1483400D02*
X-4259D01*
G01X-9844Y1483557D02*
X-6694D01*
G01X-1970Y1483636D02*
X-1D01*
G01Y1484660D02*
X-1970D01*
G01X-6694Y1484739D02*
X-9844D01*
G01X-4259Y1484896D02*
X-4725D01*
G01X-2197Y1485054D02*
X-3151D01*
G01X-4725Y1485329D02*
X-6694D01*
G01X15077Y1485447D02*
X8523D01*
G01D02*
X-1D01*
G01D02*
X-985D01*
G01Y1486786D02*
X-1D01*
G01D02*
X8523D01*
G01D02*
X12600D01*
G01X-4725Y1486904D02*
X-6694D01*
G01X-3151Y1487180D02*
X-2197D01*
G01X-4725Y1487337D02*
X-4259D01*
G01X-9844Y1487494D02*
X-6694D01*
G01X-1970Y1487573D02*
X-1D01*
G01Y1488597D02*
X-1970D01*
G01X-6694Y1488676D02*
X-9844D01*
G01X-4259Y1488833D02*
X-4725D01*
G01X-2197Y1488991D02*
X-3151D01*
G01X-4725Y1489266D02*
X-6694D01*
G01X15077Y1489384D02*
X8523D01*
G01D02*
X-1D01*
G01D02*
X-985D01*
G01X-3378Y1475762D02*
X-4259Y1475526D01*
G01X-3378Y1479699D02*
X-4259Y1479463D01*
G01X-3378Y1483636D02*
X-4259Y1483400D01*
G01X-3378Y1487573D02*
X-4259Y1487337D01*
G01X-6694Y1475683D02*
X-4725Y1475998D01*
G01X-6694Y1479620D02*
X-4725Y1479935D01*
G01X-6694Y1483557D02*
X-4725Y1483872D01*
G01X-6694Y1487494D02*
X-4725Y1487809D01*
G01X-3378Y1508282D02*
X-3151Y1508676D01*
G01X-1970Y1507258D02*
X-2197Y1506865D01*
G01X-3378Y1504345D02*
X-3151Y1504739D01*
G01X-1970Y1503321D02*
X-2197Y1502928D01*
G01X-3378Y1500408D02*
X-3151Y1500802D01*
G01X-1970Y1499384D02*
X-2197Y1498991D01*
G01X-3378Y1496471D02*
X-3151Y1496865D01*
G01X-1970Y1495447D02*
X-2197Y1495054D01*
G01X-3378Y1492534D02*
X-3151Y1492928D01*
G01X-1970Y1491510D02*
X-2197Y1491117D01*
G01X-9844Y1507180D02*
X-10631Y1506825D01*
G01X-9844Y1503243D02*
X-10631Y1502888D01*
G01X-9844Y1499306D02*
X-10631Y1498951D01*
G01X-9844Y1495369D02*
X-10631Y1495014D01*
G01X-9844Y1491431D02*
X-10631Y1491077D01*
G01X-10531Y1510807D02*
Y1508670D01*
G01Y1506870D02*
Y1504733D01*
G01Y1502933D02*
Y1500796D01*
G01Y1495059D02*
Y1492922D01*
G01Y1498996D02*
Y1496859D01*
G01X-6694Y1508951D02*
Y1508361D01*
G01Y1507180D02*
Y1506589D01*
G01Y1505014D02*
Y1504424D01*
G01Y1503243D02*
Y1502652D01*
G01Y1501077D02*
Y1500487D01*
G01Y1499306D02*
Y1498715D01*
G01Y1497140D02*
Y1496550D01*
G01Y1495369D02*
Y1494778D01*
G01Y1493203D02*
Y1492613D01*
G01Y1491431D02*
Y1490841D01*
G01X-4725Y1508951D02*
Y1508046D01*
G01Y1507494D02*
Y1506589D01*
G01Y1505014D02*
Y1504109D01*
G01Y1503557D02*
Y1502652D01*
G01Y1501077D02*
Y1500172D01*
G01Y1499620D02*
Y1498715D01*
G01Y1497140D02*
Y1496235D01*
G01Y1495683D02*
Y1494778D01*
G01Y1493203D02*
Y1492298D01*
G01Y1491746D02*
Y1490841D01*
G01X-3757Y1510841D02*
Y1508636D01*
G01Y1506904D02*
Y1504699D01*
G01Y1502967D02*
Y1500762D01*
G01Y1495093D02*
Y1492888D01*
G01Y1499030D02*
Y1496825D01*
G01X-2521Y1510841D02*
Y1508636D01*
G01Y1506904D02*
Y1504699D01*
G01Y1502967D02*
Y1500762D01*
G01Y1495093D02*
Y1492888D01*
G01Y1499030D02*
Y1496825D01*
G01X-2251Y1511156D02*
Y1508321D01*
G01Y1507219D02*
Y1504384D01*
G01Y1503282D02*
Y1500447D01*
G01Y1499345D02*
Y1496510D01*
G01Y1495408D02*
Y1492573D01*
G01X-985Y1510408D02*
Y1509069D01*
G01Y1506471D02*
Y1505132D01*
G01Y1502534D02*
Y1501195D01*
G01Y1494660D02*
Y1493321D01*
G01Y1498597D02*
Y1497258D01*
G01X8523Y1510408D02*
Y1509069D01*
G01Y1506471D02*
Y1505132D01*
G01Y1502534D02*
Y1501195D01*
G01Y1498597D02*
Y1497258D01*
G01Y1494660D02*
Y1493321D01*
G01X-3151Y1491117D02*
X-3378Y1491510D01*
G01X-2197Y1492928D02*
X-1970Y1492534D01*
G01X-3151Y1495054D02*
X-3378Y1495447D01*
G01X-2197Y1496865D02*
X-1970Y1496471D01*
G01X-3151Y1498991D02*
X-3378Y1499384D01*
G01X-2197Y1500802D02*
X-1970Y1500408D01*
G01X-3151Y1502928D02*
X-3378Y1503321D01*
G01X-2197Y1504739D02*
X-1970Y1504345D01*
G01X-3151Y1506865D02*
X-3378Y1507258D01*
G01X-2197Y1508676D02*
X-1970Y1508282D01*
G01X-10631Y1492967D02*
X-9844Y1492613D01*
G01X-10631Y1496904D02*
X-9844Y1496550D01*
G01X-10631Y1500841D02*
X-9844Y1500487D01*
G01X-10631Y1504778D02*
X-9844Y1504424D01*
G01X-10631Y1508715D02*
X-9844Y1508361D01*
G01X-4259Y1492770D02*
X-3378Y1492534D01*
G01X-4259Y1496707D02*
X-3378Y1496471D01*
G01X-4259Y1500644D02*
X-3378Y1500408D01*
G01X-4259Y1504581D02*
X-3378Y1504345D01*
G01X-4259Y1508518D02*
X-3378Y1508282D01*
G01X-4725Y1492298D02*
X-6694Y1492613D01*
G01X-4725Y1496235D02*
X-6694Y1496550D01*
G01X-4725Y1500172D02*
X-6694Y1500487D01*
G01X-4725Y1504109D02*
X-6694Y1504424D01*
G01X-4725Y1508046D02*
X-6694Y1508361D01*
G01X-985Y1490723D02*
X-1D01*
G01D02*
X8523D01*
G01D02*
X12600D01*
G01X-4725Y1490841D02*
X-6694D01*
G01X-3151Y1491117D02*
X-2197D01*
G01X-4725Y1491274D02*
X-4259D01*
G01X-9844Y1491431D02*
X-6694D01*
G01X-1970Y1491510D02*
X-1D01*
G01Y1492534D02*
X-1970D01*
G01X-6694Y1492613D02*
X-9844D01*
G01X-4259Y1492770D02*
X-4725D01*
G01X-2197Y1492928D02*
X-3151D01*
G01X-4725Y1493203D02*
X-6694D01*
G01X15077Y1493321D02*
X8523D01*
G01D02*
X-1D01*
G01D02*
X-985D01*
G01Y1494660D02*
X-1D01*
G01D02*
X8523D01*
G01D02*
X12600D01*
G01X-4725Y1494778D02*
X-6694D01*
G01X-3151Y1495054D02*
X-2197D01*
G01X-4725Y1495211D02*
X-4259D01*
G01X-9844Y1495369D02*
X-6694D01*
G01X-1970Y1495447D02*
X-1D01*
G01Y1496471D02*
X-1970D01*
G01X-6694Y1496550D02*
X-9844D01*
G01X-4259Y1496707D02*
X-4725D01*
G01X-2197Y1496865D02*
X-3151D01*
G01X-4725Y1497140D02*
X-6694D01*
G01X15077Y1497258D02*
X8523D01*
G01D02*
X-1D01*
G01D02*
X-985D01*
G01Y1498597D02*
X-1D01*
G01D02*
X8523D01*
G01D02*
X12600D01*
G01X-4725Y1498715D02*
X-6694D01*
G01X-3151Y1498991D02*
X-2197D01*
G01X-4725Y1499148D02*
X-4259D01*
G01X-9844Y1499306D02*
X-6694D01*
G01X-1970Y1499384D02*
X-1D01*
G01Y1500408D02*
X-1970D01*
G01X-6694Y1500487D02*
X-9844D01*
G01X-4259Y1500644D02*
X-4725D01*
G01X-2197Y1500802D02*
X-3151D01*
G01X-4725Y1501077D02*
X-6694D01*
G01X15077Y1501195D02*
X8523D01*
G01D02*
X-1D01*
G01D02*
X-985D01*
G01Y1502534D02*
X-1D01*
G01D02*
X8523D01*
G01D02*
X12600D01*
G01X-4725Y1502652D02*
X-6694D01*
G01X-3151Y1502928D02*
X-2197D01*
G01X-4725Y1503085D02*
X-4259D01*
G01X-9844Y1503243D02*
X-6694D01*
G01X-1970Y1503321D02*
X-1D01*
G01Y1504345D02*
X-1970D01*
G01X-6694Y1504424D02*
X-9844D01*
G01X-4259Y1504581D02*
X-4725D01*
G01X-2197Y1504739D02*
X-3151D01*
G01X-4725Y1505014D02*
X-6694D01*
G01X15077Y1505132D02*
X8523D01*
G01D02*
X-1D01*
G01D02*
X-985D01*
G01Y1506471D02*
X-1D01*
G01D02*
X8523D01*
G01D02*
X12600D01*
G01X-4725Y1506589D02*
X-6694D01*
G01X-3151Y1506865D02*
X-2197D01*
G01X-4725Y1507022D02*
X-4259D01*
G01X-9844Y1507180D02*
X-6694D01*
G01X-1970Y1507258D02*
X-1D01*
G01Y1508282D02*
X-1970D01*
G01X-6694Y1508361D02*
X-9844D01*
G01X-4259Y1508518D02*
X-4725D01*
G01X-2197Y1508676D02*
X-3151D01*
G01X-4725Y1508951D02*
X-6694D01*
G01X15077Y1509069D02*
X8523D01*
G01D02*
X-1D01*
G01D02*
X-985D01*
G01X-3378Y1491510D02*
X-4259Y1491274D01*
G01X-3378Y1495447D02*
X-4259Y1495211D01*
G01X-6694Y1491431D02*
X-4725Y1491746D01*
G01X-6694Y1495369D02*
X-4725Y1495683D01*
G01X-6694Y1499306D02*
X-4725Y1499620D01*
G01X-6694Y1503243D02*
X-4725Y1503557D01*
G01X-6694Y1507180D02*
X-4725Y1507494D01*
G01X-3378Y1499384D02*
X-4259Y1499148D01*
G01X-3378Y1503321D02*
X-4259Y1503085D01*
G01X-3378Y1507258D02*
X-4259Y1507022D01*
G01X-3378Y1527967D02*
X-3151Y1528361D01*
G01X-1970Y1526943D02*
X-2197Y1526550D01*
G01X-3378Y1524030D02*
X-3151Y1524424D01*
G01X-1970Y1523006D02*
X-2197Y1522613D01*
G01X-3378Y1520093D02*
X-3151Y1520487D01*
G01X-1970Y1519069D02*
X-2197Y1518676D01*
G01X-3378Y1516156D02*
X-3151Y1516550D01*
G01X-1970Y1515132D02*
X-2197Y1514739D01*
G01X-3378Y1512219D02*
X-3151Y1512613D01*
G01X-1970Y1511195D02*
X-2197Y1510802D01*
G01X-9844Y1526865D02*
X-10631Y1526510D01*
G01X-9844Y1522928D02*
X-10631Y1522573D01*
G01X-9844Y1518991D02*
X-10631Y1518636D01*
G01X-9844Y1515054D02*
X-10631Y1514699D01*
G01X-9844Y1511117D02*
X-10631Y1510762D01*
G01X-10531Y1530492D02*
Y1528355D01*
G01Y1526555D02*
Y1524418D01*
G01Y1518681D02*
Y1516544D01*
G01Y1522618D02*
Y1520481D01*
G01Y1514744D02*
Y1512607D01*
G01X-6694Y1528636D02*
Y1528046D01*
G01Y1526865D02*
Y1526274D01*
G01Y1524699D02*
Y1524109D01*
G01Y1522928D02*
Y1522337D01*
G01Y1520762D02*
Y1520172D01*
G01Y1518991D02*
Y1518400D01*
G01Y1516825D02*
Y1516235D01*
G01Y1515054D02*
Y1514463D01*
G01Y1512888D02*
Y1512298D01*
G01Y1511117D02*
Y1510526D01*
G01X-4725Y1528636D02*
Y1527731D01*
G01Y1527180D02*
Y1526274D01*
G01Y1524699D02*
Y1523794D01*
G01Y1523243D02*
Y1522337D01*
G01Y1520762D02*
Y1519857D01*
G01Y1519306D02*
Y1518400D01*
G01Y1516825D02*
Y1515920D01*
G01Y1515369D02*
Y1514463D01*
G01Y1512888D02*
Y1511983D01*
G01Y1511431D02*
Y1510526D01*
G01X-3757Y1530526D02*
Y1528321D01*
G01Y1526589D02*
Y1524384D01*
G01Y1518715D02*
Y1516510D01*
G01Y1522652D02*
Y1520447D01*
G01Y1514778D02*
Y1512573D01*
G01X-2521Y1530526D02*
Y1528321D01*
G01Y1526589D02*
Y1524384D01*
G01Y1518715D02*
Y1516510D01*
G01Y1522652D02*
Y1520447D01*
G01Y1514778D02*
Y1512573D01*
G01X-2251Y1530841D02*
Y1528006D01*
G01Y1526904D02*
Y1524069D01*
G01Y1522967D02*
Y1520132D01*
G01Y1519030D02*
Y1516195D01*
G01Y1515093D02*
Y1512258D01*
G01X-985Y1530093D02*
Y1528754D01*
G01Y1526156D02*
Y1524817D01*
G01Y1518282D02*
Y1516943D01*
G01Y1522219D02*
Y1520880D01*
G01Y1514345D02*
Y1513006D01*
G01X8523Y1530093D02*
Y1528754D01*
G01Y1526156D02*
Y1524817D01*
G01Y1522219D02*
Y1520880D01*
G01Y1518282D02*
Y1516943D01*
G01Y1514345D02*
Y1513006D01*
G01X-3151Y1510802D02*
X-3378Y1511195D01*
G01X-2197Y1512613D02*
X-1970Y1512219D01*
G01X-3151Y1514739D02*
X-3378Y1515132D01*
G01X-2197Y1516550D02*
X-1970Y1516156D01*
G01X-3151Y1518676D02*
X-3378Y1519069D01*
G01X-2197Y1520487D02*
X-1970Y1520093D01*
G01X-3151Y1522613D02*
X-3378Y1523006D01*
G01X-2197Y1524424D02*
X-1970Y1524030D01*
G01X-3151Y1526550D02*
X-3378Y1526943D01*
G01X-2197Y1528361D02*
X-1970Y1527967D01*
G01X-10631Y1512652D02*
X-9844Y1512298D01*
G01X-10631Y1516589D02*
X-9844Y1516235D01*
G01X-10631Y1520526D02*
X-9844Y1520172D01*
G01X-10631Y1524463D02*
X-9844Y1524109D01*
G01X-10631Y1528400D02*
X-9844Y1528046D01*
G01X-4259Y1512455D02*
X-3378Y1512219D01*
G01X-4259Y1516392D02*
X-3378Y1516156D01*
G01X-4259Y1520329D02*
X-3378Y1520093D01*
G01X-4259Y1524266D02*
X-3378Y1524030D01*
G01X-4259Y1528203D02*
X-3378Y1527967D01*
G01X-4725Y1511983D02*
X-6694Y1512298D01*
G01X-4725Y1515920D02*
X-6694Y1516235D01*
G01X-4725Y1519857D02*
X-6694Y1520172D01*
G01X-4725Y1523794D02*
X-6694Y1524109D01*
G01X-4725Y1527731D02*
X-6694Y1528046D01*
G01X-985Y1510408D02*
X-1D01*
G01D02*
X8523D01*
G01D02*
X12600D01*
G01X-4725Y1510526D02*
X-6694D01*
G01X-3151Y1510802D02*
X-2197D01*
G01X-4725Y1510959D02*
X-4259D01*
G01X-9844Y1511117D02*
X-6694D01*
G01X-1970Y1511195D02*
X-1D01*
G01Y1512219D02*
X-1970D01*
G01X-6694Y1512298D02*
X-9844D01*
G01X-4259Y1512455D02*
X-4725D01*
G01X-2197Y1512613D02*
X-3151D01*
G01X-4725Y1512888D02*
X-6694D01*
G01X15077Y1513006D02*
X8523D01*
G01D02*
X-1D01*
G01D02*
X-985D01*
G01Y1514345D02*
X-1D01*
G01D02*
X8523D01*
G01D02*
X12600D01*
G01X-4725Y1514463D02*
X-6694D01*
G01X-3151Y1514739D02*
X-2197D01*
G01X-4725Y1514896D02*
X-4259D01*
G01X-9844Y1515054D02*
X-6694D01*
G01X-1970Y1515132D02*
X-1D01*
G01Y1516156D02*
X-1970D01*
G01X-6694Y1516235D02*
X-9844D01*
G01X-4259Y1516392D02*
X-4725D01*
G01X-2197Y1516550D02*
X-3151D01*
G01X-4725Y1516825D02*
X-6694D01*
G01X15077Y1516943D02*
X8523D01*
G01D02*
X-1D01*
G01D02*
X-985D01*
G01Y1518282D02*
X-1D01*
G01D02*
X8523D01*
G01D02*
X12600D01*
G01X-4725Y1518400D02*
X-6694D01*
G01X-3151Y1518676D02*
X-2197D01*
G01X-4725Y1518833D02*
X-4259D01*
G01X-9844Y1518991D02*
X-6694D01*
G01X-1970Y1519069D02*
X-1D01*
G01Y1520093D02*
X-1970D01*
G01X-6694Y1520172D02*
X-9844D01*
G01X-4259Y1520329D02*
X-4725D01*
G01X-2197Y1520487D02*
X-3151D01*
G01X-4725Y1520762D02*
X-6694D01*
G01X15077Y1520880D02*
X8523D01*
G01D02*
X-1D01*
G01D02*
X-985D01*
G01Y1522219D02*
X-1D01*
G01D02*
X8523D01*
G01D02*
X12600D01*
G01X-4725Y1522337D02*
X-6694D01*
G01X-3151Y1522613D02*
X-2197D01*
G01X-4725Y1522770D02*
X-4259D01*
G01X-9844Y1522928D02*
X-6694D01*
G01X-1970Y1523006D02*
X-1D01*
G01Y1524030D02*
X-1970D01*
G01X-6694Y1524109D02*
X-9844D01*
G01X-4259Y1524266D02*
X-4725D01*
G01X-2197Y1524424D02*
X-3151D01*
G01X-4725Y1524699D02*
X-6694D01*
G01X15077Y1524817D02*
X8523D01*
G01D02*
X-1D01*
G01D02*
X-985D01*
G01Y1526156D02*
X-1D01*
G01D02*
X8523D01*
G01D02*
X12600D01*
G01X-4725Y1526274D02*
X-6694D01*
G01X-3151Y1526550D02*
X-2197D01*
G01X-4725Y1526707D02*
X-4259D01*
G01X-9844Y1526865D02*
X-6694D01*
G01X-1970Y1526943D02*
X-1D01*
G01Y1527967D02*
X-1970D01*
G01X-6694Y1528046D02*
X-9844D01*
G01X-4259Y1528203D02*
X-4725D01*
G01X-2197Y1528361D02*
X-3151D01*
G01X-4725Y1528636D02*
X-6694D01*
G01X15077Y1528754D02*
X8523D01*
G01D02*
X-1D01*
G01D02*
X-985D01*
G01Y1530093D02*
X-1D01*
G01D02*
X8523D01*
G01D02*
X12600D01*
G01X-6694Y1511117D02*
X-4725Y1511431D01*
G01X-6694Y1515054D02*
X-4725Y1515369D01*
G01X-6694Y1518991D02*
X-4725Y1519306D01*
G01X-6694Y1522928D02*
X-4725Y1523243D01*
G01X-6694Y1526865D02*
X-4725Y1527180D01*
G01X-3378Y1511195D02*
X-4259Y1510959D01*
G01X-3378Y1515132D02*
X-4259Y1514896D01*
G01X-3378Y1519069D02*
X-4259Y1518833D01*
G01X-3378Y1523006D02*
X-4259Y1522770D01*
G01X-3378Y1526943D02*
X-4259Y1526707D01*
G01X-1970Y1550565D02*
X-2197Y1550172D01*
G01X-3378Y1547652D02*
X-3151Y1548046D01*
G01X-1970Y1546628D02*
X-2197Y1546235D01*
G01X-3378Y1543715D02*
X-3151Y1544109D01*
G01X-1970Y1542691D02*
X-2197Y1542298D01*
G01X-3378Y1539778D02*
X-3151Y1540172D01*
G01X-1970Y1538754D02*
X-2197Y1538361D01*
G01X-3378Y1535841D02*
X-3151Y1536235D01*
G01X-1970Y1534817D02*
X-2197Y1534424D01*
G01X-3378Y1531904D02*
X-3151Y1532298D01*
G01X-1970Y1530880D02*
X-2197Y1530487D01*
G01X-9844Y1550487D02*
X-10631Y1550132D01*
G01X-9844Y1546550D02*
X-10631Y1546195D01*
G01X-9844Y1542613D02*
X-10631Y1542258D01*
G01X-9844Y1538676D02*
X-10631Y1538321D01*
G01X-9844Y1534739D02*
X-10631Y1534384D01*
G01X-9844Y1530802D02*
X-10631Y1530447D01*
G01X-10531Y1546240D02*
Y1544103D01*
G01Y1550177D02*
Y1548040D01*
G01Y1542303D02*
Y1540166D01*
G01Y1538366D02*
Y1536229D01*
G01Y1534429D02*
Y1532292D01*
G01X-6694Y1550487D02*
Y1549896D01*
G01Y1548321D02*
Y1547731D01*
G01Y1546550D02*
Y1545959D01*
G01Y1544384D02*
Y1543794D01*
G01Y1542613D02*
Y1542022D01*
G01Y1540447D02*
Y1539857D01*
G01Y1538676D02*
Y1538085D01*
G01Y1536510D02*
Y1535920D01*
G01Y1534739D02*
Y1534148D01*
G01Y1532573D02*
Y1531983D01*
G01Y1530802D02*
Y1530211D01*
G01X-4725Y1546865D02*
Y1545959D01*
G01Y1550802D02*
Y1549896D01*
G01Y1548321D02*
Y1547416D01*
G01Y1542928D02*
Y1542022D01*
G01Y1544384D02*
Y1543479D01*
G01Y1538991D02*
Y1538085D01*
G01Y1540447D02*
Y1539542D01*
G01Y1535054D02*
Y1534148D01*
G01Y1532573D02*
Y1531668D01*
G01Y1536510D02*
Y1535605D01*
G01Y1531117D02*
Y1530211D01*
G01X-3757Y1546274D02*
Y1544069D01*
G01Y1550211D02*
Y1548006D01*
G01Y1542337D02*
Y1540132D01*
G01Y1538400D02*
Y1536195D01*
G01Y1534463D02*
Y1532258D01*
G01X-2521Y1546274D02*
Y1544069D01*
G01Y1550211D02*
Y1548006D01*
G01Y1542337D02*
Y1540132D01*
G01Y1538400D02*
Y1536195D01*
G01Y1534463D02*
Y1532258D01*
G01X-2251Y1550526D02*
Y1547691D01*
G01Y1546589D02*
Y1543754D01*
G01Y1542652D02*
Y1539817D01*
G01Y1538715D02*
Y1535880D01*
G01Y1534778D02*
Y1531943D01*
G01X-985Y1549778D02*
Y1548439D01*
G01Y1541904D02*
Y1540565D01*
G01Y1545841D02*
Y1544502D01*
G01Y1537967D02*
Y1536628D01*
G01Y1534030D02*
Y1532691D01*
G01X8523Y1549778D02*
Y1548439D01*
G01Y1545841D02*
Y1544502D01*
G01Y1541904D02*
Y1540565D01*
G01Y1537967D02*
Y1536628D01*
G01Y1534030D02*
Y1532691D01*
G01X-3151Y1530487D02*
X-3378Y1530880D01*
G01X-2197Y1532298D02*
X-1970Y1531904D01*
G01X-3151Y1534424D02*
X-3378Y1534817D01*
G01X-2197Y1536235D02*
X-1970Y1535841D01*
G01X-3151Y1538361D02*
X-3378Y1538754D01*
G01X-2197Y1540172D02*
X-1970Y1539778D01*
G01X-3151Y1542298D02*
X-3378Y1542691D01*
G01X-2197Y1544109D02*
X-1970Y1543715D01*
G01X-3151Y1546235D02*
X-3378Y1546628D01*
G01X-2197Y1548046D02*
X-1970Y1547652D01*
G01X-3151Y1550172D02*
X-3378Y1550565D01*
G01X-10631Y1532337D02*
X-9844Y1531983D01*
G01X-10631Y1536274D02*
X-9844Y1535920D01*
G01X-10631Y1540211D02*
X-9844Y1539857D01*
G01X-10631Y1544148D02*
X-9844Y1543794D01*
G01X-10631Y1548085D02*
X-9844Y1547731D01*
G01X-4259Y1532140D02*
X-3378Y1531904D01*
G01X-4259Y1536077D02*
X-3378Y1535841D01*
G01X-4259Y1540014D02*
X-3378Y1539778D01*
G01X-4725Y1531668D02*
X-6694Y1531983D01*
G01X-4725Y1535605D02*
X-6694Y1535920D01*
G01X-4725Y1539542D02*
X-6694Y1539857D01*
G01X-4725Y1543479D02*
X-6694Y1543794D01*
G01X-4725Y1547416D02*
X-6694Y1547731D01*
G01X-4259Y1543951D02*
X-3378Y1543715D01*
G01X-4259Y1547888D02*
X-3378Y1547652D01*
G01X-4725Y1530211D02*
X-6694D01*
G01X-3151Y1530487D02*
X-2197D01*
G01X-4725Y1530644D02*
X-4259D01*
G01X-9844Y1530802D02*
X-6694D01*
G01X-1970Y1530880D02*
X-1D01*
G01Y1531904D02*
X-1970D01*
G01X-6694Y1531983D02*
X-9844D01*
G01X-4259Y1532140D02*
X-4725D01*
G01X-2197Y1532298D02*
X-3151D01*
G01X-4725Y1532573D02*
X-6694D01*
G01X15077Y1532691D02*
X8523D01*
G01D02*
X-1D01*
G01D02*
X-985D01*
G01Y1534030D02*
X-1D01*
G01D02*
X8523D01*
G01D02*
X12600D01*
G01X-4725Y1534148D02*
X-6694D01*
G01X-3151Y1534424D02*
X-2197D01*
G01X-4725Y1534581D02*
X-4259D01*
G01X-9844Y1534739D02*
X-6694D01*
G01X-1970Y1534817D02*
X-1D01*
G01Y1535841D02*
X-1970D01*
G01X-6694Y1535920D02*
X-9844D01*
G01X-4259Y1536077D02*
X-4725D01*
G01X-2197Y1536235D02*
X-3151D01*
G01X-4725Y1536510D02*
X-6694D01*
G01X15077Y1536628D02*
X8523D01*
G01D02*
X-1D01*
G01D02*
X-985D01*
G01Y1537967D02*
X-1D01*
G01D02*
X8523D01*
G01D02*
X12600D01*
G01X-4725Y1538085D02*
X-6694D01*
G01X-3151Y1538361D02*
X-2197D01*
G01X-4725Y1538518D02*
X-4259D01*
G01X-9844Y1538676D02*
X-6694D01*
G01X-1970Y1538754D02*
X-1D01*
G01X-6694Y1530802D02*
X-4725Y1531117D01*
G01X-6694Y1534739D02*
X-4725Y1535054D01*
G01X-6694Y1538676D02*
X-4725Y1538991D01*
G01X-1Y1539778D02*
X-1970D01*
G01X-6694Y1539857D02*
X-9844D01*
G01X-4259Y1540014D02*
X-4725D01*
G01X-2197Y1540172D02*
X-3151D01*
G01X-4725Y1540447D02*
X-6694D01*
G01X15077Y1540565D02*
X8523D01*
G01D02*
X-1D01*
G01D02*
X-985D01*
G01Y1541904D02*
X-1D01*
G01D02*
X8523D01*
G01D02*
X12600D01*
G01X-4725Y1542022D02*
X-6694D01*
G01X-3151Y1542298D02*
X-2197D01*
G01X-4725Y1542455D02*
X-4259D01*
G01X-9844Y1542613D02*
X-6694D01*
G01X-1970Y1542691D02*
X-1D01*
G01Y1543715D02*
X-1970D01*
G01X-6694Y1543794D02*
X-9844D01*
G01X-4259Y1543951D02*
X-4725D01*
G01X-2197Y1544109D02*
X-3151D01*
G01X-4725Y1544384D02*
X-6694D01*
G01X15077Y1544502D02*
X8523D01*
G01D02*
X-1D01*
G01D02*
X-985D01*
G01Y1545841D02*
X-1D01*
G01D02*
X8523D01*
G01D02*
X12600D01*
G01X-4725Y1545959D02*
X-6694D01*
G01X-3151Y1546235D02*
X-2197D01*
G01X-4725Y1546392D02*
X-4259D01*
G01X-9844Y1546550D02*
X-6694D01*
G01X-1970Y1546628D02*
X-1D01*
G01Y1547652D02*
X-1970D01*
G01X-6694Y1547731D02*
X-9844D01*
G01X-4259Y1547888D02*
X-4725D01*
G01X-2197Y1548046D02*
X-3151D01*
G01X-4725Y1548321D02*
X-6694D01*
G01X15077Y1548439D02*
X8523D01*
G01D02*
X-1D01*
G01D02*
X-985D01*
G01Y1549778D02*
X-1D01*
G01D02*
X8523D01*
G01D02*
X12600D01*
G01X-4725Y1549896D02*
X-6694D01*
G01X-3151Y1550172D02*
X-2197D01*
G01X-3378Y1530880D02*
X-4259Y1530644D01*
G01X-3378Y1534817D02*
X-4259Y1534581D01*
G01X-3378Y1538754D02*
X-4259Y1538518D01*
G01X-3378Y1542691D02*
X-4259Y1542455D01*
G01X-3378Y1546628D02*
X-4259Y1546392D01*
G01X-6694Y1542613D02*
X-4725Y1542928D01*
G01X-6694Y1546550D02*
X-4725Y1546865D01*
G01X-3378Y1555526D02*
X-3151Y1555920D01*
G01X-1970Y1554502D02*
X-2197Y1554109D01*
G01X-3378Y1551589D02*
X-3151Y1551983D01*
G01X-9844Y1554424D02*
X-10631Y1554069D01*
G01X-10531Y1558051D02*
Y1555914D01*
G01Y1554114D02*
Y1551977D01*
G01X-6694Y1556195D02*
Y1555605D01*
G01Y1554424D02*
Y1553833D01*
G01Y1552258D02*
Y1551668D01*
G01X-4725Y1556195D02*
Y1555290D01*
G01Y1554739D02*
Y1553833D01*
G01Y1552258D02*
Y1551353D01*
G01X-3757Y1558085D02*
Y1555880D01*
G01Y1554148D02*
Y1551943D01*
G01X-2521Y1558085D02*
Y1555880D01*
G01Y1554148D02*
Y1551943D01*
G01X-2251Y1558400D02*
Y1555565D01*
G01Y1554463D02*
Y1551628D01*
G01X-985Y1557652D02*
Y1556313D01*
G01Y1553715D02*
Y1552376D01*
G01X8523Y1557652D02*
Y1556313D01*
G01Y1553715D02*
Y1552376D01*
G01X-2197Y1551983D02*
X-1970Y1551589D01*
G01X-3151Y1554109D02*
X-3378Y1554502D01*
G01X-2197Y1555920D02*
X-1970Y1555526D01*
G01X-10631Y1552022D02*
X-9844Y1551668D01*
G01X-10631Y1555959D02*
X-9844Y1555605D01*
G01X-4725Y1551353D02*
X-6694Y1551668D01*
G01X-4259Y1551825D02*
X-3378Y1551589D01*
G01X-4259Y1555762D02*
X-3378Y1555526D01*
G01X-4725Y1555290D02*
X-6694Y1555605D01*
G01X-4725Y1550329D02*
X-4259D01*
G01X-9844Y1550487D02*
X-6694D01*
G01X-1970Y1550565D02*
X-1D01*
G01Y1551589D02*
X-1970D01*
G01X-6694Y1551668D02*
X-9844D01*
G01X-4259Y1551825D02*
X-4725D01*
G01X-2197Y1551983D02*
X-3151D01*
G01X-4725Y1552258D02*
X-6694D01*
G01X15077Y1552376D02*
X8523D01*
G01D02*
X-1D01*
G01D02*
X-985D01*
G01Y1553715D02*
X-1D01*
G01D02*
X8523D01*
G01D02*
X12600D01*
G01X-4725Y1553833D02*
X-6694D01*
G01X-3151Y1554109D02*
X-2197D01*
G01X-4725Y1554266D02*
X-4259D01*
G01X-9844Y1554424D02*
X-6694D01*
G01X-1970Y1554502D02*
X-1D01*
G01Y1555526D02*
X-1970D01*
G01X-6694Y1555605D02*
X-9844D01*
G01X-4259Y1555762D02*
X-4725D01*
G01X-2197Y1555920D02*
X-3151D01*
G01X-4725Y1556195D02*
X-6694D01*
G01X15077Y1556313D02*
X8523D01*
G01D02*
X-1D01*
G01D02*
X-985D01*
G01X-3378Y1550565D02*
X-4259Y1550329D01*
G01X-3378Y1554502D02*
X-4259Y1554266D01*
G01X-6694Y1550487D02*
X-4725Y1550802D01*
G01X-6694Y1554424D02*
X-4725Y1554739D01*
G01X-38426Y1569975D02*
Y1567613D01*
G01Y1566038D02*
Y1563676D01*
G01Y1562101D02*
Y1559739D01*
G01X-38108Y1569276D02*
Y1568311D01*
G01Y1565339D02*
Y1564374D01*
G01Y1561402D02*
Y1560437D01*
G01X-37871Y1565362D02*
Y1564351D01*
G01Y1569299D02*
Y1568288D01*
G01Y1561425D02*
Y1560414D01*
G01X-35595Y1569518D02*
Y1568069D01*
G01Y1565581D02*
Y1564132D01*
G01Y1561644D02*
Y1560195D01*
G01X-35546Y1569975D02*
Y1567613D01*
G01Y1566038D02*
Y1563676D01*
G01Y1562101D02*
Y1559739D01*
G01X-35357Y1569541D02*
Y1568046D01*
G01Y1565604D02*
Y1564109D01*
G01Y1561667D02*
Y1560172D01*
G01X-34607Y1569896D02*
Y1567691D01*
G01Y1565959D02*
Y1563754D01*
G01Y1562022D02*
Y1559817D01*
G01X-34136Y1569555D02*
Y1568032D01*
G01Y1565618D02*
Y1564095D01*
G01Y1561681D02*
Y1560158D01*
G01X-33153Y1569566D02*
Y1568021D01*
G01Y1565629D02*
Y1564084D01*
G01Y1561692D02*
Y1560147D01*
G01X-32319Y1569575D02*
Y1568012D01*
G01Y1565638D02*
Y1564075D01*
G01Y1561701D02*
Y1560138D01*
G01X-31941Y1569580D02*
Y1568007D01*
G01Y1565643D02*
Y1564070D01*
G01Y1561706D02*
Y1560133D01*
G01X-38108Y1560437D02*
X-35351Y1560172D01*
G01X-38108Y1564374D02*
X-35351Y1564109D01*
G01X-38108Y1568311D02*
X-35351Y1568046D01*
G01Y1557731D02*
X-38108Y1557465D01*
G01X-35351Y1561668D02*
X-38108Y1561402D01*
G01X-35351Y1557731D02*
X-10631Y1558006D01*
G01X-35351Y1561668D02*
X-10631Y1561943D01*
G01X-35351Y1565605D02*
X-10631Y1565880D01*
G01X-35351Y1569542D02*
X-10631Y1569817D01*
G01X-39607Y1557120D02*
X-24844D01*
G01X-35546Y1558085D02*
X-1D01*
G01X-24509Y1558164D02*
X-39607D01*
G01Y1559739D02*
X-24509D01*
G01X-35546Y1559817D02*
X-1D01*
G01X-39607Y1560270D02*
X-27993D01*
G01X-35546Y1562022D02*
X-1D01*
G01X-24509Y1562101D02*
X-39607D01*
G01Y1563676D02*
X-24509D01*
G01X-35546Y1563754D02*
X-1D01*
G01X-35546Y1565959D02*
X-1D01*
G01X-24509Y1566038D02*
X-39607D01*
G01Y1567613D02*
X-24509D01*
G01X-35546Y1567691D02*
X-1D01*
G01X-35546Y1569896D02*
X-1D01*
G01X-24509Y1569975D02*
X-39607D01*
G01X-10631Y1559896D02*
X-35351Y1560172D01*
G01X-10631Y1563833D02*
X-35351Y1564109D01*
G01X-10631Y1567770D02*
X-35351Y1568046D01*
G01Y1565605D02*
X-38108Y1565339D01*
G01X-35351Y1569542D02*
X-38108Y1569276D01*
G01X-38426Y1589660D02*
Y1587298D01*
G01Y1585723D02*
Y1583361D01*
G01Y1581786D02*
Y1579424D01*
G01Y1577849D02*
Y1575487D01*
G01Y1573912D02*
Y1571550D01*
G01X-38108Y1588961D02*
Y1587996D01*
G01Y1585024D02*
Y1584059D01*
G01Y1581087D02*
Y1580122D01*
G01Y1577150D02*
Y1576185D01*
G01Y1573213D02*
Y1572248D01*
G01X-37871Y1588984D02*
Y1587973D01*
G01Y1585047D02*
Y1584036D01*
G01Y1581110D02*
Y1580099D01*
G01Y1577173D02*
Y1576162D01*
G01Y1573236D02*
Y1572225D01*
G01X-35595Y1589203D02*
Y1587754D01*
G01Y1585266D02*
Y1583817D01*
G01Y1581329D02*
Y1579880D01*
G01Y1577392D02*
Y1575943D01*
G01Y1573455D02*
Y1572006D01*
G01X-35546Y1589660D02*
Y1587298D01*
G01Y1585723D02*
Y1583361D01*
G01Y1581786D02*
Y1579424D01*
G01Y1577849D02*
Y1575487D01*
G01Y1573912D02*
Y1571550D01*
G01X-35357Y1589226D02*
Y1587731D01*
G01Y1585289D02*
Y1583794D01*
G01Y1581352D02*
Y1579857D01*
G01Y1577415D02*
Y1575920D01*
G01Y1573478D02*
Y1571983D01*
G01X-34607Y1589581D02*
Y1587376D01*
G01Y1585644D02*
Y1583439D01*
G01Y1581707D02*
Y1579502D01*
G01Y1577770D02*
Y1575565D01*
G01Y1573833D02*
Y1571628D01*
G01X-34136Y1589240D02*
Y1587717D01*
G01Y1585303D02*
Y1583780D01*
G01Y1581366D02*
Y1579843D01*
G01Y1577429D02*
Y1575906D01*
G01Y1573492D02*
Y1571969D01*
G01X-33153Y1589251D02*
Y1587706D01*
G01Y1585314D02*
Y1583769D01*
G01Y1581377D02*
Y1579832D01*
G01Y1577440D02*
Y1575895D01*
G01Y1573503D02*
Y1571958D01*
G01X-32319Y1589260D02*
Y1587697D01*
G01Y1585323D02*
Y1583760D01*
G01Y1581386D02*
Y1579823D01*
G01Y1577449D02*
Y1575886D01*
G01Y1573512D02*
Y1571949D01*
G01X-31941Y1589265D02*
Y1587693D01*
G01Y1585328D02*
Y1583756D01*
G01Y1581391D02*
Y1579819D01*
G01Y1577454D02*
Y1575881D01*
G01Y1573517D02*
Y1571944D01*
G01X-38108Y1572248D02*
X-35351Y1571983D01*
G01X-38108Y1576185D02*
X-35351Y1575920D01*
G01X-38108Y1580122D02*
X-35351Y1579857D01*
G01X-38108Y1584059D02*
X-35351Y1583794D01*
G01X-38108Y1587996D02*
X-35351Y1587731D01*
G01Y1573479D02*
X-10631Y1573754D01*
G01X-35351Y1577416D02*
X-10631Y1577691D01*
G01X-35351Y1581353D02*
X-10631Y1581628D01*
G01X-35351Y1585290D02*
X-10631Y1585565D01*
G01X-35351Y1589227D02*
X-10631Y1589502D01*
G01X-39607Y1571550D02*
X-24509D01*
G01X-35546Y1571628D02*
X-1D01*
G01X-27993Y1573617D02*
X-39607D01*
G01X-35546Y1573833D02*
X-1D01*
G01X-24509Y1573912D02*
X-39607D01*
G01Y1575487D02*
X-24509D01*
G01X-35546Y1575565D02*
X-1D01*
G01X-39607Y1576766D02*
X-24844D01*
G01X-35546Y1577770D02*
X-1D01*
G01X-24509Y1577849D02*
X-39607D01*
G01Y1579424D02*
X-24509D01*
G01X-35546Y1579502D02*
X-1D01*
G01X-39607Y1580743D02*
X-24844D01*
G01X-35546Y1581707D02*
X-1D01*
G01X-24509Y1581786D02*
X-39607D01*
G01Y1583361D02*
X-24509D01*
G01X-35546Y1583439D02*
X-1D01*
G01X-39607Y1583892D02*
X-27993D01*
G01X-35546Y1585644D02*
X-1D01*
G01X-24509Y1585723D02*
X-39607D01*
G01Y1587298D02*
X-24509D01*
G01X-35546Y1587376D02*
X-1D01*
G01X-35546Y1589581D02*
X-1D01*
G01X-24509Y1589660D02*
X-39607D01*
G01X-10631Y1571707D02*
X-35351Y1571983D01*
G01X-10631Y1575644D02*
X-35351Y1575920D01*
G01X-10631Y1579581D02*
X-35351Y1579857D01*
G01X-10631Y1583518D02*
X-35351Y1583794D01*
G01X-10631Y1587455D02*
X-35351Y1587731D01*
G01Y1573479D02*
X-38108Y1573213D01*
G01X-35351Y1577416D02*
X-38108Y1577150D01*
G01X-35351Y1581353D02*
X-38108Y1581087D01*
G01X-35351Y1585290D02*
X-38108Y1585024D01*
G01X-35351Y1589227D02*
X-38108Y1588961D01*
G01X-38426Y1609345D02*
Y1606983D01*
G01Y1605408D02*
Y1603046D01*
G01Y1601471D02*
Y1599109D01*
G01Y1593597D02*
Y1591235D01*
G01Y1597534D02*
Y1595172D01*
G01X-38108Y1608646D02*
Y1607681D01*
G01Y1604709D02*
Y1603744D01*
G01Y1600772D02*
Y1599807D01*
G01Y1596835D02*
Y1595870D01*
G01Y1592898D02*
Y1591933D01*
G01X-37871Y1608669D02*
Y1607658D01*
G01Y1604732D02*
Y1603721D01*
G01Y1600795D02*
Y1599784D01*
G01Y1596858D02*
Y1595847D01*
G01Y1592921D02*
Y1591910D01*
G01X-35595Y1608888D02*
Y1607439D01*
G01Y1604951D02*
Y1603502D01*
G01Y1601014D02*
Y1599565D01*
G01Y1593140D02*
Y1591691D01*
G01Y1597077D02*
Y1595628D01*
G01X-35546Y1609345D02*
Y1606983D01*
G01Y1605408D02*
Y1603046D01*
G01Y1601471D02*
Y1599109D01*
G01Y1597534D02*
Y1595172D01*
G01Y1593597D02*
Y1591235D01*
G01X-35357Y1608911D02*
Y1607416D01*
G01Y1604974D02*
Y1603479D01*
G01Y1601037D02*
Y1599542D01*
G01Y1593163D02*
Y1591668D01*
G01Y1597100D02*
Y1595605D01*
G01X-34607Y1609266D02*
Y1607061D01*
G01Y1605329D02*
Y1603124D01*
G01Y1601392D02*
Y1599187D01*
G01Y1593518D02*
Y1591313D01*
G01Y1597455D02*
Y1595250D01*
G01X-34136Y1608925D02*
Y1607402D01*
G01Y1604988D02*
Y1603465D01*
G01Y1601051D02*
Y1599528D01*
G01Y1593177D02*
Y1591654D01*
G01Y1597114D02*
Y1595591D01*
G01X-33153Y1608936D02*
Y1607391D01*
G01Y1604999D02*
Y1603454D01*
G01Y1601062D02*
Y1599517D01*
G01Y1593188D02*
Y1591643D01*
G01Y1597125D02*
Y1595580D01*
G01X-32319Y1608945D02*
Y1607382D01*
G01Y1605008D02*
Y1603445D01*
G01Y1601071D02*
Y1599508D01*
G01Y1593197D02*
Y1591634D01*
G01Y1597134D02*
Y1595571D01*
G01X-31941Y1608950D02*
Y1607378D01*
G01Y1605013D02*
Y1603441D01*
G01Y1601076D02*
Y1599504D01*
G01Y1593202D02*
Y1591630D01*
G01Y1597139D02*
Y1595567D01*
G01X-38108Y1591933D02*
X-35351Y1591668D01*
G01Y1593164D02*
X-10631Y1593439D01*
G01X-35351Y1597101D02*
X-10631Y1597376D01*
G01X-35351Y1601038D02*
X-10631Y1601313D01*
G01X-35351Y1604975D02*
X-10631Y1605250D01*
G01X-35351Y1608912D02*
X-10631Y1609187D01*
G01X-39607Y1591235D02*
X-24509D01*
G01X-35546Y1591313D02*
X-1D01*
G01X-35546Y1593518D02*
X-1D01*
G01X-24509Y1593597D02*
X-39607D01*
G01Y1595172D02*
X-24509D01*
G01X-35546Y1595250D02*
X-1D01*
G01X-27993Y1597239D02*
X-39607D01*
G01X-35546Y1597455D02*
X-1D01*
G01X-24509Y1597534D02*
X-39607D01*
G01Y1599109D02*
X-24509D01*
G01X-35546Y1599187D02*
X-1D01*
G01X-39607Y1600388D02*
X-24844D01*
G01X-35546Y1601392D02*
X-1D01*
G01X-24509Y1601471D02*
X-39607D01*
G01Y1603046D02*
X-24509D01*
G01X-35546Y1603124D02*
X-1D01*
G01X-39607Y1604365D02*
X-24844D01*
G01X-35546Y1605329D02*
X-1D01*
G01X-24509Y1605408D02*
X-39607D01*
G01Y1606983D02*
X-24509D01*
G01X-35546Y1607061D02*
X-1D01*
G01X-39607Y1607514D02*
X-27993D01*
G01X-35546Y1609266D02*
X-1D01*
G01X-24509Y1609345D02*
X-39607D01*
G01X-10631Y1591392D02*
X-35351Y1591668D01*
G01X-10631Y1595329D02*
X-35351Y1595605D01*
G01X-10631Y1599266D02*
X-35351Y1599542D01*
G01X-10631Y1603203D02*
X-35351Y1603479D01*
G01X-10631Y1607140D02*
X-35351Y1607416D01*
G01X-38108Y1595870D02*
X-35351Y1595605D01*
G01X-38108Y1599807D02*
X-35351Y1599542D01*
G01X-38108Y1603744D02*
X-35351Y1603479D01*
G01X-38108Y1607681D02*
X-35351Y1607416D01*
G01Y1593164D02*
X-38108Y1592898D01*
G01X-35351Y1597101D02*
X-38108Y1596835D01*
G01X-35351Y1601038D02*
X-38108Y1600772D01*
G01X-35351Y1604975D02*
X-38108Y1604709D01*
G01X-35351Y1608912D02*
X-38108Y1608646D01*
G01X-38426Y1632967D02*
Y1630605D01*
G01Y1629030D02*
Y1626668D01*
G01Y1625093D02*
Y1622731D01*
G01Y1617219D02*
Y1614857D01*
G01Y1621156D02*
Y1618794D01*
G01Y1613282D02*
Y1610920D01*
G01X-38108Y1628331D02*
Y1627366D01*
G01Y1624394D02*
Y1623429D01*
G01Y1616520D02*
Y1615555D01*
G01Y1620457D02*
Y1619492D01*
G01Y1612583D02*
Y1611618D01*
G01X-37871Y1628354D02*
Y1627343D01*
G01Y1624417D02*
Y1623406D01*
G01Y1616543D02*
Y1615532D01*
G01Y1620480D02*
Y1619469D01*
G01Y1612606D02*
Y1611595D01*
G01X-35595Y1628573D02*
Y1627124D01*
G01Y1624636D02*
Y1623187D01*
G01Y1616762D02*
Y1615313D01*
G01Y1620699D02*
Y1619250D01*
G01Y1612825D02*
Y1611376D01*
G01X-35546Y1632967D02*
Y1630605D01*
G01Y1629030D02*
Y1626668D01*
G01Y1625093D02*
Y1622731D01*
G01Y1621156D02*
Y1618794D01*
G01Y1617219D02*
Y1614857D01*
G01Y1613282D02*
Y1610920D01*
G01X-35357Y1628596D02*
Y1627101D01*
G01Y1624659D02*
Y1623164D01*
G01Y1620722D02*
Y1619227D01*
G01Y1616785D02*
Y1615290D01*
G01Y1612848D02*
Y1611353D01*
G01X-34607Y1628951D02*
Y1626746D01*
G01Y1625014D02*
Y1622809D01*
G01Y1617140D02*
Y1614935D01*
G01Y1621077D02*
Y1618872D01*
G01Y1613203D02*
Y1610998D01*
G01X-34136Y1628610D02*
Y1627087D01*
G01Y1624673D02*
Y1623150D01*
G01Y1616799D02*
Y1615276D01*
G01Y1620736D02*
Y1619213D01*
G01Y1612862D02*
Y1611339D01*
G01X-33153Y1628621D02*
Y1627076D01*
G01Y1624684D02*
Y1623139D01*
G01Y1616810D02*
Y1615265D01*
G01Y1620747D02*
Y1619202D01*
G01Y1612873D02*
Y1611328D01*
G01X-32319Y1628630D02*
Y1627067D01*
G01Y1624693D02*
Y1623130D01*
G01Y1616819D02*
Y1615256D01*
G01Y1620756D02*
Y1619193D01*
G01Y1612882D02*
Y1611319D01*
G01X-31941Y1628635D02*
Y1627063D01*
G01Y1624698D02*
Y1623126D01*
G01Y1616824D02*
Y1615252D01*
G01Y1620761D02*
Y1619189D01*
G01Y1612887D02*
Y1611315D01*
G01X-39607Y1610920D02*
X-24509D01*
G01X-35546Y1610998D02*
X-1D01*
G01X-35546Y1613203D02*
X-1D01*
G01X-24509Y1613282D02*
X-39607D01*
G01Y1614857D02*
X-24509D01*
G01X-35546Y1614935D02*
X-1D01*
G01X-10631Y1611077D02*
X-35351Y1611353D01*
G01X-10631Y1615014D02*
X-35351Y1615290D01*
G01X-10631Y1618951D02*
X-35351Y1619227D01*
G01X-38108Y1611618D02*
X-35351Y1611353D01*
G01X-38108Y1615555D02*
X-35351Y1615290D01*
G01X-38108Y1619492D02*
X-35351Y1619227D01*
G01X-38108Y1623429D02*
X-35351Y1623164D01*
G01X-38108Y1627366D02*
X-35351Y1627101D01*
G01Y1612849D02*
X-38108Y1612583D01*
G01X-35351Y1616786D02*
X-38108Y1616520D01*
G01X-35351Y1620723D02*
X-38108Y1620457D01*
G01X-35351Y1624660D02*
X-38108Y1624394D01*
G01X-35351Y1628597D02*
X-38108Y1628331D01*
G01X-35351Y1612849D02*
X-10631Y1613124D01*
G01X-35351Y1616786D02*
X-10631Y1617061D01*
G01X-35351Y1620723D02*
X-10631Y1620998D01*
G01X-35351Y1624660D02*
X-10631Y1624935D01*
G01X-35351Y1628597D02*
X-10631Y1628872D01*
G01X-35546Y1617140D02*
X-1D01*
G01X-24509Y1617219D02*
X-39607D01*
G01Y1618794D02*
X-24509D01*
G01X-35546Y1618872D02*
X-1D01*
G01X-27993Y1620861D02*
X-39607D01*
G01X-35546Y1621077D02*
X-1D01*
G01X-24509Y1621156D02*
X-39607D01*
G01Y1622731D02*
X-24509D01*
G01X-35546Y1622809D02*
X-1D01*
G01X-39607Y1624010D02*
X-24844D01*
G01X-35546Y1625014D02*
X-1D01*
G01X-24509Y1625093D02*
X-39607D01*
G01Y1626668D02*
X-24509D01*
G01X-35546Y1626746D02*
X-1D01*
G01X-39607Y1627987D02*
X-24844D01*
G01X-35546Y1628951D02*
X-1D01*
G01X-24509Y1629030D02*
X-39607D01*
G01Y1630605D02*
X-24509D01*
G01X-10631Y1622888D02*
X-35351Y1623164D01*
G01X-10631Y1626825D02*
X-35351Y1627101D01*
G01X-38426Y1640841D02*
Y1638479D01*
G01Y1636904D02*
Y1634542D01*
G01X-38108Y1640142D02*
Y1639177D01*
G01Y1636205D02*
Y1635240D01*
G01Y1632268D02*
Y1631303D01*
G01X-37871Y1640165D02*
Y1639154D01*
G01Y1636228D02*
Y1635217D01*
G01Y1632291D02*
Y1631280D01*
G01X-35595Y1640384D02*
Y1638935D01*
G01Y1636447D02*
Y1634998D01*
G01Y1632510D02*
Y1631061D01*
G01X-35546Y1640841D02*
Y1638479D01*
G01Y1636904D02*
Y1634542D01*
G01X-35357Y1640407D02*
Y1638912D01*
G01Y1636470D02*
Y1634975D01*
G01Y1632533D02*
Y1631038D01*
G01X-34607Y1640762D02*
Y1638557D01*
G01Y1636825D02*
Y1634620D01*
G01Y1632888D02*
Y1630683D01*
G01X-34136Y1640421D02*
Y1638898D01*
G01Y1636484D02*
Y1634961D01*
G01Y1632547D02*
Y1631024D01*
G01X-33153Y1640432D02*
Y1638887D01*
G01Y1636495D02*
Y1634950D01*
G01Y1632558D02*
Y1631013D01*
G01X-32319Y1640441D02*
Y1638878D01*
G01Y1636504D02*
Y1634941D01*
G01Y1632567D02*
Y1631004D01*
G01X-31941Y1640446D02*
Y1638874D01*
G01Y1636509D02*
Y1634937D01*
G01Y1632572D02*
Y1631000D01*
G01X-38108Y1631303D02*
X-35351Y1631038D01*
G01X-38108Y1635240D02*
X-35351Y1634975D01*
G01X-38108Y1639177D02*
X-35351Y1638912D01*
G01Y1632534D02*
X-38108Y1632268D01*
G01X-35351Y1636471D02*
X-38108Y1636205D01*
G01X-35351Y1632534D02*
X-10631Y1632809D01*
G01X-35351Y1636471D02*
X-10631Y1636746D01*
G01X-35546Y1630683D02*
X-1D01*
G01X-39607Y1631136D02*
X-27993D01*
G01X-35546Y1632888D02*
X-1D01*
G01X-24509Y1632967D02*
X-39607D01*
G01Y1634542D02*
X-24509D01*
G01X-35546Y1634620D02*
X-1D01*
G01X-35546Y1636825D02*
X-1D01*
G01X-24509Y1636904D02*
X-39607D01*
G01Y1638479D02*
X-24509D01*
G01X-35546Y1638557D02*
X-1D01*
G01X-10631Y1630762D02*
X-35351Y1631038D01*
G01X-10631Y1634699D02*
X-35351Y1634975D01*
G01X-10631Y1638636D02*
X-35351Y1638912D01*
G01X-27993Y1557120D02*
Y1576766D01*
G01X-27265Y1569975D02*
Y1567613D01*
G01Y1566038D02*
Y1563676D01*
G01Y1562101D02*
Y1559739D01*
G01X-26943Y1569635D02*
Y1567952D01*
G01Y1565698D02*
Y1564015D01*
G01Y1561761D02*
Y1560078D01*
G01X-26566Y1569639D02*
Y1567948D01*
G01Y1565702D02*
Y1564011D01*
G01Y1561765D02*
Y1560074D01*
G01X-24844Y1557120D02*
Y1576766D01*
G01X-24509Y1569975D02*
Y1567613D01*
G01Y1566038D02*
Y1563676D01*
G01Y1562101D02*
Y1559739D01*
G01X-24122Y1569667D02*
Y1567920D01*
G01Y1565730D02*
Y1563983D01*
G01Y1561793D02*
Y1560046D01*
G01X-23684Y1569672D02*
Y1567915D01*
G01Y1565735D02*
Y1563978D01*
G01Y1561798D02*
Y1560041D01*
G01X-12993Y1570211D02*
Y1569896D01*
G01Y1567691D02*
Y1567376D01*
G01Y1566274D02*
Y1565959D01*
G01Y1563754D02*
Y1563439D01*
G01Y1562337D02*
Y1562022D01*
G01Y1559817D02*
Y1559502D01*
G01Y1558400D02*
Y1558085D01*
G01X-12280Y1569799D02*
Y1567788D01*
G01Y1565862D02*
Y1563851D01*
G01Y1561925D02*
Y1559914D01*
G01X-11843Y1569804D02*
Y1567783D01*
G01Y1565867D02*
Y1563846D01*
G01Y1561930D02*
Y1559909D01*
G01X-1Y1558400D02*
X-12993D01*
G01Y1559502D02*
X-1D01*
G01Y1562337D02*
X-12993D01*
G01Y1563439D02*
X-1D01*
G01Y1566274D02*
X-12993D01*
G01Y1567376D02*
X-1D01*
G01Y1570211D02*
X-12993D01*
G01X-27993Y1580743D02*
Y1600388D01*
G01X-27265Y1589660D02*
Y1587298D01*
G01Y1585723D02*
Y1583361D01*
G01Y1581786D02*
Y1579424D01*
G01Y1577849D02*
Y1575487D01*
G01Y1573912D02*
Y1571550D01*
G01X-26943Y1589320D02*
Y1587637D01*
G01Y1585383D02*
Y1583700D01*
G01Y1581446D02*
Y1579763D01*
G01Y1577509D02*
Y1575826D01*
G01Y1573572D02*
Y1571889D01*
G01X-26566Y1589324D02*
Y1587633D01*
G01Y1585387D02*
Y1583696D01*
G01Y1581450D02*
Y1579759D01*
G01Y1577513D02*
Y1575822D01*
G01Y1573576D02*
Y1571885D01*
G01X-24844Y1580743D02*
Y1600388D01*
G01X-24509Y1589660D02*
Y1587298D01*
G01Y1585723D02*
Y1583361D01*
G01Y1581786D02*
Y1579424D01*
G01Y1577849D02*
Y1575487D01*
G01Y1573912D02*
Y1571550D01*
G01X-24122Y1589352D02*
Y1587606D01*
G01Y1585415D02*
Y1583669D01*
G01Y1581478D02*
Y1579731D01*
G01Y1577541D02*
Y1575794D01*
G01Y1573604D02*
Y1571857D01*
G01X-23684Y1589357D02*
Y1587600D01*
G01Y1585420D02*
Y1583663D01*
G01Y1581483D02*
Y1579726D01*
G01Y1577546D02*
Y1575789D01*
G01Y1573609D02*
Y1571852D01*
G01X-12993Y1589896D02*
Y1589581D01*
G01Y1587376D02*
Y1587061D01*
G01Y1585959D02*
Y1585644D01*
G01Y1583439D02*
Y1583124D01*
G01Y1579502D02*
Y1579187D01*
G01Y1582022D02*
Y1581707D01*
G01Y1575565D02*
Y1575250D01*
G01Y1578085D02*
Y1577770D01*
G01Y1571628D02*
Y1571313D01*
G01Y1574148D02*
Y1573833D01*
G01X-12280Y1589484D02*
Y1587473D01*
G01Y1585547D02*
Y1583536D01*
G01Y1581610D02*
Y1579599D01*
G01Y1577673D02*
Y1575662D01*
G01Y1573736D02*
Y1571725D01*
G01X-11843Y1589489D02*
Y1587469D01*
G01Y1585552D02*
Y1583531D01*
G01Y1581615D02*
Y1579594D01*
G01Y1577678D02*
Y1575657D01*
G01Y1573741D02*
Y1571720D01*
G01X-12993Y1571313D02*
X-1D01*
G01Y1574148D02*
X-12993D01*
G01Y1575250D02*
X-1D01*
G01Y1578085D02*
X-12993D01*
G01Y1579187D02*
X-1D01*
G01Y1582022D02*
X-12993D01*
G01Y1583124D02*
X-1D01*
G01Y1585959D02*
X-12993D01*
G01Y1587061D02*
X-1D01*
G01Y1589896D02*
X-12993D01*
G01X-27993Y1604365D02*
Y1624010D01*
G01X-27265Y1609345D02*
Y1606983D01*
G01Y1605408D02*
Y1603046D01*
G01Y1601471D02*
Y1599109D01*
G01Y1597534D02*
Y1595172D01*
G01Y1593597D02*
Y1591235D01*
G01X-26943Y1609006D02*
Y1607322D01*
G01Y1605069D02*
Y1603385D01*
G01Y1601131D02*
Y1599448D01*
G01Y1593257D02*
Y1591574D01*
G01Y1597194D02*
Y1595511D01*
G01X-26566Y1609009D02*
Y1607318D01*
G01Y1605072D02*
Y1603381D01*
G01Y1601135D02*
Y1599444D01*
G01Y1593261D02*
Y1591570D01*
G01Y1597198D02*
Y1595507D01*
G01X-24844Y1604365D02*
Y1624010D01*
G01X-24509Y1609345D02*
Y1606983D01*
G01Y1605408D02*
Y1603046D01*
G01Y1601471D02*
Y1599109D01*
G01Y1597534D02*
Y1595172D01*
G01Y1593597D02*
Y1591235D01*
G01X-24122Y1609037D02*
Y1607291D01*
G01Y1605100D02*
Y1603354D01*
G01Y1601163D02*
Y1599417D01*
G01Y1593289D02*
Y1591543D01*
G01Y1597226D02*
Y1595480D01*
G01X-23684Y1609042D02*
Y1607285D01*
G01Y1605105D02*
Y1603348D01*
G01Y1601168D02*
Y1599411D01*
G01Y1593294D02*
Y1591537D01*
G01Y1597231D02*
Y1595474D01*
G01X-12993Y1607061D02*
Y1606746D01*
G01Y1609581D02*
Y1609266D01*
G01Y1603124D02*
Y1602809D01*
G01Y1605644D02*
Y1605329D01*
G01Y1599187D02*
Y1598872D01*
G01Y1601707D02*
Y1601392D01*
G01Y1597770D02*
Y1597455D01*
G01Y1595250D02*
Y1594935D01*
G01Y1593833D02*
Y1593518D01*
G01Y1591313D02*
Y1590998D01*
G01X-12280Y1609169D02*
Y1607158D01*
G01Y1605232D02*
Y1603221D01*
G01Y1601295D02*
Y1599284D01*
G01Y1593421D02*
Y1591410D01*
G01Y1597358D02*
Y1595347D01*
G01X-11843Y1609174D02*
Y1607154D01*
G01Y1605237D02*
Y1603217D01*
G01Y1601300D02*
Y1599280D01*
G01Y1593426D02*
Y1591406D01*
G01Y1597363D02*
Y1595343D01*
G01X-12993Y1590998D02*
X-1D01*
G01Y1593833D02*
X-12993D01*
G01Y1594935D02*
X-1D01*
G01Y1597770D02*
X-12993D01*
G01Y1598872D02*
X-1D01*
G01Y1601707D02*
X-12993D01*
G01Y1602809D02*
X-1D01*
G01Y1605644D02*
X-12993D01*
G01Y1606746D02*
X-1D01*
G01Y1609581D02*
X-12993D01*
G01X-27993Y1627987D02*
Y1647632D01*
G01X-27265Y1632967D02*
Y1630605D01*
G01Y1629030D02*
Y1626668D01*
G01Y1625093D02*
Y1622731D01*
G01Y1621156D02*
Y1618794D01*
G01Y1617219D02*
Y1614857D01*
G01Y1613282D02*
Y1610920D01*
G01X-26943Y1628691D02*
Y1627007D01*
G01Y1624754D02*
Y1623070D01*
G01Y1620817D02*
Y1619133D01*
G01Y1616880D02*
Y1615196D01*
G01Y1612943D02*
Y1611259D01*
G01X-26566Y1628694D02*
Y1627003D01*
G01Y1624757D02*
Y1623066D01*
G01Y1616883D02*
Y1615192D01*
G01Y1620820D02*
Y1619129D01*
G01Y1612946D02*
Y1611255D01*
G01X-24844Y1627987D02*
Y1647632D01*
G01X-24509Y1632967D02*
Y1630605D01*
G01Y1629030D02*
Y1626668D01*
G01Y1625093D02*
Y1622731D01*
G01Y1621156D02*
Y1618794D01*
G01Y1617219D02*
Y1614857D01*
G01Y1613282D02*
Y1610920D01*
G01X-24122Y1628722D02*
Y1626976D01*
G01Y1624785D02*
Y1623039D01*
G01Y1616911D02*
Y1615165D01*
G01Y1620848D02*
Y1619102D01*
G01Y1612974D02*
Y1611228D01*
G01X-23684Y1628727D02*
Y1626970D01*
G01Y1624790D02*
Y1623033D01*
G01Y1616916D02*
Y1615159D01*
G01Y1620853D02*
Y1619096D01*
G01Y1612979D02*
Y1611222D01*
G01X-12993Y1630683D02*
Y1630369D01*
G01Y1626746D02*
Y1626431D01*
G01Y1629266D02*
Y1628951D01*
G01Y1622809D02*
Y1622494D01*
G01Y1625329D02*
Y1625014D01*
G01Y1621392D02*
Y1621077D01*
G01Y1618872D02*
Y1618557D01*
G01Y1617455D02*
Y1617140D01*
G01Y1614935D02*
Y1614620D01*
G01Y1613518D02*
Y1613203D01*
G01Y1610998D02*
Y1610683D01*
G01X-12280Y1628854D02*
Y1626843D01*
G01Y1624917D02*
Y1622906D01*
G01Y1617043D02*
Y1615032D01*
G01Y1620980D02*
Y1618969D01*
G01Y1613106D02*
Y1611095D01*
G01X-11843Y1628859D02*
Y1626839D01*
G01Y1624922D02*
Y1622902D01*
G01Y1620985D02*
Y1618965D01*
G01Y1617048D02*
Y1615028D01*
G01Y1613111D02*
Y1611091D01*
G01X-12993Y1610683D02*
X-1D01*
G01Y1613518D02*
X-12993D01*
G01Y1614620D02*
X-1D01*
G01Y1617455D02*
X-12993D01*
G01Y1618557D02*
X-1D01*
G01Y1621392D02*
X-12993D01*
G01Y1622494D02*
X-1D01*
G01Y1625329D02*
X-12993D01*
G01Y1626431D02*
X-1D01*
G01Y1629266D02*
X-12993D01*
G01Y1630369D02*
X-1D01*
G01X-27265Y1640841D02*
Y1638479D01*
G01Y1636904D02*
Y1634542D01*
G01X-26943Y1640502D02*
Y1638818D01*
G01Y1636565D02*
Y1634881D01*
G01Y1632628D02*
Y1630944D01*
G01X-26566Y1640506D02*
Y1638814D01*
G01Y1636569D02*
Y1634877D01*
G01Y1632631D02*
Y1630940D01*
G01X-24509Y1640841D02*
Y1638479D01*
G01Y1636904D02*
Y1634542D01*
G01X-24122Y1640533D02*
Y1638787D01*
G01Y1636596D02*
Y1634850D01*
G01Y1632659D02*
Y1630913D01*
G01X-23684Y1640538D02*
Y1638781D01*
G01Y1636601D02*
Y1634844D01*
G01Y1632664D02*
Y1630907D01*
G01X-12993Y1638557D02*
Y1638243D01*
G01Y1637140D02*
Y1636825D01*
G01Y1634620D02*
Y1634306D01*
G01Y1633203D02*
Y1632888D01*
G01X-12280Y1640665D02*
Y1638654D01*
G01Y1636728D02*
Y1634717D01*
G01Y1632791D02*
Y1630780D01*
G01X-11843Y1640670D02*
Y1638650D01*
G01Y1636733D02*
Y1634713D01*
G01Y1632796D02*
Y1630776D01*
G01X-1Y1633203D02*
X-12993D01*
G01Y1634306D02*
X-1D01*
G01Y1637140D02*
X-12993D01*
G01Y1638243D02*
X-1D01*
G01X-1970Y1570250D02*
X-2197Y1569857D01*
G01X-3378Y1567337D02*
X-3151Y1567731D01*
G01X-1970Y1566313D02*
X-2197Y1565920D01*
G01X-3378Y1563400D02*
X-3151Y1563794D01*
G01X-1970Y1562376D02*
X-2197Y1561983D01*
G01X-3378Y1559463D02*
X-3151Y1559857D01*
G01X-1970Y1558439D02*
X-2197Y1558046D01*
G01X-9844Y1570172D02*
X-10631Y1569817D01*
G01X-9844Y1566235D02*
X-10631Y1565880D01*
G01X-9844Y1562298D02*
X-10631Y1561943D01*
G01X-9844Y1558361D02*
X-10631Y1558006D01*
G01X-10531Y1569862D02*
Y1567725D01*
G01Y1565925D02*
Y1563788D01*
G01Y1561988D02*
Y1559851D01*
G01X-6694Y1570172D02*
Y1569581D01*
G01Y1568006D02*
Y1567416D01*
G01Y1566235D02*
Y1565644D01*
G01Y1564069D02*
Y1563479D01*
G01Y1562298D02*
Y1561707D01*
G01Y1560132D02*
Y1559542D01*
G01Y1558361D02*
Y1557770D01*
G01X-4725Y1570487D02*
Y1569581D01*
G01Y1568006D02*
Y1567101D01*
G01Y1566550D02*
Y1565644D01*
G01Y1564069D02*
Y1563164D01*
G01Y1562613D02*
Y1561707D01*
G01Y1558676D02*
Y1557770D01*
G01Y1560132D02*
Y1559227D01*
G01X-3757Y1569896D02*
Y1567691D01*
G01Y1565959D02*
Y1563754D01*
G01Y1562022D02*
Y1559817D01*
G01X-2521Y1569896D02*
Y1567691D01*
G01Y1565959D02*
Y1563754D01*
G01Y1562022D02*
Y1559817D01*
G01X-2251Y1570211D02*
Y1567376D01*
G01Y1566274D02*
Y1563439D01*
G01Y1562337D02*
Y1559502D01*
G01X-985Y1565526D02*
Y1564187D01*
G01Y1569463D02*
Y1568124D01*
G01Y1561589D02*
Y1560250D01*
G01X8523Y1569463D02*
Y1568124D01*
G01Y1565526D02*
Y1564187D01*
G01Y1561589D02*
Y1560250D01*
G01X-3151Y1558046D02*
X-3378Y1558439D01*
G01X-2197Y1559857D02*
X-1970Y1559463D01*
G01X-3151Y1561983D02*
X-3378Y1562376D01*
G01X-2197Y1563794D02*
X-1970Y1563400D01*
G01X-3151Y1565920D02*
X-3378Y1566313D01*
G01X-2197Y1567731D02*
X-1970Y1567337D01*
G01X-3151Y1569857D02*
X-3378Y1570250D01*
G01X-10631Y1559896D02*
X-9844Y1559542D01*
G01X-10631Y1563833D02*
X-9844Y1563479D01*
G01X-10631Y1567770D02*
X-9844Y1567416D01*
G01X-4259Y1559699D02*
X-3378Y1559463D01*
G01X-4259Y1563636D02*
X-3378Y1563400D01*
G01X-4259Y1567573D02*
X-3378Y1567337D01*
G01X-4725Y1559227D02*
X-6694Y1559542D01*
G01X-4725Y1563164D02*
X-6694Y1563479D01*
G01X-4725Y1567101D02*
X-6694Y1567416D01*
G01X-985Y1557652D02*
X-1D01*
G01D02*
X8523D01*
G01D02*
X12600D01*
G01X-4725Y1557770D02*
X-6694D01*
G01X-3151Y1558046D02*
X-2197D01*
G01X-4725Y1558203D02*
X-4259D01*
G01X-9844Y1558361D02*
X-6694D01*
G01X-1970Y1558439D02*
X-1D01*
G01Y1559463D02*
X-1970D01*
G01X-6694Y1559542D02*
X-9844D01*
G01X-4259Y1559699D02*
X-4725D01*
G01X-2197Y1559857D02*
X-3151D01*
G01X-4725Y1560132D02*
X-6694D01*
G01X15077Y1560250D02*
X8523D01*
G01D02*
X-1D01*
G01D02*
X-985D01*
G01Y1561589D02*
X-1D01*
G01D02*
X8523D01*
G01D02*
X12600D01*
G01X-4725Y1561707D02*
X-6694D01*
G01X-3151Y1561983D02*
X-2197D01*
G01X-4725Y1562140D02*
X-4259D01*
G01X-9844Y1562298D02*
X-6694D01*
G01X-1970Y1562376D02*
X-1D01*
G01Y1563400D02*
X-1970D01*
G01X-6694Y1563479D02*
X-9844D01*
G01X-4259Y1563636D02*
X-4725D01*
G01X-2197Y1563794D02*
X-3151D01*
G01X-4725Y1564069D02*
X-6694D01*
G01X15077Y1564187D02*
X8523D01*
G01D02*
X-1D01*
G01D02*
X-985D01*
G01Y1565526D02*
X-1D01*
G01D02*
X8523D01*
G01D02*
X12600D01*
G01X-4725Y1565644D02*
X-6694D01*
G01X-3151Y1565920D02*
X-2197D01*
G01X-4725Y1566077D02*
X-4259D01*
G01X-9844Y1566235D02*
X-6694D01*
G01X-1970Y1566313D02*
X-1D01*
G01Y1567337D02*
X-1970D01*
G01X-6694Y1567416D02*
X-9844D01*
G01X-4259Y1567573D02*
X-4725D01*
G01X-2197Y1567731D02*
X-3151D01*
G01X-4725Y1568006D02*
X-6694D01*
G01X15077Y1568124D02*
X8523D01*
G01D02*
X-1D01*
G01D02*
X-985D01*
G01Y1569463D02*
X-1D01*
G01D02*
X8523D01*
G01D02*
X12600D01*
G01X-4725Y1569581D02*
X-6694D01*
G01X-3151Y1569857D02*
X-2197D01*
G01X-4725Y1570014D02*
X-4259D01*
G01X-9844Y1570172D02*
X-6694D01*
G01X-1970Y1570250D02*
X-1D01*
G01X-3378Y1558439D02*
X-4259Y1558203D01*
G01X-3378Y1562376D02*
X-4259Y1562140D01*
G01X-3378Y1566313D02*
X-4259Y1566077D01*
G01X-3378Y1570250D02*
X-4259Y1570014D01*
G01X-6694Y1558361D02*
X-4725Y1558676D01*
G01X-6694Y1562298D02*
X-4725Y1562613D01*
G01X-6694Y1566235D02*
X-4725Y1566550D01*
G01X-6694Y1570172D02*
X-4725Y1570487D01*
G01X-9844Y1589857D02*
X-10631Y1589502D01*
G01X-9844Y1585920D02*
X-10631Y1585565D01*
G01X-9844Y1581983D02*
X-10631Y1581628D01*
G01X-1970Y1589935D02*
X-2197Y1589542D01*
G01X-3378Y1587022D02*
X-3151Y1587416D01*
G01X-1970Y1585998D02*
X-2197Y1585605D01*
G01X-3378Y1583085D02*
X-3151Y1583479D01*
G01X-1970Y1582061D02*
X-2197Y1581668D01*
G01X-3378Y1579148D02*
X-3151Y1579542D01*
G01X-1970Y1578124D02*
X-2197Y1577731D01*
G01X-3378Y1575211D02*
X-3151Y1575605D01*
G01X-1970Y1574187D02*
X-2197Y1573794D01*
G01X-3378Y1571274D02*
X-3151Y1571668D01*
G01X-9844Y1578046D02*
X-10631Y1577691D01*
G01X-9844Y1574109D02*
X-10631Y1573754D01*
G01X-10531Y1589547D02*
Y1587410D01*
G01Y1585610D02*
Y1583473D01*
G01Y1581673D02*
Y1579536D01*
G01Y1577736D02*
Y1575599D01*
G01Y1573799D02*
Y1571662D01*
G01X-6694Y1589857D02*
Y1589266D01*
G01Y1587691D02*
Y1587101D01*
G01Y1585920D02*
Y1585329D01*
G01Y1583754D02*
Y1583164D01*
G01Y1581983D02*
Y1581392D01*
G01Y1579817D02*
Y1579227D01*
G01Y1578046D02*
Y1577455D01*
G01Y1575880D02*
Y1575290D01*
G01Y1574109D02*
Y1573518D01*
G01Y1571943D02*
Y1571353D01*
G01X-4725Y1590172D02*
Y1589266D01*
G01Y1586235D02*
Y1585329D01*
G01Y1587691D02*
Y1586786D01*
G01Y1582298D02*
Y1581392D01*
G01Y1579817D02*
Y1578912D01*
G01Y1583754D02*
Y1582849D01*
G01Y1578361D02*
Y1577455D01*
G01Y1575880D02*
Y1574975D01*
G01Y1574424D02*
Y1573518D01*
G01Y1571943D02*
Y1571038D01*
G01X-3757Y1589581D02*
Y1587376D01*
G01Y1585644D02*
Y1583439D01*
G01Y1581707D02*
Y1579502D01*
G01Y1577770D02*
Y1575565D01*
G01Y1573833D02*
Y1571628D01*
G01X-2521Y1589581D02*
Y1587376D01*
G01Y1585644D02*
Y1583439D01*
G01Y1581707D02*
Y1579502D01*
G01Y1577770D02*
Y1575565D01*
G01Y1573833D02*
Y1571628D01*
G01X-2251Y1589896D02*
Y1587061D01*
G01Y1585959D02*
Y1583124D01*
G01Y1582022D02*
Y1579187D01*
G01Y1578085D02*
Y1575250D01*
G01Y1574148D02*
Y1571313D01*
G01X-985Y1589148D02*
Y1587809D01*
G01Y1585211D02*
Y1583872D01*
G01Y1581274D02*
Y1579935D01*
G01Y1577337D02*
Y1575998D01*
G01Y1573400D02*
Y1572061D01*
G01X8523Y1589148D02*
Y1587809D01*
G01Y1585211D02*
Y1583872D01*
G01Y1581274D02*
Y1579935D01*
G01Y1577337D02*
Y1575998D01*
G01Y1573400D02*
Y1572061D01*
G01X-2197Y1571668D02*
X-1970Y1571274D01*
G01X-3151Y1573794D02*
X-3378Y1574187D01*
G01X-2197Y1575605D02*
X-1970Y1575211D01*
G01X-3151Y1577731D02*
X-3378Y1578124D01*
G01X-2197Y1579542D02*
X-1970Y1579148D01*
G01X-3151Y1581668D02*
X-3378Y1582061D01*
G01X-2197Y1583479D02*
X-1970Y1583085D01*
G01X-3151Y1585605D02*
X-3378Y1585998D01*
G01X-2197Y1587416D02*
X-1970Y1587022D01*
G01X-3151Y1589542D02*
X-3378Y1589935D01*
G01X-10631Y1571707D02*
X-9844Y1571353D01*
G01X-10631Y1575644D02*
X-9844Y1575290D01*
G01X-10631Y1579581D02*
X-9844Y1579227D01*
G01X-10631Y1583518D02*
X-9844Y1583164D01*
G01X-10631Y1587455D02*
X-9844Y1587101D01*
G01X-4259Y1571510D02*
X-3378Y1571274D01*
G01X-4259Y1575447D02*
X-3378Y1575211D01*
G01X-4259Y1579384D02*
X-3378Y1579148D01*
G01X-4259Y1583321D02*
X-3378Y1583085D01*
G01X-4259Y1587258D02*
X-3378Y1587022D01*
G01X-4725Y1571038D02*
X-6694Y1571353D01*
G01X-4725Y1574975D02*
X-6694Y1575290D01*
G01X-4725Y1578912D02*
X-6694Y1579227D01*
G01X-4725Y1582849D02*
X-6694Y1583164D01*
G01X-4725Y1586786D02*
X-6694Y1587101D01*
G01X-1Y1571274D02*
X-1970D01*
G01X-6694Y1571353D02*
X-9844D01*
G01X-4259Y1571510D02*
X-4725D01*
G01X-2197Y1571668D02*
X-3151D01*
G01X-4725Y1571943D02*
X-6694D01*
G01X15077Y1572061D02*
X8523D01*
G01D02*
X-1D01*
G01D02*
X-985D01*
G01Y1573400D02*
X-1D01*
G01D02*
X8523D01*
G01D02*
X12600D01*
G01X-4725Y1573518D02*
X-6694D01*
G01X-3151Y1573794D02*
X-2197D01*
G01X-4725Y1573951D02*
X-4259D01*
G01X-9844Y1574109D02*
X-6694D01*
G01X-1970Y1574187D02*
X-1D01*
G01Y1575211D02*
X-1970D01*
G01X-6694Y1575290D02*
X-9844D01*
G01X-4259Y1575447D02*
X-4725D01*
G01X-2197Y1575605D02*
X-3151D01*
G01X-4725Y1575880D02*
X-6694D01*
G01X15077Y1575998D02*
X8523D01*
G01D02*
X-1D01*
G01D02*
X-985D01*
G01Y1577337D02*
X-1D01*
G01D02*
X8523D01*
G01D02*
X12600D01*
G01X-4725Y1577455D02*
X-6694D01*
G01X-3151Y1577731D02*
X-2197D01*
G01X-4725Y1577888D02*
X-4259D01*
G01X-9844Y1578046D02*
X-6694D01*
G01X-1970Y1578124D02*
X-1D01*
G01Y1579148D02*
X-1970D01*
G01X-6694Y1579227D02*
X-9844D01*
G01X-4259Y1579384D02*
X-4725D01*
G01X-2197Y1579542D02*
X-3151D01*
G01X-4725Y1579817D02*
X-6694D01*
G01X15077Y1579935D02*
X8523D01*
G01D02*
X-1D01*
G01D02*
X-985D01*
G01Y1581274D02*
X-1D01*
G01D02*
X8523D01*
G01D02*
X12600D01*
G01X-4725Y1581392D02*
X-6694D01*
G01X-3151Y1581668D02*
X-2197D01*
G01X-4725Y1581825D02*
X-4259D01*
G01X-9844Y1581983D02*
X-6694D01*
G01X-1970Y1582061D02*
X-1D01*
G01Y1583085D02*
X-1970D01*
G01X-6694Y1583164D02*
X-9844D01*
G01X-4259Y1583321D02*
X-4725D01*
G01X-2197Y1583479D02*
X-3151D01*
G01X-4725Y1583754D02*
X-6694D01*
G01X15077Y1583872D02*
X8523D01*
G01D02*
X-1D01*
G01D02*
X-985D01*
G01Y1585211D02*
X-1D01*
G01D02*
X8523D01*
G01D02*
X12600D01*
G01X-4725Y1585329D02*
X-6694D01*
G01X-3151Y1585605D02*
X-2197D01*
G01X-4725Y1585762D02*
X-4259D01*
G01X-9844Y1585920D02*
X-6694D01*
G01X-1970Y1585998D02*
X-1D01*
G01Y1587022D02*
X-1970D01*
G01X-6694Y1587101D02*
X-9844D01*
G01X-4259Y1587258D02*
X-4725D01*
G01X-2197Y1587416D02*
X-3151D01*
G01X-4725Y1587691D02*
X-6694D01*
G01X15077Y1587809D02*
X8523D01*
G01D02*
X-1D01*
G01D02*
X-985D01*
G01Y1589148D02*
X-1D01*
G01D02*
X8523D01*
G01D02*
X12600D01*
G01X-4725Y1589266D02*
X-6694D01*
G01X-3151Y1589542D02*
X-2197D01*
G01X-4725Y1589699D02*
X-4259D01*
G01X-9844Y1589857D02*
X-6694D01*
G01X-1970Y1589935D02*
X-1D01*
G01X-3378Y1574187D02*
X-4259Y1573951D01*
G01X-6694Y1574109D02*
X-4725Y1574424D01*
G01X-6694Y1578046D02*
X-4725Y1578361D01*
G01X-6694Y1581983D02*
X-4725Y1582298D01*
G01X-6694Y1585920D02*
X-4725Y1586235D01*
G01X-6694Y1589857D02*
X-4725Y1590172D01*
G01X-3378Y1578124D02*
X-4259Y1577888D01*
G01X-3378Y1582061D02*
X-4259Y1581825D01*
G01X-3378Y1585998D02*
X-4259Y1585762D01*
G01X-3378Y1589935D02*
X-4259Y1589699D01*
G01X-1970Y1609620D02*
X-2197Y1609227D01*
G01X-3378Y1606707D02*
X-3151Y1607101D01*
G01X-1970Y1605683D02*
X-2197Y1605290D01*
G01X-3378Y1602770D02*
X-3151Y1603164D01*
G01X-1970Y1601746D02*
X-2197Y1601353D01*
G01X-3378Y1598833D02*
X-3151Y1599227D01*
G01X-1970Y1597809D02*
X-2197Y1597416D01*
G01X-3378Y1594896D02*
X-3151Y1595290D01*
G01X-9844Y1609542D02*
X-10631Y1609187D01*
G01X-9844Y1605605D02*
X-10631Y1605250D01*
G01X-9844Y1601668D02*
X-10631Y1601313D01*
G01X-9844Y1597731D02*
X-10631Y1597376D01*
G01X-9844Y1593794D02*
X-10631Y1593439D01*
G01X-1970Y1593872D02*
X-2197Y1593479D01*
G01X-3378Y1590959D02*
X-3151Y1591353D01*
G01X-10531Y1609232D02*
Y1607095D01*
G01Y1605295D02*
Y1603158D01*
G01Y1601358D02*
Y1599221D01*
G01Y1593484D02*
Y1591347D01*
G01Y1597421D02*
Y1595284D01*
G01X-6694Y1609542D02*
Y1608951D01*
G01Y1607376D02*
Y1606786D01*
G01Y1605605D02*
Y1605014D01*
G01Y1603439D02*
Y1602849D01*
G01Y1601668D02*
Y1601077D01*
G01Y1599502D02*
Y1598912D01*
G01Y1597731D02*
Y1597140D01*
G01Y1593794D02*
Y1593203D01*
G01Y1595565D02*
Y1594975D01*
G01Y1591628D02*
Y1591038D01*
G01X-4725Y1609857D02*
Y1608951D01*
G01Y1611313D02*
Y1610408D01*
G01Y1605920D02*
Y1605014D01*
G01Y1603439D02*
Y1602534D01*
G01Y1607376D02*
Y1606471D01*
G01Y1601983D02*
Y1601077D01*
G01Y1599502D02*
Y1598597D01*
G01Y1598046D02*
Y1597140D01*
G01Y1594109D02*
Y1593203D01*
G01Y1595565D02*
Y1594660D01*
G01Y1591628D02*
Y1590723D01*
G01X-3757Y1609266D02*
Y1607061D01*
G01Y1605329D02*
Y1603124D01*
G01Y1601392D02*
Y1599187D01*
G01Y1593518D02*
Y1591313D01*
G01Y1597455D02*
Y1595250D01*
G01X-2521Y1609266D02*
Y1607061D01*
G01Y1605329D02*
Y1603124D01*
G01Y1601392D02*
Y1599187D01*
G01Y1593518D02*
Y1591313D01*
G01Y1597455D02*
Y1595250D01*
G01X-2251Y1609581D02*
Y1606746D01*
G01Y1605644D02*
Y1602809D01*
G01Y1601707D02*
Y1598872D01*
G01Y1597770D02*
Y1594935D01*
G01Y1593833D02*
Y1590998D01*
G01X-985Y1608833D02*
Y1607494D01*
G01Y1604896D02*
Y1603557D01*
G01Y1600959D02*
Y1599620D01*
G01Y1593085D02*
Y1591746D01*
G01Y1597022D02*
Y1595683D01*
G01X8523Y1608833D02*
Y1607494D01*
G01Y1604896D02*
Y1603557D01*
G01Y1600959D02*
Y1599620D01*
G01Y1593085D02*
Y1591746D01*
G01Y1597022D02*
Y1595683D01*
G01X-2197Y1591353D02*
X-1970Y1590959D01*
G01X-3151Y1593479D02*
X-3378Y1593872D01*
G01X-2197Y1595290D02*
X-1970Y1594896D01*
G01X-3151Y1597416D02*
X-3378Y1597809D01*
G01X-2197Y1599227D02*
X-1970Y1598833D01*
G01X-3151Y1601353D02*
X-3378Y1601746D01*
G01X-2197Y1603164D02*
X-1970Y1602770D01*
G01X-3151Y1605290D02*
X-3378Y1605683D01*
G01X-2197Y1607101D02*
X-1970Y1606707D01*
G01X-3151Y1609227D02*
X-3378Y1609620D01*
G01X-10631Y1591392D02*
X-9844Y1591038D01*
G01X-10631Y1595329D02*
X-9844Y1594975D01*
G01X-10631Y1599266D02*
X-9844Y1598912D01*
G01X-10631Y1603203D02*
X-9844Y1602849D01*
G01X-10631Y1607140D02*
X-9844Y1606786D01*
G01X-4259Y1591195D02*
X-3378Y1590959D01*
G01X-4259Y1595132D02*
X-3378Y1594896D01*
G01X-4259Y1599069D02*
X-3378Y1598833D01*
G01X-4259Y1603006D02*
X-3378Y1602770D01*
G01X-4259Y1606943D02*
X-3378Y1606707D01*
G01X-4725Y1590723D02*
X-6694Y1591038D01*
G01X-4725Y1594660D02*
X-6694Y1594975D01*
G01X-4725Y1598597D02*
X-6694Y1598912D01*
G01X-4725Y1602534D02*
X-6694Y1602849D01*
G01X-4725Y1606471D02*
X-6694Y1606786D01*
G01X-4725Y1610408D02*
X-6694Y1610723D01*
G01X-1Y1590959D02*
X-1970D01*
G01X-6694Y1591038D02*
X-9844D01*
G01X-4259Y1591195D02*
X-4725D01*
G01X-2197Y1591353D02*
X-3151D01*
G01X-4725Y1591628D02*
X-6694D01*
G01X15077Y1591746D02*
X8523D01*
G01D02*
X-1D01*
G01D02*
X-985D01*
G01Y1593085D02*
X-1D01*
G01D02*
X8523D01*
G01D02*
X12600D01*
G01X-4725Y1593203D02*
X-6694D01*
G01X-3151Y1593479D02*
X-2197D01*
G01X-4725Y1593636D02*
X-4259D01*
G01X-9844Y1593794D02*
X-6694D01*
G01X-1970Y1593872D02*
X-1D01*
G01Y1594896D02*
X-1970D01*
G01X-6694Y1594975D02*
X-9844D01*
G01X-4259Y1595132D02*
X-4725D01*
G01X-2197Y1595290D02*
X-3151D01*
G01X-4725Y1595565D02*
X-6694D01*
G01X15077Y1595683D02*
X8523D01*
G01D02*
X-1D01*
G01D02*
X-985D01*
G01Y1597022D02*
X-1D01*
G01D02*
X8523D01*
G01D02*
X12600D01*
G01X-4725Y1597140D02*
X-6694D01*
G01X-3151Y1597416D02*
X-2197D01*
G01X-4725Y1597573D02*
X-4259D01*
G01X-9844Y1597731D02*
X-6694D01*
G01X-1970Y1597809D02*
X-1D01*
G01Y1598833D02*
X-1970D01*
G01X-6694Y1598912D02*
X-9844D01*
G01X-4259Y1599069D02*
X-4725D01*
G01X-2197Y1599227D02*
X-3151D01*
G01X-4725Y1599502D02*
X-6694D01*
G01X15077Y1599620D02*
X8523D01*
G01D02*
X-1D01*
G01D02*
X-985D01*
G01Y1600959D02*
X-1D01*
G01D02*
X8523D01*
G01D02*
X12600D01*
G01X-4725Y1601077D02*
X-6694D01*
G01X-3151Y1601353D02*
X-2197D01*
G01X-4725Y1601510D02*
X-4259D01*
G01X-9844Y1601668D02*
X-6694D01*
G01X-1970Y1601746D02*
X-1D01*
G01Y1602770D02*
X-1970D01*
G01X-6694Y1602849D02*
X-9844D01*
G01X-4259Y1603006D02*
X-4725D01*
G01X-2197Y1603164D02*
X-3151D01*
G01X-4725Y1603439D02*
X-6694D01*
G01X15077Y1603557D02*
X8523D01*
G01D02*
X-1D01*
G01D02*
X-985D01*
G01Y1604896D02*
X-1D01*
G01D02*
X8523D01*
G01D02*
X12600D01*
G01X-4725Y1605014D02*
X-6694D01*
G01X-3151Y1605290D02*
X-2197D01*
G01X-4725Y1605447D02*
X-4259D01*
G01X-9844Y1605605D02*
X-6694D01*
G01X-1970Y1605683D02*
X-1D01*
G01Y1606707D02*
X-1970D01*
G01X-6694Y1606786D02*
X-9844D01*
G01X-4259Y1606943D02*
X-4725D01*
G01X-2197Y1607101D02*
X-3151D01*
G01X-4725Y1607376D02*
X-6694D01*
G01X15077Y1607494D02*
X8523D01*
G01D02*
X-1D01*
G01D02*
X-985D01*
G01Y1608833D02*
X-1D01*
G01D02*
X8523D01*
G01D02*
X12600D01*
G01X-4725Y1608951D02*
X-6694D01*
G01X-3151Y1609227D02*
X-2197D01*
G01X-4725Y1609384D02*
X-4259D01*
G01X-9844Y1609542D02*
X-6694D01*
G01X-1970Y1609620D02*
X-1D01*
G01X-6694Y1593794D02*
X-4725Y1594109D01*
G01X-6694Y1597731D02*
X-4725Y1598046D01*
G01X-6694Y1601668D02*
X-4725Y1601983D01*
G01X-6694Y1605605D02*
X-4725Y1605920D01*
G01X-6694Y1609542D02*
X-4725Y1609857D01*
G01X-3378Y1593872D02*
X-4259Y1593636D01*
G01X-3378Y1597809D02*
X-4259Y1597573D01*
G01X-3378Y1601746D02*
X-4259Y1601510D01*
G01X-3378Y1605683D02*
X-4259Y1605447D01*
G01X-3378Y1609620D02*
X-4259Y1609384D01*
G01X-3378Y1630329D02*
X-3151Y1630723D01*
G01X-1970Y1629306D02*
X-2197Y1628912D01*
G01X-3378Y1626392D02*
X-3151Y1626786D01*
G01X-1970Y1625369D02*
X-2197Y1624975D01*
G01X-3378Y1622455D02*
X-3151Y1622849D01*
G01X-1970Y1621431D02*
X-2197Y1621038D01*
G01X-3378Y1618518D02*
X-3151Y1618912D01*
G01X-1970Y1617494D02*
X-2197Y1617101D01*
G01X-3378Y1614581D02*
X-3151Y1614975D01*
G01X-1970Y1613557D02*
X-2197Y1613164D01*
G01X-3378Y1610644D02*
X-3151Y1611038D01*
G01X-9844Y1629227D02*
X-10631Y1628872D01*
G01X-9844Y1625290D02*
X-10631Y1624935D01*
G01X-9844Y1621353D02*
X-10631Y1620998D01*
G01X-9844Y1617416D02*
X-10631Y1617061D01*
G01X-9844Y1613479D02*
X-10631Y1613124D01*
G01X-10531Y1628917D02*
Y1626780D01*
G01Y1621043D02*
Y1618906D01*
G01Y1624980D02*
Y1622843D01*
G01Y1617106D02*
Y1614969D01*
G01Y1613169D02*
Y1611032D01*
G01X-6694Y1630998D02*
Y1630408D01*
G01Y1629227D02*
Y1628636D01*
G01Y1627061D02*
Y1626471D01*
G01Y1625290D02*
Y1624699D01*
G01Y1623124D02*
Y1622534D01*
G01Y1621353D02*
Y1620762D01*
G01Y1619187D02*
Y1618597D01*
G01Y1617416D02*
Y1616825D01*
G01Y1615250D02*
Y1614660D01*
G01Y1613479D02*
Y1612888D01*
G01Y1611313D02*
Y1610723D01*
G01X-4725Y1630998D02*
Y1630093D01*
G01Y1629542D02*
Y1628636D01*
G01Y1627061D02*
Y1626156D01*
G01Y1621668D02*
Y1620762D01*
G01Y1625605D02*
Y1624699D01*
G01Y1623124D02*
Y1622219D01*
G01Y1617731D02*
Y1616825D01*
G01Y1619187D02*
Y1618282D01*
G01Y1613794D02*
Y1612888D01*
G01Y1615250D02*
Y1614345D01*
G01X-3757Y1628951D02*
Y1626746D01*
G01Y1625014D02*
Y1622809D01*
G01Y1621077D02*
Y1618872D01*
G01Y1617140D02*
Y1614935D01*
G01Y1613203D02*
Y1610998D01*
G01X-2521Y1628951D02*
Y1626746D01*
G01Y1621077D02*
Y1618872D01*
G01Y1625014D02*
Y1622809D01*
G01Y1617140D02*
Y1614935D01*
G01Y1613203D02*
Y1610998D01*
G01X-2251Y1633203D02*
Y1630369D01*
G01Y1629266D02*
Y1626431D01*
G01Y1625329D02*
Y1622494D01*
G01Y1621392D02*
Y1618557D01*
G01Y1617455D02*
Y1614620D01*
G01Y1613518D02*
Y1610683D01*
G01X-985Y1628518D02*
Y1627180D01*
G01Y1624581D02*
Y1623243D01*
G01Y1616707D02*
Y1615369D01*
G01Y1620644D02*
Y1619306D01*
G01Y1612770D02*
Y1611431D01*
G01X8523Y1628518D02*
Y1627180D01*
G01Y1624581D02*
Y1623243D01*
G01Y1620644D02*
Y1619306D01*
G01Y1616707D02*
Y1615369D01*
G01Y1612770D02*
Y1611431D01*
G01X-2197Y1611038D02*
X-1970Y1610644D01*
G01X-3151Y1613164D02*
X-3378Y1613557D01*
G01X-2197Y1614975D02*
X-1970Y1614581D01*
G01X-3151Y1617101D02*
X-3378Y1617494D01*
G01X-2197Y1618912D02*
X-1970Y1618518D01*
G01X-3151Y1621038D02*
X-3378Y1621431D01*
G01X-2197Y1622849D02*
X-1970Y1622455D01*
G01X-3151Y1624975D02*
X-3378Y1625369D01*
G01X-2197Y1626786D02*
X-1970Y1626392D01*
G01X-3151Y1628912D02*
X-3378Y1629306D01*
G01X-2197Y1630723D02*
X-1970Y1630329D01*
G01X-10631Y1611077D02*
X-9844Y1610723D01*
G01X-10631Y1615014D02*
X-9844Y1614660D01*
G01X-10631Y1618951D02*
X-9844Y1618597D01*
G01X-10631Y1622888D02*
X-9844Y1622534D01*
G01X-10631Y1626825D02*
X-9844Y1626471D01*
G01X-10631Y1630762D02*
X-9844Y1630408D01*
G01X-4259Y1610880D02*
X-3378Y1610644D01*
G01X-4259Y1614817D02*
X-3378Y1614581D01*
G01X-4259Y1618754D02*
X-3378Y1618518D01*
G01X-4725Y1614345D02*
X-6694Y1614660D01*
G01X-4725Y1618282D02*
X-6694Y1618597D01*
G01X-4725Y1622219D02*
X-6694Y1622534D01*
G01X-4725Y1626156D02*
X-6694Y1626471D01*
G01X-4725Y1630093D02*
X-6694Y1630408D01*
G01X-4259Y1622691D02*
X-3378Y1622455D01*
G01X-4259Y1626628D02*
X-3378Y1626392D01*
G01X-4259Y1630565D02*
X-3378Y1630329D01*
G01X-1Y1610644D02*
X-1970D01*
G01X-6694Y1610723D02*
X-9844D01*
G01X-4259Y1610880D02*
X-4725D01*
G01X-2197Y1611038D02*
X-3151D01*
G01X-4725Y1611313D02*
X-6694D01*
G01X15077Y1611431D02*
X8523D01*
G01D02*
X-1D01*
G01D02*
X-985D01*
G01Y1612770D02*
X-1D01*
G01D02*
X8523D01*
G01D02*
X12600D01*
G01X-4725Y1612888D02*
X-6694D01*
G01X-3151Y1613164D02*
X-2197D01*
G01X-4725Y1613321D02*
X-4259D01*
G01X-9844Y1613479D02*
X-6694D01*
G01X-1970Y1613557D02*
X-1D01*
G01Y1614581D02*
X-1970D01*
G01X-6694Y1614660D02*
X-9844D01*
G01X-4259Y1614817D02*
X-4725D01*
G01X-2197Y1614975D02*
X-3151D01*
G01X-4725Y1615250D02*
X-6694D01*
G01X15077Y1615369D02*
X8523D01*
G01D02*
X-1D01*
G01D02*
X-985D01*
G01X-6694Y1613479D02*
X-4725Y1613794D01*
G01X-985Y1616707D02*
X-1D01*
G01D02*
X8523D01*
G01D02*
X12600D01*
G01X-4725Y1616825D02*
X-6694D01*
G01X-3151Y1617101D02*
X-2197D01*
G01X-4725Y1617258D02*
X-4259D01*
G01X-9844Y1617416D02*
X-6694D01*
G01X-1970Y1617494D02*
X-1D01*
G01Y1618518D02*
X-1970D01*
G01X-6694Y1618597D02*
X-9844D01*
G01X-4259Y1618754D02*
X-4725D01*
G01X-2197Y1618912D02*
X-3151D01*
G01X-4725Y1619187D02*
X-6694D01*
G01X15077Y1619306D02*
X8523D01*
G01D02*
X-1D01*
G01D02*
X-985D01*
G01Y1620644D02*
X-1D01*
G01D02*
X8523D01*
G01D02*
X12600D01*
G01X-4725Y1620762D02*
X-6694D01*
G01X-3151Y1621038D02*
X-2197D01*
G01X-4725Y1621195D02*
X-4259D01*
G01X-9844Y1621353D02*
X-6694D01*
G01X-1970Y1621431D02*
X-1D01*
G01Y1622455D02*
X-1970D01*
G01X-6694Y1622534D02*
X-9844D01*
G01X-4259Y1622691D02*
X-4725D01*
G01X-2197Y1622849D02*
X-3151D01*
G01X-4725Y1623124D02*
X-6694D01*
G01X15077Y1623243D02*
X8523D01*
G01D02*
X-1D01*
G01D02*
X-985D01*
G01Y1624581D02*
X-1D01*
G01D02*
X8523D01*
G01D02*
X12600D01*
G01X-4725Y1624699D02*
X-6694D01*
G01X-3151Y1624975D02*
X-2197D01*
G01X-4725Y1625132D02*
X-4259D01*
G01X-9844Y1625290D02*
X-6694D01*
G01X-1970Y1625369D02*
X-1D01*
G01Y1626392D02*
X-1970D01*
G01X-6694Y1626471D02*
X-9844D01*
G01X-4259Y1626628D02*
X-4725D01*
G01X-2197Y1626786D02*
X-3151D01*
G01X-4725Y1627061D02*
X-6694D01*
G01X15077Y1627180D02*
X8523D01*
G01D02*
X-1D01*
G01D02*
X-985D01*
G01Y1628518D02*
X-1D01*
G01D02*
X8523D01*
G01D02*
X12600D01*
G01X-4725Y1628636D02*
X-6694D01*
G01X-3151Y1628912D02*
X-2197D01*
G01X-4725Y1629069D02*
X-4259D01*
G01X-9844Y1629227D02*
X-6694D01*
G01X-1970Y1629306D02*
X-1D01*
G01Y1630329D02*
X-1970D01*
G01X-6694Y1630408D02*
X-9844D01*
G01X-4259Y1630565D02*
X-4725D01*
G01X-3378Y1613557D02*
X-4259Y1613321D01*
G01X-3378Y1617494D02*
X-4259Y1617258D01*
G01X-3378Y1621431D02*
X-4259Y1621195D01*
G01X-3378Y1625369D02*
X-4259Y1625132D01*
G01X-3378Y1629306D02*
X-4259Y1629069D01*
G01X-6694Y1617416D02*
X-4725Y1617731D01*
G01X-6694Y1621353D02*
X-4725Y1621668D01*
G01X-6694Y1625290D02*
X-4725Y1625605D01*
G01X-6694Y1629227D02*
X-4725Y1629542D01*
G01X-3378Y1638203D02*
X-3151Y1638597D01*
G01X-1970Y1637180D02*
X-2197Y1636786D01*
G01X-3378Y1634266D02*
X-3151Y1634660D01*
G01X-1970Y1633243D02*
X-2197Y1632849D01*
G01X-9844Y1637101D02*
X-10631Y1636746D01*
G01X-9844Y1633164D02*
X-10631Y1632809D01*
G01X-10531Y1640728D02*
Y1638591D01*
G01Y1636791D02*
Y1634654D01*
G01Y1632854D02*
Y1630717D01*
G01X-6694Y1638872D02*
Y1638282D01*
G01Y1637101D02*
Y1636510D01*
G01Y1634935D02*
Y1634345D01*
G01Y1633164D02*
Y1632573D01*
G01X-4725Y1637416D02*
Y1636510D01*
G01Y1638872D02*
Y1637967D01*
G01Y1633479D02*
Y1632573D01*
G01Y1634935D02*
Y1634030D01*
G01X-3757Y1640762D02*
Y1638557D01*
G01Y1636825D02*
Y1634620D01*
G01Y1632888D02*
Y1630683D01*
G01X-2521Y1640762D02*
Y1638557D01*
G01Y1636825D02*
Y1634620D01*
G01Y1632888D02*
Y1630683D01*
G01X-2251Y1641077D02*
Y1638243D01*
G01Y1637140D02*
Y1634306D01*
G01X-985Y1640329D02*
Y1638991D01*
G01Y1636392D02*
Y1635054D01*
G01Y1632455D02*
Y1631117D01*
G01X8523Y1640329D02*
Y1638991D01*
G01Y1636392D02*
Y1635054D01*
G01Y1632455D02*
Y1631117D01*
G01X-3151Y1632849D02*
X-3378Y1633243D01*
G01X-2197Y1634660D02*
X-1970Y1634266D01*
G01X-3151Y1636786D02*
X-3378Y1637180D01*
G01X-2197Y1638597D02*
X-1970Y1638203D01*
G01X-10631Y1634699D02*
X-9844Y1634345D01*
G01X-10631Y1638636D02*
X-9844Y1638282D01*
G01X-4259Y1634502D02*
X-3378Y1634266D01*
G01X-4259Y1638439D02*
X-3378Y1638203D01*
G01X-4725Y1634030D02*
X-6694Y1634345D01*
G01X-4725Y1637967D02*
X-6694Y1638282D01*
G01X-2197Y1630723D02*
X-3151D01*
G01X-4725Y1630998D02*
X-6694D01*
G01X15077Y1631117D02*
X8523D01*
G01D02*
X-1D01*
G01D02*
X-985D01*
G01Y1632455D02*
X-1D01*
G01D02*
X8523D01*
G01D02*
X12600D01*
G01X-4725Y1632573D02*
X-6694D01*
G01X-3151Y1632849D02*
X-2197D01*
G01X-4725Y1633006D02*
X-4259D01*
G01X-9844Y1633164D02*
X-6694D01*
G01X-1970Y1633243D02*
X-1D01*
G01Y1634266D02*
X-1970D01*
G01X-6694Y1634345D02*
X-9844D01*
G01X-4259Y1634502D02*
X-4725D01*
G01X-2197Y1634660D02*
X-3151D01*
G01X-4725Y1634935D02*
X-6694D01*
G01X15077Y1635054D02*
X8523D01*
G01D02*
X-1D01*
G01D02*
X-985D01*
G01Y1636392D02*
X-1D01*
G01D02*
X8523D01*
G01D02*
X12600D01*
G01X-4725Y1636510D02*
X-6694D01*
G01X-3151Y1636786D02*
X-2197D01*
G01X-4725Y1636943D02*
X-4259D01*
G01X-9844Y1637101D02*
X-6694D01*
G01X-1970Y1637180D02*
X-1D01*
G01Y1638203D02*
X-1970D01*
G01X-6694Y1638282D02*
X-9844D01*
G01X-4259Y1638439D02*
X-4725D01*
G01X-2197Y1638597D02*
X-3151D01*
G01X-4725Y1638872D02*
X-6694D01*
G01X15077Y1638991D02*
X8523D01*
G01D02*
X-1D01*
G01D02*
X-985D01*
G01X-3378Y1633243D02*
X-4259Y1633006D01*
G01X-3378Y1637180D02*
X-4259Y1636943D01*
G01X-6694Y1633164D02*
X-4725Y1633479D01*
G01X-6694Y1637101D02*
X-4725Y1637416D01*
G01X-38426Y1652652D02*
Y1650290D01*
G01Y1644778D02*
Y1642416D01*
G01Y1648715D02*
Y1646353D01*
G01X-38108Y1648016D02*
Y1647051D01*
G01Y1644079D02*
Y1643114D01*
G01X-37871Y1648039D02*
Y1647028D01*
G01Y1644102D02*
Y1643091D01*
G01X-35595Y1652195D02*
Y1650746D01*
G01Y1648258D02*
Y1646809D01*
G01Y1644321D02*
Y1642872D01*
G01X-35546Y1652652D02*
Y1650290D01*
G01Y1648715D02*
Y1646353D01*
G01Y1644778D02*
Y1642416D01*
G01X-35357Y1652218D02*
Y1650723D01*
G01Y1648281D02*
Y1646786D01*
G01Y1644344D02*
Y1642849D01*
G01X-34607Y1652573D02*
Y1650369D01*
G01Y1644699D02*
Y1642494D01*
G01Y1648636D02*
Y1646431D01*
G01X-34136Y1652232D02*
Y1650709D01*
G01Y1648295D02*
Y1646772D01*
G01Y1644358D02*
Y1642835D01*
G01X-33153Y1652243D02*
Y1650698D01*
G01Y1648306D02*
Y1646761D01*
G01Y1644369D02*
Y1642824D01*
G01X-32319Y1652252D02*
Y1650689D01*
G01Y1648315D02*
Y1646752D01*
G01Y1644378D02*
Y1642815D01*
G01X-31941Y1652257D02*
Y1650685D01*
G01Y1648320D02*
Y1646748D01*
G01Y1644383D02*
Y1642811D01*
G01X-38108Y1643114D02*
X-35351Y1642849D01*
G01X-38108Y1647051D02*
X-35351Y1646786D01*
G01X-38108Y1650988D02*
X-35351Y1650723D01*
G01Y1640408D02*
X-38108Y1640142D01*
G01X-35351Y1640408D02*
X-10631Y1640683D01*
G01X-35351Y1644345D02*
X-10631Y1644620D01*
G01X-35351Y1648282D02*
X-10631Y1648557D01*
G01X-35546Y1640762D02*
X-1D01*
G01X-24509Y1640841D02*
X-39607D01*
G01Y1642416D02*
X-24509D01*
G01X-35546Y1642494D02*
X-1D01*
G01X-27993Y1644483D02*
X-39607D01*
G01X-35546Y1644699D02*
X-1D01*
G01X-24509Y1644778D02*
X-39607D01*
G01Y1646353D02*
X-24509D01*
G01X-35546Y1646431D02*
X-1D01*
G01X-39607Y1647632D02*
X-24844D01*
G01X-35546Y1648636D02*
X-1D01*
G01X-24509Y1648715D02*
X-39607D01*
G01Y1650290D02*
X-24509D01*
G01X-35546Y1650369D02*
X-1D01*
G01X-10631Y1642573D02*
X-35351Y1642849D01*
G01X-10631Y1646510D02*
X-35351Y1646786D01*
G01X-10631Y1650447D02*
X-35351Y1650723D01*
G01Y1644345D02*
X-38108Y1644079D01*
G01X-35351Y1648282D02*
X-38108Y1648016D01*
G01X-38426Y1668400D02*
Y1666038D01*
G01Y1672337D02*
Y1669975D01*
G01Y1664463D02*
Y1662101D01*
G01Y1660526D02*
Y1658164D01*
G01Y1656589D02*
Y1654227D01*
G01X-38108Y1671638D02*
Y1670673D01*
G01Y1667701D02*
Y1666736D01*
G01Y1663764D02*
Y1662799D01*
G01Y1659827D02*
Y1658862D01*
G01Y1655890D02*
Y1654925D01*
G01Y1651953D02*
Y1650988D01*
G01X-37871Y1671661D02*
Y1670650D01*
G01Y1663787D02*
Y1662776D01*
G01Y1667724D02*
Y1666713D01*
G01Y1659850D02*
Y1658839D01*
G01Y1655913D02*
Y1654902D01*
G01Y1651976D02*
Y1650965D01*
G01X-35595Y1671880D02*
Y1670431D01*
G01Y1667943D02*
Y1666494D01*
G01Y1664006D02*
Y1662557D01*
G01Y1660069D02*
Y1658620D01*
G01Y1656132D02*
Y1654683D01*
G01X-35546Y1672337D02*
Y1669975D01*
G01Y1668400D02*
Y1666038D01*
G01Y1664463D02*
Y1662101D01*
G01Y1660526D02*
Y1658164D01*
G01Y1656589D02*
Y1654227D01*
G01X-35357Y1667966D02*
Y1666471D01*
G01Y1671903D02*
Y1670408D01*
G01Y1664029D02*
Y1662534D01*
G01Y1660092D02*
Y1658597D01*
G01Y1656155D02*
Y1654660D01*
G01X-34607Y1668321D02*
Y1666117D01*
G01Y1672258D02*
Y1670054D01*
G01Y1664384D02*
Y1662180D01*
G01Y1660447D02*
Y1658243D01*
G01Y1656510D02*
Y1654306D01*
G01X-34136Y1667980D02*
Y1666457D01*
G01Y1671917D02*
Y1670394D01*
G01Y1664043D02*
Y1662520D01*
G01Y1660106D02*
Y1658583D01*
G01Y1656169D02*
Y1654646D01*
G01X-33153Y1671928D02*
Y1670383D01*
G01Y1667991D02*
Y1666446D01*
G01Y1664054D02*
Y1662509D01*
G01Y1660117D02*
Y1658572D01*
G01Y1656180D02*
Y1654635D01*
G01X-32319Y1668000D02*
Y1666437D01*
G01Y1671937D02*
Y1670374D01*
G01Y1664063D02*
Y1662500D01*
G01Y1660126D02*
Y1658563D01*
G01Y1656189D02*
Y1654626D01*
G01X-31941Y1668005D02*
Y1666433D01*
G01Y1671942D02*
Y1670370D01*
G01Y1664068D02*
Y1662496D01*
G01Y1660131D02*
Y1658559D01*
G01Y1656194D02*
Y1654622D01*
G01X-38108Y1654925D02*
X-35351Y1654660D01*
G01X-38108Y1658862D02*
X-35351Y1658597D01*
G01X-38108Y1662799D02*
X-35351Y1662534D01*
G01X-38108Y1666736D02*
X-35351Y1666471D01*
G01X-38108Y1670673D02*
X-35351Y1670408D01*
G01Y1652219D02*
X-10631Y1652494D01*
G01X-35351Y1656156D02*
X-10631Y1656431D01*
G01X-35351Y1660093D02*
X-10631Y1660369D01*
G01X-35351Y1664030D02*
X-10631Y1664306D01*
G01X-35351Y1667967D02*
X-10631Y1668243D01*
G01X-39607Y1651609D02*
X-24844D01*
G01X-35546Y1652573D02*
X-1D01*
G01X-24509Y1652652D02*
X-39607D01*
G01Y1654227D02*
X-24509D01*
G01X-35546Y1654306D02*
X-1D01*
G01X-39607Y1654758D02*
X-27993D01*
G01X-35546Y1656510D02*
X-1D01*
G01X-24509Y1656589D02*
X-39607D01*
G01Y1658164D02*
X-24509D01*
G01X-35546Y1658243D02*
X-1D01*
G01X-35546Y1660447D02*
X-1D01*
G01X-24509Y1660526D02*
X-39607D01*
G01Y1662101D02*
X-24509D01*
G01X-35546Y1662180D02*
X-1D01*
G01X-35546Y1664384D02*
X-1D01*
G01X-24509Y1664463D02*
X-39607D01*
G01Y1666038D02*
X-24509D01*
G01X-35546Y1666117D02*
X-1D01*
G01X-27993Y1668105D02*
X-39607D01*
G01X-35546Y1668321D02*
X-1D01*
G01X-24509Y1668400D02*
X-39607D01*
G01Y1669975D02*
X-24509D01*
G01X-35546Y1670054D02*
X-1D01*
G01X-10631Y1654384D02*
X-35351Y1654660D01*
G01X-10631Y1658321D02*
X-35351Y1658597D01*
G01X-10631Y1662258D02*
X-35351Y1662534D01*
G01X-10631Y1666195D02*
X-35351Y1666471D01*
G01X-10631Y1670132D02*
X-35351Y1670408D01*
G01Y1652219D02*
X-38108Y1651953D01*
G01X-35351Y1656156D02*
X-38108Y1655890D01*
G01X-35351Y1660093D02*
X-38108Y1659827D01*
G01X-35351Y1664030D02*
X-38108Y1663764D01*
G01X-35351Y1667967D02*
X-38108Y1667701D01*
G01X-38426Y1684148D02*
Y1681786D01*
G01Y1680211D02*
Y1677849D01*
G01Y1676274D02*
Y1673912D01*
G01X-38108Y1683449D02*
Y1682484D01*
G01Y1679512D02*
Y1678547D01*
G01Y1675575D02*
Y1674610D01*
G01X-37871Y1683472D02*
Y1682461D01*
G01Y1679535D02*
Y1678524D01*
G01Y1675598D02*
Y1674587D01*
G01X-35595Y1683691D02*
Y1682242D01*
G01Y1679754D02*
Y1678305D01*
G01Y1675817D02*
Y1674368D01*
G01X-35546Y1680211D02*
Y1677849D01*
G01Y1684148D02*
Y1681786D01*
G01Y1676274D02*
Y1673912D01*
G01X-35357Y1683714D02*
Y1682219D01*
G01Y1679777D02*
Y1678282D01*
G01Y1675840D02*
Y1674345D01*
G01X-34607Y1684069D02*
Y1681865D01*
G01Y1680132D02*
Y1677928D01*
G01Y1676195D02*
Y1673991D01*
G01X-34136Y1683728D02*
Y1682205D01*
G01Y1679791D02*
Y1678268D01*
G01Y1675854D02*
Y1674331D01*
G01X-33153Y1683739D02*
Y1682194D01*
G01Y1679802D02*
Y1678257D01*
G01Y1675865D02*
Y1674320D01*
G01X-32319Y1683748D02*
Y1682185D01*
G01Y1679811D02*
Y1678248D01*
G01Y1675874D02*
Y1674311D01*
G01X-31941Y1683753D02*
Y1682181D01*
G01Y1679816D02*
Y1678244D01*
G01Y1675879D02*
Y1674307D01*
G01X-36561Y1687740D02*
X-39607Y1689873D01*
G01X-35351Y1671904D02*
X-10631Y1672180D01*
G01X-35351Y1675841D02*
X-10631Y1676117D01*
G01X-35351Y1679778D02*
X-10631Y1680054D01*
G01X-35351Y1683715D02*
X-10631Y1683991D01*
G01X-39607Y1671254D02*
X-24844D01*
G01X-35546Y1672258D02*
X-1D01*
G01X-24509Y1672337D02*
X-39607D01*
G01Y1673912D02*
X-24509D01*
G01X-35546Y1673991D02*
X-1D01*
G01X-39607Y1675231D02*
X-24844D01*
G01X-35546Y1676195D02*
X-1D01*
G01X-24509Y1676274D02*
X-39607D01*
G01Y1677849D02*
X-24509D01*
G01X-35546Y1677928D02*
X-1D01*
G01X-39607Y1678380D02*
X-27993D01*
G01X-35546Y1680132D02*
X-1D01*
G01X-24509Y1680211D02*
X-39607D01*
G01Y1681786D02*
X-24509D01*
G01X-35546Y1681865D02*
X-1D01*
G01X-35546Y1684069D02*
X-1D01*
G01X-24509Y1684148D02*
X-39607D01*
G01X-8899Y1687199D02*
X-34845D01*
G01X-10631Y1674069D02*
X-35351Y1674345D01*
G01X-10631Y1678006D02*
X-35351Y1678282D01*
G01X-10631Y1681943D02*
X-35351Y1682219D01*
G01X-38108Y1674610D02*
X-35351Y1674345D01*
G01X-38108Y1678547D02*
X-35351Y1678282D01*
G01X-38108Y1682484D02*
X-35351Y1682219D01*
G01Y1671904D02*
X-38108Y1671638D01*
G01X-35351Y1675841D02*
X-38108Y1675575D01*
G01X-35351Y1679778D02*
X-38108Y1679512D01*
G01X-35351Y1683715D02*
X-38108Y1683449D01*
G01X-36561Y1687740D02*
G03X-34845Y1687199I1716J2451D01*
G01X-27993Y1691727D02*
X-39607D01*
G01Y1694876D02*
X-1D01*
G01X-27265Y1652652D02*
Y1650290D01*
G01Y1648715D02*
Y1646353D01*
G01Y1644778D02*
Y1642416D01*
G01X-26943Y1652313D02*
Y1650629D01*
G01Y1648376D02*
Y1646692D01*
G01Y1644439D02*
Y1642755D01*
G01X-26566Y1652317D02*
Y1650625D01*
G01Y1648380D02*
Y1646688D01*
G01Y1644443D02*
Y1642751D01*
G01X-24509Y1652652D02*
Y1650290D01*
G01Y1648715D02*
Y1646353D01*
G01Y1644778D02*
Y1642416D01*
G01X-24122Y1652344D02*
Y1650598D01*
G01Y1644470D02*
Y1642724D01*
G01Y1648407D02*
Y1646661D01*
G01X-23684Y1652349D02*
Y1650593D01*
G01Y1644475D02*
Y1642719D01*
G01Y1648412D02*
Y1646656D01*
G01X-12993Y1650369D02*
Y1650054D01*
G01Y1646431D02*
Y1646117D01*
G01Y1648951D02*
Y1648636D01*
G01Y1645014D02*
Y1644699D01*
G01Y1642494D02*
Y1642180D01*
G01Y1641077D02*
Y1640762D01*
G01X-12280Y1652476D02*
Y1650465D01*
G01Y1648539D02*
Y1646528D01*
G01Y1644602D02*
Y1642591D01*
G01X-11843Y1652481D02*
Y1650461D01*
G01Y1648544D02*
Y1646524D01*
G01Y1644607D02*
Y1642587D01*
G01X-1Y1641077D02*
X-12993D01*
G01Y1642180D02*
X-1D01*
G01Y1645014D02*
X-12993D01*
G01Y1646117D02*
X-1D01*
G01Y1648951D02*
X-12993D01*
G01Y1650054D02*
X-1D01*
G01X-27993Y1651609D02*
Y1671254D01*
G01X-27265Y1672337D02*
Y1669975D01*
G01Y1668400D02*
Y1666038D01*
G01Y1664463D02*
Y1662101D01*
G01Y1660526D02*
Y1658164D01*
G01Y1656589D02*
Y1654227D01*
G01X-26943Y1668061D02*
Y1666377D01*
G01Y1671998D02*
Y1670314D01*
G01Y1664124D02*
Y1662440D01*
G01Y1660187D02*
Y1658503D01*
G01Y1656250D02*
Y1654566D01*
G01X-26566Y1672002D02*
Y1670310D01*
G01Y1668065D02*
Y1666373D01*
G01Y1664128D02*
Y1662436D01*
G01Y1660191D02*
Y1658499D01*
G01Y1656254D02*
Y1654562D01*
G01X-24844Y1651609D02*
Y1671254D01*
G01X-24509Y1672337D02*
Y1669975D01*
G01Y1668400D02*
Y1666038D01*
G01Y1664463D02*
Y1662101D01*
G01Y1660526D02*
Y1658164D01*
G01Y1656589D02*
Y1654227D01*
G01X-24122Y1668092D02*
Y1666346D01*
G01Y1672029D02*
Y1670283D01*
G01Y1664155D02*
Y1662409D01*
G01Y1660218D02*
Y1658472D01*
G01Y1656281D02*
Y1654535D01*
G01X-23684Y1668097D02*
Y1666341D01*
G01Y1672034D02*
Y1670278D01*
G01Y1664160D02*
Y1662404D01*
G01Y1660223D02*
Y1658467D01*
G01Y1656286D02*
Y1654530D01*
G01X-12993Y1670054D02*
Y1669739D01*
G01Y1668636D02*
Y1668321D01*
G01Y1666117D02*
Y1665802D01*
G01Y1664699D02*
Y1664384D01*
G01Y1662180D02*
Y1661865D01*
G01Y1660762D02*
Y1660447D01*
G01Y1658243D02*
Y1657928D01*
G01Y1654306D02*
Y1653991D01*
G01Y1656825D02*
Y1656510D01*
G01Y1652888D02*
Y1652573D01*
G01X-12280Y1672161D02*
Y1670150D01*
G01Y1668224D02*
Y1666213D01*
G01Y1664287D02*
Y1662276D01*
G01Y1660350D02*
Y1658339D01*
G01Y1656413D02*
Y1654402D01*
G01X-11843Y1668229D02*
Y1666209D01*
G01Y1672166D02*
Y1670146D01*
G01Y1664292D02*
Y1662272D01*
G01Y1660355D02*
Y1658335D01*
G01Y1656418D02*
Y1654398D01*
G01X-1Y1652888D02*
X-12993D01*
G01Y1653991D02*
X-1D01*
G01Y1656825D02*
X-12993D01*
G01Y1657928D02*
X-1D01*
G01Y1660762D02*
X-12993D01*
G01Y1661865D02*
X-1D01*
G01Y1664699D02*
X-12993D01*
G01Y1665802D02*
X-1D01*
G01Y1668636D02*
X-12993D01*
G01Y1669739D02*
X-1D01*
G01X-27993Y1675231D02*
Y1694876D01*
G01X-27265Y1684148D02*
Y1681786D01*
G01Y1680211D02*
Y1677849D01*
G01Y1676274D02*
Y1673912D01*
G01X-26943Y1683809D02*
Y1682125D01*
G01Y1679872D02*
Y1678188D01*
G01Y1675935D02*
Y1674251D01*
G01X-26566Y1683813D02*
Y1682121D01*
G01Y1679876D02*
Y1678184D01*
G01Y1675939D02*
Y1674247D01*
G01X-24844Y1675231D02*
Y1694876D01*
G01X-24509Y1680211D02*
Y1677849D01*
G01Y1684148D02*
Y1681786D01*
G01Y1676274D02*
Y1673912D01*
G01X-24122Y1683840D02*
Y1682094D01*
G01Y1679903D02*
Y1678157D01*
G01Y1675966D02*
Y1674220D01*
G01X-23684Y1683845D02*
Y1682089D01*
G01Y1679908D02*
Y1678152D01*
G01Y1675971D02*
Y1674215D01*
G01X-12993Y1684384D02*
Y1684069D01*
G01Y1677928D02*
Y1677613D01*
G01Y1680447D02*
Y1680132D01*
G01Y1681865D02*
Y1681550D01*
G01Y1673991D02*
Y1673676D01*
G01Y1676510D02*
Y1676195D01*
G01Y1672573D02*
Y1672258D01*
G01X-12280Y1683972D02*
Y1681961D01*
G01Y1680035D02*
Y1678024D01*
G01Y1676098D02*
Y1674087D01*
G01X-11843Y1683977D02*
Y1681957D01*
G01Y1680040D02*
Y1678020D01*
G01Y1676103D02*
Y1674083D01*
G01X-1Y1672573D02*
X-12993D01*
G01Y1673676D02*
X-1D01*
G01Y1676510D02*
X-12993D01*
G01Y1677613D02*
X-1D01*
G01Y1680447D02*
X-12993D01*
G01Y1681550D02*
X-1D01*
G01Y1684384D02*
X-12993D01*
G01X-3378Y1650014D02*
X-3151Y1650408D01*
G01X-1970Y1648991D02*
X-2197Y1648597D01*
G01X-3378Y1646077D02*
X-3151Y1646471D01*
G01X-1970Y1645054D02*
X-2197Y1644660D01*
G01X-3378Y1642140D02*
X-3151Y1642534D01*
G01X-1970Y1641117D02*
X-2197Y1640723D01*
G01X-9844Y1648912D02*
X-10631Y1648557D01*
G01X-9844Y1644975D02*
X-10631Y1644620D01*
G01X-9844Y1641038D02*
X-10631Y1640683D01*
G01X-10531Y1652539D02*
Y1650402D01*
G01Y1644665D02*
Y1642528D01*
G01Y1648602D02*
Y1646465D01*
G01X-6694Y1650683D02*
Y1650093D01*
G01Y1648912D02*
Y1648321D01*
G01Y1646746D02*
Y1646156D01*
G01Y1644975D02*
Y1644384D01*
G01Y1642809D02*
Y1642219D01*
G01Y1641038D02*
Y1640447D01*
G01X-4725Y1650683D02*
Y1649778D01*
G01Y1649227D02*
Y1648321D01*
G01Y1646746D02*
Y1645841D01*
G01Y1645290D02*
Y1644384D01*
G01Y1641353D02*
Y1640447D01*
G01Y1642809D02*
Y1641904D01*
G01X-3757Y1652573D02*
Y1650369D01*
G01Y1644699D02*
Y1642494D01*
G01Y1648636D02*
Y1646431D01*
G01X-2521Y1652573D02*
Y1650369D01*
G01Y1644699D02*
Y1642494D01*
G01Y1648636D02*
Y1646431D01*
G01X-2251Y1652888D02*
Y1650054D01*
G01Y1648951D02*
Y1646117D01*
G01Y1645014D02*
Y1642180D01*
G01X-985Y1648203D02*
Y1646865D01*
G01Y1644266D02*
Y1642928D01*
G01X8523Y1648203D02*
Y1646865D01*
G01Y1644266D02*
Y1642928D01*
G01X-3151Y1640723D02*
X-3378Y1641117D01*
G01X-2197Y1642534D02*
X-1970Y1642140D01*
G01X-3151Y1644660D02*
X-3378Y1645054D01*
G01X-2197Y1646471D02*
X-1970Y1646077D01*
G01X-3151Y1648597D02*
X-3378Y1648991D01*
G01X-2197Y1650408D02*
X-1970Y1650014D01*
G01X-10631Y1642573D02*
X-9844Y1642219D01*
G01X-10631Y1646510D02*
X-9844Y1646156D01*
G01X-10631Y1650447D02*
X-9844Y1650093D01*
G01X-4259Y1642376D02*
X-3378Y1642140D01*
G01X-4259Y1646313D02*
X-3378Y1646077D01*
G01X-4259Y1650250D02*
X-3378Y1650014D01*
G01X-4725Y1641904D02*
X-6694Y1642219D01*
G01X-4725Y1645841D02*
X-6694Y1646156D01*
G01X-4725Y1649778D02*
X-6694Y1650093D01*
G01X-985Y1640329D02*
X-1D01*
G01D02*
X8523D01*
G01D02*
X12600D01*
G01X-4725Y1640447D02*
X-6694D01*
G01X-3151Y1640723D02*
X-2197D01*
G01X-4725Y1640880D02*
X-4259D01*
G01X-9844Y1641038D02*
X-6694D01*
G01X-1970Y1641117D02*
X-1D01*
G01Y1642140D02*
X-1970D01*
G01X-6694Y1642219D02*
X-9844D01*
G01X-4259Y1642376D02*
X-4725D01*
G01X-2197Y1642534D02*
X-3151D01*
G01X-4725Y1642809D02*
X-6694D01*
G01X15077Y1642928D02*
X8523D01*
G01D02*
X-1D01*
G01D02*
X-985D01*
G01Y1644266D02*
X-1D01*
G01D02*
X8523D01*
G01D02*
X12600D01*
G01X-4725Y1644384D02*
X-6694D01*
G01X-3151Y1644660D02*
X-2197D01*
G01X-4725Y1644817D02*
X-4259D01*
G01X-9844Y1644975D02*
X-6694D01*
G01X-1970Y1645054D02*
X-1D01*
G01Y1646077D02*
X-1970D01*
G01X-6694Y1646156D02*
X-9844D01*
G01X-4259Y1646313D02*
X-4725D01*
G01X-2197Y1646471D02*
X-3151D01*
G01X-4725Y1646746D02*
X-6694D01*
G01X15077Y1646865D02*
X8523D01*
G01D02*
X-1D01*
G01D02*
X-985D01*
G01Y1648203D02*
X-1D01*
G01D02*
X8523D01*
G01D02*
X12600D01*
G01X-4725Y1648321D02*
X-6694D01*
G01X-3151Y1648597D02*
X-2197D01*
G01X-4725Y1648754D02*
X-4259D01*
G01X-9844Y1648912D02*
X-6694D01*
G01X-1970Y1648991D02*
X-1D01*
G01Y1650014D02*
X-1970D01*
G01X-6694Y1650093D02*
X-9844D01*
G01X-4259Y1650250D02*
X-4725D01*
G01X-2197Y1650408D02*
X-3151D01*
G01X-4725Y1650683D02*
X-6694D01*
G01X-3378Y1641117D02*
X-4259Y1640880D01*
G01X-3378Y1645054D02*
X-4259Y1644817D01*
G01X-3378Y1648991D02*
X-4259Y1648754D01*
G01X-6694Y1641038D02*
X-4725Y1641353D01*
G01X-6694Y1644975D02*
X-4725Y1645290D01*
G01X-6694Y1648912D02*
X-4725Y1649227D01*
G01X-9844Y1668597D02*
X-10631Y1668243D01*
G01X-3378Y1669699D02*
X-3151Y1670093D01*
G01X-1970Y1668676D02*
X-2197Y1668282D01*
G01X-3378Y1665762D02*
X-3151Y1666156D01*
G01X-1970Y1664739D02*
X-2197Y1664345D01*
G01X-3378Y1661825D02*
X-3151Y1662219D01*
G01X-1970Y1660802D02*
X-2197Y1660408D01*
G01X-3378Y1657888D02*
X-3151Y1658282D01*
G01X-1970Y1656865D02*
X-2197Y1656471D01*
G01X-3378Y1653951D02*
X-3151Y1654345D01*
G01X-1970Y1652928D02*
X-2197Y1652534D01*
G01X-9844Y1664660D02*
X-10631Y1664306D01*
G01X-9844Y1660723D02*
X-10631Y1660369D01*
G01X-9844Y1656786D02*
X-10631Y1656431D01*
G01X-9844Y1652849D02*
X-10631Y1652494D01*
G01X-10531Y1668287D02*
Y1666150D01*
G01Y1672224D02*
Y1670087D01*
G01Y1664350D02*
Y1662213D01*
G01Y1660413D02*
Y1658276D01*
G01Y1656476D02*
Y1654339D01*
G01X-6694Y1668597D02*
Y1668006D01*
G01Y1670369D02*
Y1669778D01*
G01Y1666431D02*
Y1665841D01*
G01Y1664660D02*
Y1664069D01*
G01Y1662494D02*
Y1661904D01*
G01Y1660723D02*
Y1660132D01*
G01Y1658557D02*
Y1657967D01*
G01Y1656786D02*
Y1656195D01*
G01Y1654620D02*
Y1654030D01*
G01Y1652849D02*
Y1652258D01*
G01X-4725Y1670369D02*
Y1669463D01*
G01Y1668912D02*
Y1668006D01*
G01Y1666431D02*
Y1665526D01*
G01Y1664975D02*
Y1664069D01*
G01Y1661038D02*
Y1660132D01*
G01Y1662494D02*
Y1661589D01*
G01Y1657101D02*
Y1656195D01*
G01Y1654620D02*
Y1653715D01*
G01Y1658557D02*
Y1657652D01*
G01Y1653164D02*
Y1652258D01*
G01X-3757Y1668321D02*
Y1666117D01*
G01Y1672258D02*
Y1670054D01*
G01Y1664384D02*
Y1662180D01*
G01Y1660447D02*
Y1658243D01*
G01Y1656510D02*
Y1654306D01*
G01X-2521Y1668321D02*
Y1666117D01*
G01Y1672258D02*
Y1670054D01*
G01Y1664384D02*
Y1662180D01*
G01Y1660447D02*
Y1658243D01*
G01Y1656510D02*
Y1654306D01*
G01X-2251Y1672573D02*
Y1669739D01*
G01Y1668636D02*
Y1665802D01*
G01Y1664699D02*
Y1661865D01*
G01Y1660762D02*
Y1657928D01*
G01Y1656825D02*
Y1653991D01*
G01X-985Y1667888D02*
Y1666550D01*
G01Y1671825D02*
Y1670487D01*
G01Y1663951D02*
Y1662613D01*
G01Y1660014D02*
Y1658676D01*
G01Y1656077D02*
Y1654739D01*
G01Y1652140D02*
Y1650802D01*
G01X8523Y1667888D02*
Y1666550D01*
G01Y1671825D02*
Y1670487D01*
G01Y1663951D02*
Y1662613D01*
G01Y1660014D02*
Y1658676D01*
G01Y1656077D02*
Y1654739D01*
G01Y1652140D02*
Y1650802D01*
G01X-3151Y1652534D02*
X-3378Y1652928D01*
G01X-2197Y1654345D02*
X-1970Y1653951D01*
G01X-3151Y1656471D02*
X-3378Y1656865D01*
G01X-2197Y1658282D02*
X-1970Y1657888D01*
G01X-3151Y1660408D02*
X-3378Y1660802D01*
G01X-2197Y1662219D02*
X-1970Y1661825D01*
G01X-3151Y1664345D02*
X-3378Y1664739D01*
G01X-2197Y1666156D02*
X-1970Y1665762D01*
G01X-3151Y1668282D02*
X-3378Y1668676D01*
G01X-2197Y1670093D02*
X-1970Y1669699D01*
G01X-10631Y1654384D02*
X-9844Y1654030D01*
G01X-10631Y1658321D02*
X-9844Y1657967D01*
G01X-10631Y1662258D02*
X-9844Y1661904D01*
G01X-10631Y1666195D02*
X-9844Y1665841D01*
G01X-10631Y1670132D02*
X-9844Y1669778D01*
G01X-4259Y1654187D02*
X-3378Y1653951D01*
G01X-4259Y1658124D02*
X-3378Y1657888D01*
G01X-4259Y1662061D02*
X-3378Y1661825D01*
G01X-4259Y1665998D02*
X-3378Y1665762D01*
G01X-4259Y1669935D02*
X-3378Y1669699D01*
G01X-4725Y1653715D02*
X-6694Y1654030D01*
G01X-4725Y1657652D02*
X-6694Y1657967D01*
G01X-4725Y1661589D02*
X-6694Y1661904D01*
G01X-4725Y1665526D02*
X-6694Y1665841D01*
G01X-4725Y1669463D02*
X-6694Y1669778D01*
G01X15077Y1650802D02*
X8523D01*
G01D02*
X-1D01*
G01D02*
X-985D01*
G01Y1652140D02*
X-1D01*
G01D02*
X8523D01*
G01D02*
X12600D01*
G01X-4725Y1652258D02*
X-6694D01*
G01X-3151Y1652534D02*
X-2197D01*
G01X-4725Y1652691D02*
X-4259D01*
G01X-9844Y1652849D02*
X-6694D01*
G01X-1970Y1652928D02*
X-1D01*
G01Y1653951D02*
X-1970D01*
G01X-6694Y1654030D02*
X-9844D01*
G01X-4259Y1654187D02*
X-4725D01*
G01X-2197Y1654345D02*
X-3151D01*
G01X-4725Y1654620D02*
X-6694D01*
G01X15077Y1654739D02*
X8523D01*
G01D02*
X-1D01*
G01D02*
X-985D01*
G01Y1656077D02*
X-1D01*
G01D02*
X8523D01*
G01D02*
X12600D01*
G01X-4725Y1656195D02*
X-6694D01*
G01X-3151Y1656471D02*
X-2197D01*
G01X-4725Y1656628D02*
X-4259D01*
G01X-9844Y1656786D02*
X-6694D01*
G01X-1970Y1656865D02*
X-1D01*
G01Y1657888D02*
X-1970D01*
G01X-6694Y1657967D02*
X-9844D01*
G01X-4259Y1658124D02*
X-4725D01*
G01X-2197Y1658282D02*
X-3151D01*
G01X-4725Y1658557D02*
X-6694D01*
G01X15077Y1658676D02*
X8523D01*
G01D02*
X-1D01*
G01D02*
X-985D01*
G01Y1660014D02*
X-1D01*
G01D02*
X8523D01*
G01D02*
X12600D01*
G01X-4725Y1660132D02*
X-6694D01*
G01X-3151Y1660408D02*
X-2197D01*
G01X-4725Y1660565D02*
X-4259D01*
G01X-9844Y1660723D02*
X-6694D01*
G01X-1970Y1660802D02*
X-1D01*
G01Y1661825D02*
X-1970D01*
G01X-6694Y1661904D02*
X-9844D01*
G01X-4259Y1662061D02*
X-4725D01*
G01X-2197Y1662219D02*
X-3151D01*
G01X-4725Y1662494D02*
X-6694D01*
G01X15077Y1662613D02*
X8523D01*
G01D02*
X-1D01*
G01D02*
X-985D01*
G01Y1663951D02*
X-1D01*
G01D02*
X8523D01*
G01D02*
X12600D01*
G01X-4725Y1664069D02*
X-6694D01*
G01X-3151Y1664345D02*
X-2197D01*
G01X-4725Y1664502D02*
X-4259D01*
G01X-9844Y1664660D02*
X-6694D01*
G01X-1970Y1664739D02*
X-1D01*
G01Y1665762D02*
X-1970D01*
G01X-6694Y1665841D02*
X-9844D01*
G01X-4259Y1665998D02*
X-4725D01*
G01X-2197Y1666156D02*
X-3151D01*
G01X-4725Y1666431D02*
X-6694D01*
G01X15077Y1666550D02*
X8523D01*
G01D02*
X-1D01*
G01D02*
X-985D01*
G01Y1667888D02*
X-1D01*
G01D02*
X8523D01*
G01D02*
X12600D01*
G01X-4725Y1668006D02*
X-6694D01*
G01X-3151Y1668282D02*
X-2197D01*
G01X-4725Y1668439D02*
X-4259D01*
G01X-9844Y1668597D02*
X-6694D01*
G01X-1970Y1668676D02*
X-1D01*
G01Y1669699D02*
X-1970D01*
G01X-6694Y1669778D02*
X-9844D01*
G01X-4259Y1669935D02*
X-4725D01*
G01X-2197Y1670093D02*
X-3151D01*
G01X-4725Y1670369D02*
X-6694D01*
G01X15077Y1670487D02*
X8523D01*
G01D02*
X-1D01*
G01D02*
X-985D01*
G01X-3378Y1652928D02*
X-4259Y1652691D01*
G01X-6694Y1652849D02*
X-4725Y1653164D01*
G01X-6694Y1656786D02*
X-4725Y1657101D01*
G01X-6694Y1660723D02*
X-4725Y1661038D01*
G01X-6694Y1664660D02*
X-4725Y1664975D01*
G01X-6694Y1668597D02*
X-4725Y1668912D01*
G01X-3378Y1656865D02*
X-4259Y1656628D01*
G01X-3378Y1660802D02*
X-4259Y1660565D01*
G01X-3378Y1664739D02*
X-4259Y1664502D01*
G01X-3378Y1668676D02*
X-4259Y1668439D01*
G01X-9844Y1684345D02*
X-10631Y1683991D01*
G01X-9844Y1680408D02*
X-10631Y1680054D01*
G01X-9844Y1676471D02*
X-10631Y1676117D01*
G01X-9844Y1672534D02*
X-10631Y1672180D01*
G01X-1970Y1684424D02*
X-2197Y1684030D01*
G01X-3378Y1681510D02*
X-3151Y1681904D01*
G01X-1970Y1680487D02*
X-2197Y1680093D01*
G01X-3378Y1677573D02*
X-3151Y1677967D01*
G01X-1970Y1676550D02*
X-2197Y1676156D01*
G01X-3378Y1673636D02*
X-3151Y1674030D01*
G01X-1970Y1672613D02*
X-2197Y1672219D01*
G01X-10531Y1684035D02*
Y1681898D01*
G01Y1680098D02*
Y1677961D01*
G01Y1676161D02*
Y1674024D01*
G01X-6694Y1684345D02*
Y1683754D01*
G01Y1682180D02*
Y1681589D01*
G01Y1680408D02*
Y1679817D01*
G01Y1678243D02*
Y1677652D01*
G01Y1672534D02*
Y1671943D01*
G01Y1676471D02*
Y1675880D01*
G01Y1674306D02*
Y1673715D01*
G01X-4725Y1684660D02*
Y1683754D01*
G01Y1682180D02*
Y1681274D01*
G01Y1680723D02*
Y1679817D01*
G01Y1678243D02*
Y1677337D01*
G01Y1676786D02*
Y1675880D01*
G01Y1674306D02*
Y1673400D01*
G01Y1672849D02*
Y1671943D01*
G01X-3757Y1684069D02*
Y1681865D01*
G01Y1680132D02*
Y1677928D01*
G01Y1676195D02*
Y1673991D01*
G01X-2521Y1684069D02*
Y1681865D01*
G01Y1680132D02*
Y1677928D01*
G01Y1676195D02*
Y1673991D01*
G01X-2251Y1684384D02*
Y1681550D01*
G01Y1680447D02*
Y1677613D01*
G01Y1676510D02*
Y1673676D01*
G01X-985Y1683636D02*
Y1682298D01*
G01Y1679699D02*
Y1678361D01*
G01Y1675762D02*
Y1674424D01*
G01X8523Y1683636D02*
Y1682298D01*
G01Y1679699D02*
Y1678361D01*
G01Y1675762D02*
Y1674424D01*
G01X-3151Y1672219D02*
X-3378Y1672613D01*
G01X-2197Y1674030D02*
X-1970Y1673636D01*
G01X-3151Y1676156D02*
X-3378Y1676550D01*
G01X-2197Y1677967D02*
X-1970Y1677573D01*
G01X-3151Y1680093D02*
X-3378Y1680487D01*
G01X-2197Y1681904D02*
X-1970Y1681510D01*
G01X-3151Y1684030D02*
X-3378Y1684424D01*
G01X-10631Y1674069D02*
X-9844Y1673715D01*
G01X-10631Y1678006D02*
X-9844Y1677652D01*
G01X-10631Y1681943D02*
X-9844Y1681589D01*
G01X-4259Y1673872D02*
X-3378Y1673636D01*
G01X-4259Y1677809D02*
X-3378Y1677573D01*
G01X-4259Y1681746D02*
X-3378Y1681510D01*
G01X-4725Y1673400D02*
X-6694Y1673715D01*
G01X-4725Y1677337D02*
X-6694Y1677652D01*
G01X-4725Y1681274D02*
X-6694Y1681589D01*
G01X-985Y1671825D02*
X-1D01*
G01D02*
X8523D01*
G01D02*
X12600D01*
G01X-4725Y1671943D02*
X-6694D01*
G01X-3151Y1672219D02*
X-2197D01*
G01X-4725Y1672376D02*
X-4259D01*
G01X-9844Y1672534D02*
X-6694D01*
G01X-1970Y1672613D02*
X-1D01*
G01Y1673636D02*
X-1970D01*
G01X-6694Y1673715D02*
X-9844D01*
G01X-4259Y1673872D02*
X-4725D01*
G01X-2197Y1674030D02*
X-3151D01*
G01X-4725Y1674306D02*
X-6694D01*
G01X15077Y1674424D02*
X8523D01*
G01D02*
X-1D01*
G01D02*
X-985D01*
G01Y1675762D02*
X-1D01*
G01D02*
X8523D01*
G01D02*
X12600D01*
G01X-4725Y1675880D02*
X-6694D01*
G01X-3151Y1676156D02*
X-2197D01*
G01X-4725Y1676313D02*
X-4259D01*
G01X-9844Y1676471D02*
X-6694D01*
G01X-1970Y1676550D02*
X-1D01*
G01Y1677573D02*
X-1970D01*
G01X-6694Y1677652D02*
X-9844D01*
G01X-4259Y1677809D02*
X-4725D01*
G01X-2197Y1677967D02*
X-3151D01*
G01X-4725Y1678243D02*
X-6694D01*
G01X15077Y1678361D02*
X8523D01*
G01D02*
X-1D01*
G01D02*
X-985D01*
G01Y1679699D02*
X-1D01*
G01D02*
X8523D01*
G01D02*
X12600D01*
G01X-4725Y1679817D02*
X-6694D01*
G01X-3151Y1680093D02*
X-2197D01*
G01X-4725Y1680250D02*
X-4259D01*
G01X-9844Y1680408D02*
X-6694D01*
G01X-1970Y1680487D02*
X-1D01*
G01Y1681510D02*
X-1970D01*
G01X-6694Y1681589D02*
X-9844D01*
G01X-4259Y1681746D02*
X-4725D01*
G01X-2197Y1681904D02*
X-3151D01*
G01X-4725Y1682180D02*
X-6694D01*
G01X15077Y1682298D02*
X8523D01*
G01D02*
X-1D01*
G01D02*
X-985D01*
G01Y1683636D02*
X-1D01*
G01D02*
X8523D01*
G01D02*
X12600D01*
G01X-4725Y1683754D02*
X-6694D01*
G01X-3151Y1684030D02*
X-2197D01*
G01X-4725Y1684187D02*
X-4259D01*
G01X-9844Y1684345D02*
X-6694D01*
G01X-1970Y1684424D02*
X-1D01*
G01Y1688577D02*
X24802D01*
G01X-6694Y1672534D02*
X-4725Y1672849D01*
G01X-6694Y1676471D02*
X-4725Y1676786D01*
G01X-6694Y1680408D02*
X-4725Y1680723D01*
G01X-6694Y1684345D02*
X-4725Y1684660D01*
G01X-3378Y1672613D02*
X-4259Y1672376D01*
G01X-3378Y1676550D02*
X-4259Y1676313D01*
G01X-3378Y1680487D02*
X-4259Y1680250D01*
G01X-3378Y1684424D02*
X-4259Y1684187D01*
G01X-9056Y1694876D02*
Y1714168D01*
G01X-1Y1694876D02*
Y1714168D01*
G01X9842Y1698026D02*
X-9056Y1696855D01*
G01Y1706304D02*
X9842Y1705900D01*
G01X14369Y1701963D02*
G03I-4527J0D01*
G01X13779D02*
G03I-3937J0D01*
G01X-1Y1714168D02*
Y1734654D01*
G01X24802Y1714168D02*
X-9056D01*
G01X26771Y1716136D02*
X-1D01*
G01X-34603Y1761819D02*
X-39607Y1758315D01*
G01Y1852370D02*
Y1753945D01*
G01X-38426Y1770776D02*
Y1768414D01*
G01Y1766839D02*
Y1764477D01*
G01X-36812Y1808343D02*
Y1760272D01*
G01X-36192Y1766309D02*
Y1764975D01*
G01Y1770246D02*
Y1768912D01*
G01X-35595Y1770304D02*
Y1768855D01*
G01Y1766367D02*
Y1764918D01*
G01X-35546Y1768850D02*
Y1768414D01*
G01Y1770776D02*
Y1770309D01*
G01Y1766839D02*
Y1766372D01*
G01Y1764913D02*
Y1764477D01*
G01X-35331Y1766392D02*
Y1764894D01*
G01Y1770329D02*
Y1768831D01*
G01X-34607Y1766760D02*
Y1764556D01*
G01Y1768493D02*
Y1770697D01*
G01X-34136Y1768818D02*
Y1770341D01*
G01Y1764881D02*
Y1766404D01*
G01X-33702Y1761819D02*
Y1757882D01*
G01X-33153Y1770352D02*
Y1768807D01*
G01Y1766415D02*
Y1764870D01*
G01X-31995Y1770365D02*
Y1768794D01*
G01Y1766428D02*
Y1764857D01*
G01X-31725Y1768791D02*
Y1770368D01*
G01Y1764854D02*
Y1766431D01*
G01X-39607Y1753945D02*
X-1D01*
G01X-39607Y1757095D02*
X-27993D01*
G01X-33702Y1757882D02*
X-39607D01*
G01Y1761819D02*
X-9607D01*
G01X-39607Y1764477D02*
X-24509D01*
G01X-35546Y1764556D02*
X-1D01*
G01X-39607Y1766544D02*
X-27993D01*
G01X-35546Y1766760D02*
X-1D01*
G01X-24509Y1766839D02*
X-39607D01*
G01X-35351Y1764894D02*
X-10631Y1764619D01*
G01X-35351Y1768831D02*
X-10631Y1768556D01*
G01X-36192Y1764975D02*
X-35351Y1764894D01*
G01X-36192Y1768912D02*
X-35351Y1768831D01*
G01X-36192Y1766309D02*
X-35341Y1766391D01*
G01X-36192Y1770246D02*
X-35341Y1770328D01*
G01X-35351Y1766390D02*
X-10631Y1766666D01*
G01X-35351Y1770327D02*
X-10631Y1770603D01*
G01X-39607Y1768414D02*
X-24509D01*
G01X-35546Y1768493D02*
X-1D01*
G01X-39607Y1769693D02*
X-24844D01*
G01X-35546Y1770697D02*
X-1D01*
G01X-24509Y1770776D02*
X-39607D01*
G01X-38426Y1790461D02*
Y1788099D01*
G01Y1786524D02*
Y1784162D01*
G01Y1782587D02*
Y1780225D01*
G01Y1778650D02*
Y1776288D01*
G01Y1774713D02*
Y1772351D01*
G01X-36192Y1789931D02*
Y1788597D01*
G01Y1785994D02*
Y1784660D01*
G01Y1782057D02*
Y1780723D01*
G01Y1778120D02*
Y1776786D01*
G01Y1774183D02*
Y1772849D01*
G01X-35595Y1789989D02*
Y1788540D01*
G01Y1786052D02*
Y1784603D01*
G01Y1782115D02*
Y1780666D01*
G01Y1778178D02*
Y1776729D01*
G01Y1774241D02*
Y1772792D01*
G01X-35546Y1790461D02*
Y1789994D01*
G01Y1788535D02*
Y1788099D01*
G01Y1786524D02*
Y1786057D01*
G01Y1780661D02*
Y1780225D01*
G01Y1782587D02*
Y1782120D01*
G01Y1784598D02*
Y1784162D01*
G01Y1776724D02*
Y1776288D01*
G01Y1778650D02*
Y1778183D01*
G01Y1772787D02*
Y1772351D01*
G01Y1774713D02*
Y1774246D01*
G01X-35331Y1790014D02*
Y1788516D01*
G01Y1786077D02*
Y1784579D01*
G01Y1782140D02*
Y1780642D01*
G01Y1778203D02*
Y1776705D01*
G01Y1774266D02*
Y1772768D01*
G01X-34607Y1790382D02*
Y1788178D01*
G01Y1786445D02*
Y1784241D01*
G01Y1782508D02*
Y1780304D01*
G01Y1778571D02*
Y1776367D01*
G01Y1774634D02*
Y1772430D01*
G01X-34136Y1772755D02*
Y1774278D01*
G01Y1776692D02*
Y1778215D01*
G01Y1780629D02*
Y1782152D01*
G01Y1784566D02*
Y1786089D01*
G01Y1788503D02*
Y1790026D01*
G01X-33153Y1790037D02*
Y1788492D01*
G01Y1786100D02*
Y1784555D01*
G01Y1782163D02*
Y1780618D01*
G01Y1778226D02*
Y1776681D01*
G01Y1774289D02*
Y1772744D01*
G01X-31995Y1790050D02*
Y1788479D01*
G01Y1786113D02*
Y1784542D01*
G01Y1782176D02*
Y1780605D01*
G01Y1778239D02*
Y1776668D01*
G01Y1774302D02*
Y1772731D01*
G01X-31725Y1772728D02*
Y1774305D01*
G01Y1776665D02*
Y1778242D01*
G01Y1780602D02*
Y1782179D01*
G01Y1784539D02*
Y1786116D01*
G01Y1788476D02*
Y1790053D01*
G01X-35351Y1772768D02*
X-10631Y1772493D01*
G01X-36192Y1772849D02*
X-35351Y1772768D01*
G01X-36192Y1776786D02*
X-35351Y1776705D01*
G01X-36192Y1780723D02*
X-35351Y1780642D01*
G01X-36192Y1784660D02*
X-35351Y1784579D01*
G01X-36192Y1788597D02*
X-35351Y1788516D01*
G01X-36192Y1774183D02*
X-35341Y1774265D01*
G01X-36192Y1778120D02*
X-35341Y1778202D01*
G01X-36192Y1782057D02*
X-35341Y1782139D01*
G01X-36192Y1785994D02*
X-35341Y1786076D01*
G01X-36192Y1789931D02*
X-35341Y1790013D01*
G01X-35351Y1774264D02*
X-10631Y1774540D01*
G01X-35351Y1778201D02*
X-10631Y1778477D01*
G01X-35351Y1782138D02*
X-10631Y1782414D01*
G01X-35351Y1786075D02*
X-10631Y1786351D01*
G01X-35351Y1790012D02*
X-10631Y1790288D01*
G01X-39607Y1772351D02*
X-24509D01*
G01X-35546Y1772430D02*
X-1D01*
G01X-39607Y1774418D02*
X-24844D01*
G01X-35546Y1774634D02*
X-1D01*
G01X-24509Y1774713D02*
X-39607D01*
G01Y1776288D02*
X-24509D01*
G01X-35546Y1776367D02*
X-1D01*
G01X-27993Y1777567D02*
X-39607D01*
G01X-35546Y1778571D02*
X-1D01*
G01X-24509Y1778650D02*
X-39607D01*
G01Y1780225D02*
X-24509D01*
G01X-35546Y1780304D02*
X-1D01*
G01X-35546Y1782508D02*
X-1D01*
G01X-24509Y1782587D02*
X-39607D01*
G01Y1784162D02*
X-24509D01*
G01X-35546Y1784241D02*
X-1D01*
G01X-35546Y1786445D02*
X-1D01*
G01X-24509Y1786524D02*
X-39607D01*
G01Y1787016D02*
X-27993D01*
G01X-39607Y1788099D02*
X-24509D01*
G01X-35546Y1788178D02*
X-1D01*
G01X-39607Y1790166D02*
X-24844D01*
G01X-35546Y1790382D02*
X-1D01*
G01X-24509Y1790461D02*
X-39607D01*
G01X-35351Y1776705D02*
X-10631Y1776430D01*
G01X-35351Y1780642D02*
X-10631Y1780367D01*
G01X-35351Y1784579D02*
X-10631Y1784304D01*
G01X-35351Y1788516D02*
X-10631Y1788241D01*
G01X-38426Y1806209D02*
Y1803847D01*
G01Y1802272D02*
Y1799910D01*
G01Y1794398D02*
Y1792036D01*
G01Y1798335D02*
Y1795973D01*
G01X-36192Y1805680D02*
Y1804345D01*
G01Y1801743D02*
Y1800408D01*
G01Y1797806D02*
Y1796471D01*
G01Y1793869D02*
Y1792534D01*
G01X-35595Y1805737D02*
Y1804288D01*
G01Y1801800D02*
Y1800351D01*
G01Y1797863D02*
Y1796414D01*
G01Y1793926D02*
Y1792477D01*
G01X-35546Y1804283D02*
Y1803847D01*
G01Y1800346D02*
Y1799910D01*
G01Y1802272D02*
Y1801805D01*
G01Y1794398D02*
Y1793931D01*
G01Y1796409D02*
Y1795973D01*
G01Y1798335D02*
Y1797868D01*
G01Y1792472D02*
Y1792036D01*
G01X-35331Y1805762D02*
Y1804264D01*
G01Y1801825D02*
Y1800327D01*
G01Y1797888D02*
Y1796390D01*
G01Y1793951D02*
Y1792453D01*
G01X-34607Y1806130D02*
Y1803926D01*
G01Y1802193D02*
Y1799989D01*
G01Y1798256D02*
Y1796052D01*
G01Y1794319D02*
Y1792115D01*
G01X-34136Y1792440D02*
Y1793963D01*
G01Y1796377D02*
Y1797900D01*
G01Y1800314D02*
Y1801837D01*
G01Y1804251D02*
Y1805774D01*
G01X-33153Y1805785D02*
Y1804240D01*
G01Y1801848D02*
Y1800303D01*
G01Y1797911D02*
Y1796366D01*
G01Y1793974D02*
Y1792429D01*
G01X-31995Y1805798D02*
Y1804227D01*
G01Y1801861D02*
Y1800290D01*
G01Y1797924D02*
Y1796353D01*
G01Y1793987D02*
Y1792416D01*
G01X-31725Y1792413D02*
Y1793990D01*
G01Y1796350D02*
Y1797927D01*
G01Y1800287D02*
Y1801864D01*
G01Y1804224D02*
Y1805801D01*
G01X-36192Y1792534D02*
X-35351Y1792453D01*
G01X-36192Y1796471D02*
X-35351Y1796390D01*
G01X-36192Y1800408D02*
X-35351Y1800327D01*
G01X-36192Y1804345D02*
X-35351Y1804264D01*
G01X-36192Y1793869D02*
X-35341Y1793950D01*
G01X-35351Y1793949D02*
X-10631Y1794225D01*
G01X-35351Y1797886D02*
X-10631Y1798162D01*
G01X-35351Y1801823D02*
X-10631Y1802099D01*
G01X-39607Y1792036D02*
X-24509D01*
G01X-35546Y1792115D02*
X-1D01*
G01X-35546Y1794319D02*
X-1D01*
G01X-24509Y1794398D02*
X-39607D01*
G01Y1794890D02*
X-24844D01*
G01X-39607Y1795973D02*
X-24509D01*
G01X-35546Y1796052D02*
X-1D01*
G01X-27993Y1798040D02*
X-39607D01*
G01X-35546Y1798256D02*
X-1D01*
G01X-24509Y1798335D02*
X-39607D01*
G01Y1799910D02*
X-24509D01*
G01X-35546Y1799989D02*
X-1D01*
G01X-35546Y1802193D02*
X-1D01*
G01X-24509Y1802272D02*
X-39607D01*
G01Y1803847D02*
X-24509D01*
G01X-35546Y1803926D02*
X-1D01*
G01X-35351Y1792453D02*
X-10631Y1792178D01*
G01X-35351Y1796390D02*
X-10631Y1796115D01*
G01X-35351Y1800327D02*
X-10631Y1800052D01*
G01X-35351Y1804264D02*
X-10631Y1803989D01*
G01X-36192Y1797806D02*
X-35341Y1797887D01*
G01X-36192Y1801743D02*
X-35341Y1801824D01*
G01X-27993Y1769693D02*
Y1753945D01*
G01X-27265Y1770776D02*
Y1768414D01*
G01Y1766839D02*
Y1764477D01*
G01X-26511Y1770426D02*
Y1768733D01*
G01Y1766489D02*
Y1764796D01*
G01X-26242Y1766492D02*
Y1764793D01*
G01Y1770429D02*
Y1768730D01*
G01X-24844Y1753945D02*
Y1769693D01*
G01X-24509Y1770776D02*
Y1768414D01*
G01Y1766839D02*
Y1764477D01*
G01X-23998Y1770454D02*
Y1768705D01*
G01Y1766517D02*
Y1764768D01*
G01X-23519Y1770459D02*
Y1768699D01*
G01Y1766522D02*
Y1764762D01*
G01X-12993Y1771012D02*
Y1770697D01*
G01Y1768493D02*
Y1768178D01*
G01Y1767075D02*
Y1766760D01*
G01Y1764556D02*
Y1764241D01*
G01X-12445Y1770583D02*
Y1768576D01*
G01Y1766646D02*
Y1764639D01*
G01X-11967Y1768570D02*
Y1770588D01*
G01Y1764633D02*
Y1766651D01*
G01X-12993Y1764241D02*
X-1D01*
G01Y1767075D02*
X-12993D01*
G01Y1768178D02*
X-1D01*
G01Y1771012D02*
X-12993D01*
G01X-27993Y1774418D02*
Y1790166D01*
G01X-27265Y1790461D02*
Y1788099D01*
G01Y1786524D02*
Y1784162D01*
G01Y1782587D02*
Y1780225D01*
G01Y1778650D02*
Y1776288D01*
G01Y1774713D02*
Y1772351D01*
G01X-26511Y1790111D02*
Y1788418D01*
G01Y1786174D02*
Y1784481D01*
G01Y1782237D02*
Y1780544D01*
G01Y1778300D02*
Y1776607D01*
G01Y1774363D02*
Y1772670D01*
G01X-26242Y1790114D02*
Y1788415D01*
G01Y1786177D02*
Y1784478D01*
G01Y1782240D02*
Y1780541D01*
G01Y1778303D02*
Y1776604D01*
G01Y1774366D02*
Y1772667D01*
G01X-24844Y1774418D02*
Y1790166D01*
G01X-24509Y1790461D02*
Y1788099D01*
G01Y1782587D02*
Y1780225D01*
G01Y1786524D02*
Y1784162D01*
G01Y1778650D02*
Y1776288D01*
G01Y1774713D02*
Y1772351D01*
G01X-23998Y1790139D02*
Y1788390D01*
G01Y1786202D02*
Y1784453D01*
G01Y1782265D02*
Y1780516D01*
G01Y1778328D02*
Y1776579D01*
G01Y1774391D02*
Y1772642D01*
G01X-23519Y1790144D02*
Y1788384D01*
G01Y1786207D02*
Y1784447D01*
G01Y1782270D02*
Y1780510D01*
G01Y1778333D02*
Y1776573D01*
G01Y1774396D02*
Y1772636D01*
G01X-12993Y1790697D02*
Y1790382D01*
G01Y1786760D02*
Y1786445D01*
G01Y1788178D02*
Y1787863D01*
G01Y1780304D02*
Y1779989D01*
G01Y1782823D02*
Y1782508D01*
G01Y1784241D02*
Y1783926D01*
G01Y1776367D02*
Y1776052D01*
G01Y1778886D02*
Y1778571D01*
G01Y1772430D02*
Y1772115D01*
G01Y1774949D02*
Y1774634D01*
G01X-12445Y1790268D02*
Y1788261D01*
G01Y1786331D02*
Y1784324D01*
G01Y1782394D02*
Y1780387D01*
G01Y1778457D02*
Y1776450D01*
G01Y1774520D02*
Y1772513D01*
G01X-11967Y1772507D02*
Y1774525D01*
G01Y1776444D02*
Y1778462D01*
G01Y1780381D02*
Y1782399D01*
G01Y1784319D02*
Y1786336D01*
G01Y1788256D02*
Y1790273D01*
G01X-12993Y1772115D02*
X-1D01*
G01Y1774949D02*
X-12993D01*
G01Y1776052D02*
X-1D01*
G01Y1778886D02*
X-12993D01*
G01Y1779989D02*
X-1D01*
G01Y1782823D02*
X-12993D01*
G01Y1783926D02*
X-1D01*
G01Y1786760D02*
X-12993D01*
G01Y1787863D02*
X-1D01*
G01Y1790697D02*
X-12993D01*
G01X-27993Y1794890D02*
Y1810638D01*
G01X-27265Y1806209D02*
Y1803847D01*
G01Y1802272D02*
Y1799910D01*
G01Y1798335D02*
Y1795973D01*
G01Y1794398D02*
Y1792036D01*
G01X-26511Y1805859D02*
Y1804166D01*
G01Y1801922D02*
Y1800229D01*
G01Y1797985D02*
Y1796292D01*
G01Y1794048D02*
Y1792355D01*
G01X-26242Y1805862D02*
Y1804163D01*
G01Y1801925D02*
Y1800226D01*
G01Y1797988D02*
Y1796289D01*
G01Y1794051D02*
Y1792352D01*
G01X-24844Y1794890D02*
Y1810638D01*
G01X-24509Y1806209D02*
Y1803847D01*
G01Y1802272D02*
Y1799910D01*
G01Y1798335D02*
Y1795973D01*
G01Y1794398D02*
Y1792036D01*
G01X-23998Y1805887D02*
Y1804138D01*
G01Y1801950D02*
Y1800201D01*
G01Y1798013D02*
Y1796264D01*
G01Y1794076D02*
Y1792327D01*
G01X-23519Y1805893D02*
Y1804132D01*
G01Y1801956D02*
Y1800195D01*
G01Y1798019D02*
Y1796258D01*
G01Y1794081D02*
Y1792321D01*
G01X-12993Y1803926D02*
Y1803611D01*
G01Y1802508D02*
Y1802193D01*
G01Y1799989D02*
Y1799674D01*
G01Y1798571D02*
Y1798256D01*
G01Y1796052D02*
Y1795737D01*
G01Y1794634D02*
Y1794319D01*
G01Y1792115D02*
Y1791800D01*
G01X-12445Y1806016D02*
Y1804009D01*
G01Y1802079D02*
Y1800072D01*
G01Y1798142D02*
Y1796135D01*
G01Y1794205D02*
Y1792198D01*
G01X-11967Y1792193D02*
Y1794210D01*
G01Y1796130D02*
Y1798147D01*
G01Y1800067D02*
Y1802084D01*
G01Y1804004D02*
Y1806021D01*
G01X-12993Y1791800D02*
X-1D01*
G01Y1794634D02*
X-12993D01*
G01Y1795737D02*
X-1D01*
G01Y1798571D02*
X-12993D01*
G01Y1799674D02*
X-1D01*
G01Y1802508D02*
X-12993D01*
G01Y1803611D02*
X-1D01*
G01X-9056Y1734654D02*
Y1753945D01*
G01X-1Y1734654D02*
Y1753945D01*
G01X9842Y1742922D02*
X-9056Y1742134D01*
G01X-1Y1732685D02*
X26771D01*
G01X-9056Y1734654D02*
X24802D01*
G01X-9056Y1751583D02*
X9842Y1750796D01*
G01X14369Y1746859D02*
G03I-4527J0D01*
G01X13779D02*
G03I-3937J0D01*
G01X8653Y1765530D02*
X8921Y1765727D01*
G01X-10631Y1770603D02*
X-9844Y1770957D01*
G01X-10631Y1766666D02*
X-9844Y1767020D01*
G01X-1983Y1771012D02*
X-2197Y1770642D01*
G01X-3346Y1768178D02*
X-3151Y1768516D01*
G01X-1983Y1767075D02*
X-2197Y1766705D01*
G01X-3346Y1764241D02*
X-3151Y1764579D01*
G01X8452Y1765268D02*
X8653Y1765530D01*
G01X8854Y1765202D02*
X8787Y1765006D01*
G01X8385Y1764940D02*
X8452Y1765268D01*
G01X-10531Y1770648D02*
Y1768511D01*
G01Y1766711D02*
Y1764574D01*
G01X-9607Y1761819D02*
Y1807626D01*
G01X-6694Y1770957D02*
Y1770367D01*
G01Y1768792D02*
Y1768201D01*
G01Y1767020D02*
Y1766430D01*
G01Y1764855D02*
Y1764264D01*
G01X-6038Y1771012D02*
Y1770697D01*
G01Y1767075D02*
Y1766760D01*
G01Y1768493D02*
Y1768178D01*
G01Y1764556D02*
Y1764241D01*
G01X-4725D02*
Y1764855D01*
G01Y1766430D02*
Y1767075D01*
G01Y1768178D02*
Y1768792D01*
G01Y1770367D02*
Y1771012D01*
G01X-3757Y1766760D02*
Y1764556D01*
G01Y1770697D02*
Y1768493D01*
G01X-2521Y1766760D02*
Y1764556D01*
G01Y1770697D02*
Y1768493D01*
G01X-2251Y1771012D02*
Y1768178D01*
G01Y1767075D02*
Y1764241D01*
G01X-985Y1770248D02*
Y1768910D01*
G01Y1766311D02*
Y1764973D01*
G01X-1Y1753945D02*
Y1852370D01*
G01X196Y1770248D02*
Y1768910D01*
G01Y1766311D02*
Y1764973D01*
G01X8385Y1763365D02*
Y1764940D01*
G01Y1766711D02*
Y1767105D01*
G01X8787Y1765006D02*
Y1763759D01*
G01X-2197Y1764579D02*
X-2001Y1764241D01*
G01X-3151Y1766705D02*
X-3364Y1767075D01*
G01X-2197Y1768516D02*
X-2001Y1768178D01*
G01X-3151Y1770642D02*
X-3364Y1771012D01*
G01X8854Y1766318D02*
X8385Y1766711D01*
G01X-10631Y1764619D02*
X-9844Y1764264D01*
G01X-10631Y1768556D02*
X-9844Y1768201D01*
G01X-4259Y1764422D02*
X-3582Y1764241D01*
G01X-4259Y1768359D02*
X-3582Y1768178D01*
G01X-6545Y1764241D02*
X-6694Y1764264D01*
G01X-6545Y1768178D02*
X-6694Y1768201D01*
G01X24802Y1760244D02*
X-1D01*
G01X11534Y1763365D02*
X8385D01*
G01X8787Y1763759D02*
X9725D01*
G01X-9844Y1764264D02*
X-6694D01*
G01X-4725Y1764422D02*
X-4259D01*
G01X-3151Y1764579D02*
X-2197D01*
G01X-4725Y1764855D02*
X-6694D01*
G01X9000Y1764973D02*
X-1D01*
G01D02*
X-985D01*
G01X-1Y1766311D02*
X9000D01*
G01X-985D02*
X-1D01*
G01X-4725Y1766430D02*
X-6694D01*
G01X-3151Y1766705D02*
X-2197D01*
G01X-4259Y1766863D02*
X-4725D01*
G01X-6694Y1767020D02*
X-9844D01*
G01X8385Y1767105D02*
X11534D01*
G01X-6351Y1767075D02*
X-6694Y1767020D01*
G01X-9844Y1768201D02*
X-6694D01*
G01X-4725Y1768359D02*
X-4259D01*
G01X-3151Y1768516D02*
X-2197D01*
G01X-4725Y1768792D02*
X-6694D01*
G01X9000Y1768910D02*
X-1D01*
G01D02*
X-985D01*
G01X-1Y1770248D02*
X9000D01*
G01X-985D02*
X-1D01*
G01X-4725Y1770367D02*
X-6694D01*
G01X-3151Y1770642D02*
X-2197D01*
G01X-4259Y1770800D02*
X-4725D01*
G01X-6694Y1770957D02*
X-9844D01*
G01X-3467Y1767075D02*
X-4259Y1766863D01*
G01X-3467Y1771012D02*
X-4259Y1770800D01*
G01X-6351Y1771012D02*
X-6694Y1770957D01*
G01X-10631Y1790288D02*
X-9844Y1790642D01*
G01Y1786705D02*
X-10631Y1786351D01*
G01X-9844Y1782768D02*
X-10631Y1782414D01*
G01X-9844Y1778831D02*
X-10631Y1778477D01*
G01Y1774540D02*
X-9844Y1774894D01*
G01X-1983Y1790697D02*
X-2197Y1790327D01*
G01X-3346Y1787863D02*
X-3151Y1788201D01*
G01X-1983Y1786760D02*
X-2197Y1786390D01*
G01X-3346Y1783926D02*
X-3151Y1784264D01*
G01X-1983Y1782823D02*
X-2197Y1782453D01*
G01X-3346Y1779989D02*
X-3151Y1780327D01*
G01X-1983Y1778886D02*
X-2197Y1778516D01*
G01X-3346Y1776052D02*
X-3151Y1776390D01*
G01X-1983Y1774949D02*
X-2197Y1774579D01*
G01X-3346Y1772115D02*
X-3151Y1772453D01*
G01X-10531Y1790333D02*
Y1788196D01*
G01Y1786396D02*
Y1784259D01*
G01Y1782459D02*
Y1780322D01*
G01Y1778522D02*
Y1776385D01*
G01Y1774585D02*
Y1772448D01*
G01X-6694Y1790642D02*
Y1790052D01*
G01Y1786705D02*
Y1786115D01*
G01Y1788477D02*
Y1787886D01*
G01Y1782768D02*
Y1782178D01*
G01Y1780603D02*
Y1780012D01*
G01Y1784540D02*
Y1783949D01*
G01Y1778831D02*
Y1778241D01*
G01Y1776666D02*
Y1776075D01*
G01Y1774894D02*
Y1774304D01*
G01Y1772729D02*
Y1772138D01*
G01X-6038Y1790697D02*
Y1790382D01*
G01Y1786760D02*
Y1786445D01*
G01Y1788178D02*
Y1787863D01*
G01Y1780304D02*
Y1779989D01*
G01Y1782823D02*
Y1782508D01*
G01Y1784241D02*
Y1783926D01*
G01Y1776367D02*
Y1776052D01*
G01Y1778886D02*
Y1778571D01*
G01Y1772430D02*
Y1772115D01*
G01Y1774949D02*
Y1774634D01*
G01X-4725Y1772115D02*
Y1772729D01*
G01Y1774304D02*
Y1774949D01*
G01Y1776052D02*
Y1776666D01*
G01Y1778241D02*
Y1778886D01*
G01Y1779989D02*
Y1780603D01*
G01Y1782178D02*
Y1782823D01*
G01Y1783926D02*
Y1784540D01*
G01Y1786115D02*
Y1786760D01*
G01Y1787863D02*
Y1788477D01*
G01Y1790052D02*
Y1790697D01*
G01X-3757Y1790382D02*
Y1788178D01*
G01Y1786445D02*
Y1784241D01*
G01Y1782508D02*
Y1780304D01*
G01Y1778571D02*
Y1776367D01*
G01Y1774634D02*
Y1772430D01*
G01X-2521Y1790382D02*
Y1788178D01*
G01Y1786445D02*
Y1784241D01*
G01Y1782508D02*
Y1780304D01*
G01Y1778571D02*
Y1776367D01*
G01Y1774634D02*
Y1772430D01*
G01X-2251Y1790697D02*
Y1787863D01*
G01Y1782823D02*
Y1779989D01*
G01Y1786760D02*
Y1783926D01*
G01Y1778886D02*
Y1776052D01*
G01Y1774949D02*
Y1772115D01*
G01X-985Y1789933D02*
Y1788595D01*
G01Y1785996D02*
Y1784658D01*
G01Y1782059D02*
Y1780721D01*
G01Y1778122D02*
Y1776784D01*
G01Y1774185D02*
Y1772847D01*
G01X196Y1789933D02*
Y1788595D01*
G01Y1785996D02*
Y1784658D01*
G01Y1782059D02*
Y1780721D01*
G01Y1778122D02*
Y1776784D01*
G01Y1774185D02*
Y1772847D01*
G01X-2197Y1772453D02*
X-2001Y1772115D01*
G01X-3151Y1774579D02*
X-3364Y1774949D01*
G01X-2197Y1776390D02*
X-2001Y1776052D01*
G01X-3151Y1778516D02*
X-3364Y1778886D01*
G01X-2197Y1780327D02*
X-2001Y1779989D01*
G01X-3151Y1782453D02*
X-3364Y1782823D01*
G01X-2197Y1784264D02*
X-2001Y1783926D01*
G01X-3151Y1786390D02*
X-3364Y1786760D01*
G01X-2197Y1788201D02*
X-2001Y1787863D01*
G01X-3151Y1790327D02*
X-3364Y1790697D01*
G01X-10631Y1772493D02*
X-9844Y1772138D01*
G01X-10631Y1776430D02*
X-9844Y1776075D01*
G01X-10631Y1780367D02*
X-9844Y1780012D01*
G01X-10631Y1784304D02*
X-9844Y1783949D01*
G01X-10631Y1788241D02*
X-9844Y1787886D01*
G01X-4259Y1772296D02*
X-3582Y1772115D01*
G01X-4259Y1776233D02*
X-3582Y1776052D01*
G01X-6545Y1772115D02*
X-6694Y1772138D01*
G01X-6545Y1776052D02*
X-6694Y1776075D01*
G01X-6545Y1779989D02*
X-6694Y1780012D01*
G01X-6545Y1783926D02*
X-6694Y1783949D01*
G01X-4259Y1780170D02*
X-3582Y1779989D01*
G01X-4259Y1784107D02*
X-3582Y1783926D01*
G01X-4259Y1788044D02*
X-3582Y1787863D01*
G01X-6545D02*
X-6694Y1787886D01*
G01X-9844Y1772138D02*
X-6694D01*
G01X-4725Y1772296D02*
X-4259D01*
G01X-3151Y1772453D02*
X-2197D01*
G01X-4725Y1772729D02*
X-6694D01*
G01X9000Y1772847D02*
X-1D01*
G01D02*
X-985D01*
G01X-1Y1774185D02*
X9000D01*
G01X-985D02*
X-1D01*
G01X-4725Y1774304D02*
X-6694D01*
G01X-3151Y1774579D02*
X-2197D01*
G01X-4259Y1774737D02*
X-4725D01*
G01X-6694Y1774894D02*
X-9844D01*
G01Y1776075D02*
X-6694D01*
G01X-4725Y1776233D02*
X-4259D01*
G01X-3151Y1776390D02*
X-2197D01*
G01X-4725Y1776666D02*
X-6694D01*
G01X9000Y1776784D02*
X-1D01*
G01D02*
X-985D01*
G01X-1Y1778122D02*
X9000D01*
G01X-985D02*
X-1D01*
G01X-4725Y1778241D02*
X-6694D01*
G01X-3151Y1778516D02*
X-2197D01*
G01X-4259Y1778674D02*
X-4725D01*
G01X-6694Y1778831D02*
X-9844D01*
G01Y1780012D02*
X-6694D01*
G01X-4725Y1780170D02*
X-4259D01*
G01X-3151Y1780327D02*
X-2197D01*
G01X-4725Y1780603D02*
X-6694D01*
G01X9000Y1780721D02*
X-1D01*
G01D02*
X-985D01*
G01X-1Y1782059D02*
X9000D01*
G01X-985D02*
X-1D01*
G01X-4725Y1782178D02*
X-6694D01*
G01X-3151Y1782453D02*
X-2197D01*
G01X-4259Y1782611D02*
X-4725D01*
G01X-6694Y1782768D02*
X-9844D01*
G01Y1783949D02*
X-6694D01*
G01X-4725Y1784107D02*
X-4259D01*
G01X-3151Y1784264D02*
X-2197D01*
G01X-4725Y1784540D02*
X-6694D01*
G01X9000Y1784658D02*
X-1D01*
G01D02*
X-985D01*
G01X-1Y1785996D02*
X9000D01*
G01X-985D02*
X-1D01*
G01X-4725Y1786115D02*
X-6694D01*
G01X-3151Y1786390D02*
X-2197D01*
G01X-4259Y1786548D02*
X-4725D01*
G01X-6694Y1786705D02*
X-9844D01*
G01Y1787886D02*
X-6694D01*
G01X-4725Y1788044D02*
X-4259D01*
G01X-3151Y1788201D02*
X-2197D01*
G01X-4725Y1788477D02*
X-6694D01*
G01X9000Y1788595D02*
X-1D01*
G01D02*
X-985D01*
G01X-1Y1789933D02*
X9000D01*
G01X-985D02*
X-1D01*
G01X-4725Y1790052D02*
X-6694D01*
G01X-3151Y1790327D02*
X-2197D01*
G01X-4259Y1790485D02*
X-4725D01*
G01X-6694Y1790642D02*
X-9844D01*
G01X-3467Y1774949D02*
X-4259Y1774737D01*
G01X-3467Y1778886D02*
X-4259Y1778674D01*
G01X-3467Y1782823D02*
X-4259Y1782611D01*
G01X-3467Y1786760D02*
X-4259Y1786548D01*
G01X-3467Y1790697D02*
X-4259Y1790485D01*
G01X-6351Y1774949D02*
X-6694Y1774894D01*
G01X-6351Y1778886D02*
X-6694Y1778831D01*
G01X-6351Y1782823D02*
X-6694Y1782768D01*
G01X-6351Y1786760D02*
X-6694Y1786705D01*
G01X-6351Y1790697D02*
X-6694Y1790642D01*
G01X-9844Y1802453D02*
X-10631Y1802099D01*
G01X-9844Y1798516D02*
X-10631Y1798162D01*
G01Y1794225D02*
X-9844Y1794579D01*
G01X-3346Y1803611D02*
X-3151Y1803949D01*
G01X-1983Y1802508D02*
X-2197Y1802138D01*
G01X-3346Y1799674D02*
X-3151Y1800012D01*
G01X-1983Y1798571D02*
X-2197Y1798201D01*
G01X-3346Y1795737D02*
X-3151Y1796075D01*
G01X-1983Y1794634D02*
X-2197Y1794264D01*
G01X-3346Y1791800D02*
X-3151Y1792138D01*
G01X-10531Y1806081D02*
Y1803944D01*
G01Y1802144D02*
Y1800007D01*
G01Y1798207D02*
Y1796070D01*
G01Y1794270D02*
Y1792133D01*
G01X-6694Y1804225D02*
Y1803634D01*
G01Y1800288D02*
Y1799697D01*
G01Y1802453D02*
Y1801863D01*
G01Y1796351D02*
Y1795760D01*
G01Y1798516D02*
Y1797926D01*
G01Y1794579D02*
Y1793989D01*
G01Y1792414D02*
Y1791823D01*
G01X-6038Y1803926D02*
Y1803611D01*
G01Y1802508D02*
Y1802193D01*
G01Y1799989D02*
Y1799674D01*
G01Y1798571D02*
Y1798256D01*
G01Y1796052D02*
Y1795737D01*
G01Y1794634D02*
Y1794319D01*
G01Y1792115D02*
Y1791800D01*
G01X-4725D02*
Y1792414D01*
G01Y1797926D02*
Y1798571D01*
G01Y1795737D02*
Y1796351D01*
G01Y1793989D02*
Y1794634D01*
G01Y1801863D02*
Y1802508D01*
G01Y1799674D02*
Y1800288D01*
G01Y1803611D02*
Y1804225D01*
G01X-3757Y1806130D02*
Y1803926D01*
G01Y1802193D02*
Y1799989D01*
G01Y1794319D02*
Y1792115D01*
G01Y1798256D02*
Y1796052D01*
G01X-2521Y1806130D02*
Y1803926D01*
G01Y1802193D02*
Y1799989D01*
G01Y1798256D02*
Y1796052D01*
G01Y1794319D02*
Y1792115D01*
G01X-2251Y1806445D02*
Y1803611D01*
G01Y1802508D02*
Y1799674D01*
G01Y1798571D02*
Y1795737D01*
G01Y1794634D02*
Y1791800D01*
G01X-985Y1805681D02*
Y1804343D01*
G01Y1801744D02*
Y1800406D01*
G01Y1797807D02*
Y1796469D01*
G01Y1793870D02*
Y1792532D01*
G01X196Y1805681D02*
Y1804343D01*
G01Y1801744D02*
Y1800406D01*
G01Y1797807D02*
Y1796469D01*
G01Y1793870D02*
Y1792532D01*
G01X-2197Y1792138D02*
X-2001Y1791800D01*
G01X-3151Y1794264D02*
X-3364Y1794634D01*
G01X-2197Y1796075D02*
X-2001Y1795737D01*
G01X-3151Y1798201D02*
X-3364Y1798571D01*
G01X-2197Y1800012D02*
X-2001Y1799674D01*
G01X-3151Y1802138D02*
X-3364Y1802508D01*
G01X-2197Y1803949D02*
X-2001Y1803611D01*
G01X-10631Y1792178D02*
X-9844Y1791823D01*
G01X-10631Y1796115D02*
X-9844Y1795760D01*
G01X-10631Y1800052D02*
X-9844Y1799697D01*
G01X-10631Y1803989D02*
X-9844Y1803634D01*
G01X-4259Y1791981D02*
X-3582Y1791800D01*
G01X-4259Y1795918D02*
X-3582Y1795737D01*
G01X-4259Y1799855D02*
X-3582Y1799674D01*
G01X-4259Y1803792D02*
X-3582Y1803611D01*
G01X-6545Y1791800D02*
X-6694Y1791823D01*
G01X-6545Y1795737D02*
X-6694Y1795760D01*
G01X-6545Y1799674D02*
X-6694Y1799697D01*
G01X-6545Y1803611D02*
X-6694Y1803634D01*
G01X-9844Y1791823D02*
X-6694D01*
G01X-4725Y1791981D02*
X-4259D01*
G01X-3151Y1792138D02*
X-2197D01*
G01X-4725Y1792414D02*
X-6694D01*
G01X9000Y1792532D02*
X-1D01*
G01D02*
X-985D01*
G01X-1Y1793870D02*
X9000D01*
G01X-985D02*
X-1D01*
G01X-4725Y1793989D02*
X-6694D01*
G01X-3151Y1794264D02*
X-2197D01*
G01X-4259Y1794422D02*
X-4725D01*
G01X-6694Y1794579D02*
X-9844D01*
G01Y1795760D02*
X-6694D01*
G01X-4725Y1795918D02*
X-4259D01*
G01X-3151Y1796075D02*
X-2197D01*
G01X-4725Y1796351D02*
X-6694D01*
G01X9000Y1796469D02*
X-1D01*
G01D02*
X-985D01*
G01X-1Y1797807D02*
X9000D01*
G01X-985D02*
X-1D01*
G01X-4725Y1797926D02*
X-6694D01*
G01X-3151Y1798201D02*
X-2197D01*
G01X-4259Y1798359D02*
X-4725D01*
G01X-6694Y1798516D02*
X-9844D01*
G01Y1799697D02*
X-6694D01*
G01X-4725Y1799855D02*
X-4259D01*
G01X-3151Y1800012D02*
X-2197D01*
G01X-4725Y1800288D02*
X-6694D01*
G01X9000Y1800406D02*
X-1D01*
G01D02*
X-985D01*
G01X-1Y1801744D02*
X9000D01*
G01X-985D02*
X-1D01*
G01X-4725Y1801863D02*
X-6694D01*
G01X-3151Y1802138D02*
X-2197D01*
G01X-4259Y1802296D02*
X-4725D01*
G01X-6694Y1802453D02*
X-9844D01*
G01Y1803634D02*
X-6694D01*
G01X-4725Y1803792D02*
X-4259D01*
G01X-3151Y1803949D02*
X-2197D01*
G01X-4725Y1804225D02*
X-6694D01*
G01X9000Y1804343D02*
X-1D01*
G01D02*
X-985D01*
G01X-3467Y1794634D02*
X-4259Y1794422D01*
G01X-3467Y1798571D02*
X-4259Y1798359D01*
G01X-3467Y1802508D02*
X-4259Y1802296D01*
G01X-6351Y1794634D02*
X-6694Y1794579D01*
G01X-6351Y1798571D02*
X-6694Y1798516D01*
G01X-6351Y1802508D02*
X-6694Y1802453D01*
G01X8988Y1765333D02*
X8854Y1765202D01*
G01X10194D02*
X10329Y1765333D01*
G01X9993Y1765530D02*
X10261Y1765727D01*
G01X8921D02*
X9122Y1765793D01*
G01X9189Y1765399D02*
X8988Y1765333D01*
G01X10261Y1765727D02*
X10462Y1765793D01*
G01X10329Y1765333D02*
X10529Y1765399D01*
G01X9926D02*
X9993Y1765530D01*
G01X10127Y1765006D02*
X10194Y1765202D01*
G01X9000Y1770248D02*
Y1768910D01*
G01Y1766311D02*
Y1764973D01*
G01X9725Y1763759D02*
Y1765006D01*
G01X10127Y1763759D02*
Y1765006D01*
G01X11132D02*
Y1763759D01*
G01X11534Y1767105D02*
Y1766711D01*
G01Y1764940D02*
Y1763365D01*
G01X11468Y1765268D02*
X11534Y1764940D01*
G01X9725Y1765006D02*
X9658Y1765202D01*
G01X11066D02*
X11132Y1765006D01*
G01X9859Y1765530D02*
X9926Y1765399D01*
G01X11267Y1765530D02*
X11468Y1765268D01*
G01X9658Y1765202D02*
X9524Y1765333D01*
G01X10931D02*
X11066Y1765202D01*
G01X8921Y1766711D02*
X9390Y1766318D01*
G01X9591Y1765727D02*
X9859Y1765530D01*
G01X10999Y1765727D02*
X11267Y1765530D01*
G01X9524Y1765333D02*
X9323Y1765399D01*
G01X9390Y1765793D02*
X9591Y1765727D01*
G01X10730Y1765399D02*
X10931Y1765333D01*
G01X10797Y1765793D02*
X10999Y1765727D01*
G01X11132Y1763759D02*
X10127D01*
G01X12829Y1764973D02*
X9000D01*
G01X9323Y1765399D02*
X9189D01*
G01X10529D02*
X10730D01*
G01X9122Y1765793D02*
X9390D01*
G01X10462D02*
X10797D01*
G01X9000Y1766311D02*
X12829D01*
G01X9390Y1766318D02*
X8854D01*
G01X11534Y1766711D02*
X8921D01*
G01X12829Y1768910D02*
X9000D01*
G01Y1770248D02*
X12829D01*
G01X9000Y1789933D02*
Y1788595D01*
G01Y1785996D02*
Y1784658D01*
G01Y1782059D02*
Y1780721D01*
G01Y1778122D02*
Y1776784D01*
G01Y1774185D02*
Y1772847D01*
G01X12829D02*
X9000D01*
G01Y1774185D02*
X12829D01*
G01Y1776784D02*
X9000D01*
G01Y1778122D02*
X12829D01*
G01Y1780721D02*
X9000D01*
G01Y1782059D02*
X12829D01*
G01Y1784658D02*
X9000D01*
G01Y1785996D02*
X12829D01*
G01Y1788595D02*
X9000D01*
G01Y1789933D02*
X12829D01*
G01X9000Y1805681D02*
Y1804343D01*
G01Y1801744D02*
Y1800406D01*
G01Y1797807D02*
Y1796469D01*
G01Y1793870D02*
Y1792532D01*
G01X12829D02*
X9000D01*
G01Y1793870D02*
X12829D01*
G01Y1796469D02*
X9000D01*
G01Y1797807D02*
X12829D01*
G01Y1800406D02*
X9000D01*
G01Y1801744D02*
X12829D01*
G01Y1804343D02*
X9000D01*
G01X-35546Y1806209D02*
Y1805742D01*
G01X-35434Y1808433D02*
Y1813433D01*
G01X-36561Y1808167D02*
X-39020Y1809889D01*
G01X-35351Y1805760D02*
X-10631Y1806036D01*
G01X-35546Y1806130D02*
X-1D01*
G01X-24509Y1806209D02*
X-39607D01*
G01Y1807489D02*
X-27993D01*
G01X-9607Y1807626D02*
X-34845D01*
G01X-1Y1808433D02*
X-35434D01*
G01X-39607Y1810638D02*
X-24844D01*
G01X-36192Y1805680D02*
X-35341Y1805761D01*
G01X-36561Y1808167D02*
G03X-34845Y1807626I1716J2451D01*
G01X-39020Y1812175D02*
G03X-39607Y1811046I791J-1128D01*
G01Y1811018D02*
G03X-39020Y1809889I1378J-1D01*
G01Y1812175D02*
X-36561Y1813896D01*
G01X-38426Y1833768D02*
Y1831406D01*
G01Y1829831D02*
Y1827469D01*
G01Y1825894D02*
Y1823532D01*
G01Y1818020D02*
Y1815658D01*
G01Y1821957D02*
Y1819595D01*
G01X-36812Y1845272D02*
Y1813720D01*
G01X-36192Y1829302D02*
Y1827967D01*
G01Y1825365D02*
Y1824030D01*
G01Y1821428D02*
Y1820093D01*
G01Y1817491D02*
Y1816156D01*
G01X-35595Y1829359D02*
Y1827910D01*
G01Y1825422D02*
Y1823973D01*
G01Y1821485D02*
Y1820036D01*
G01Y1817548D02*
Y1816099D01*
G01X-35546Y1827905D02*
Y1827469D01*
G01Y1829831D02*
Y1829364D01*
G01Y1831842D02*
Y1831406D01*
G01Y1823968D02*
Y1823532D01*
G01Y1825894D02*
Y1825427D01*
G01Y1818020D02*
Y1817553D01*
G01Y1820031D02*
Y1819595D01*
G01Y1821957D02*
Y1821490D01*
G01Y1816094D02*
Y1815658D01*
G01X-35331Y1829384D02*
Y1827886D01*
G01Y1825447D02*
Y1823949D01*
G01Y1821510D02*
Y1820012D01*
G01Y1817573D02*
Y1816075D01*
G01X-34607Y1833689D02*
Y1831485D01*
G01Y1829752D02*
Y1827548D01*
G01Y1825815D02*
Y1823611D01*
G01Y1821878D02*
Y1819674D01*
G01Y1815737D02*
Y1817941D01*
G01X-34136Y1816062D02*
Y1817585D01*
G01Y1819999D02*
Y1821522D01*
G01Y1823936D02*
Y1825459D01*
G01Y1827873D02*
Y1829396D01*
G01X-33153Y1829407D02*
Y1827862D01*
G01Y1825470D02*
Y1823925D01*
G01Y1821533D02*
Y1819988D01*
G01Y1817596D02*
Y1816051D01*
G01X-31995Y1829420D02*
Y1827849D01*
G01Y1825483D02*
Y1823912D01*
G01Y1821546D02*
Y1819975D01*
G01Y1817609D02*
Y1816038D01*
G01X-31725Y1816035D02*
Y1817612D01*
G01Y1819972D02*
Y1821549D01*
G01Y1823909D02*
Y1825486D01*
G01Y1827846D02*
Y1829423D01*
G01X-36192Y1816156D02*
X-35351Y1816075D01*
G01X-36192Y1820093D02*
X-35351Y1820012D01*
G01X-36192Y1824030D02*
X-35351Y1823949D01*
G01Y1817571D02*
X-10631Y1817847D01*
G01X-35351Y1821508D02*
X-10631Y1821784D01*
G01X-35351Y1825445D02*
X-10631Y1825721D01*
G01X-35351Y1829382D02*
X-10631Y1829658D01*
G01X-35434Y1813433D02*
X-1D01*
G01X-34845Y1814437D02*
X-9607D01*
G01X-39607Y1815363D02*
X-24844D01*
G01X-39607Y1815658D02*
X-24509D01*
G01X-35546Y1815737D02*
X-1D01*
G01X-35546Y1817941D02*
X-1D01*
G01X-24509Y1818020D02*
X-39607D01*
G01X-27993Y1818512D02*
X-39607D01*
G01Y1819595D02*
X-24509D01*
G01X-35546Y1819674D02*
X-1D01*
G01X-35546Y1821878D02*
X-1D01*
G01X-24509Y1821957D02*
X-39607D01*
G01Y1823532D02*
X-24509D01*
G01X-35546Y1823611D02*
X-1D01*
G01X-35546Y1825815D02*
X-1D01*
G01X-24509Y1825894D02*
X-39607D01*
G01Y1827469D02*
X-24509D01*
G01X-35546Y1827548D02*
X-1D01*
G01X-39607Y1827961D02*
X-27993D01*
G01X-35546Y1829752D02*
X-1D01*
G01X-24509Y1829831D02*
X-39607D01*
G01Y1831111D02*
X-24844D01*
G01X-39607Y1831406D02*
X-24509D01*
G01X-35546Y1831485D02*
X-1D01*
G01X-35351Y1816075D02*
X-10631Y1815800D01*
G01X-35351Y1820012D02*
X-10631Y1819737D01*
G01X-35351Y1823949D02*
X-10631Y1823674D01*
G01X-35351Y1827886D02*
X-10631Y1827611D01*
G01X-36192Y1827967D02*
X-35351Y1827886D01*
G01X-36192Y1817491D02*
X-35341Y1817572D01*
G01X-36192Y1821428D02*
X-35341Y1821509D01*
G01X-36192Y1825365D02*
X-35341Y1825446D01*
G01X-36192Y1829302D02*
X-35341Y1829383D01*
G01X-34845Y1814437D02*
G03X-36561Y1813896I0J-2992D01*
G01X-38426Y1841642D02*
Y1839280D01*
G01Y1837705D02*
Y1835343D01*
G01X-36192Y1841113D02*
Y1839778D01*
G01Y1837176D02*
Y1835841D01*
G01Y1833239D02*
Y1831904D01*
G01X-35595Y1841170D02*
Y1839721D01*
G01Y1833296D02*
Y1831847D01*
G01Y1837233D02*
Y1835784D01*
G01X-35546Y1841642D02*
Y1841175D01*
G01Y1837705D02*
Y1837238D01*
G01Y1839716D02*
Y1839280D01*
G01Y1833768D02*
Y1833301D01*
G01Y1835779D02*
Y1835343D01*
G01X-35331Y1841195D02*
Y1839697D01*
G01Y1837258D02*
Y1835760D01*
G01Y1833321D02*
Y1831823D01*
G01X-34607Y1841563D02*
Y1839359D01*
G01Y1837626D02*
Y1835422D01*
G01X-34136Y1831810D02*
Y1833333D01*
G01Y1835747D02*
Y1837270D01*
G01Y1839684D02*
Y1841207D01*
G01X-33153Y1841218D02*
Y1839673D01*
G01Y1833344D02*
Y1831799D01*
G01Y1837281D02*
Y1835736D01*
G01X-31995Y1841231D02*
Y1839660D01*
G01Y1837294D02*
Y1835723D01*
G01Y1833357D02*
Y1831786D01*
G01X-31725Y1831783D02*
Y1833360D01*
G01Y1835720D02*
Y1837297D01*
G01Y1839657D02*
Y1841234D01*
G01X-39607Y1847230D02*
X-36561Y1845096D01*
G01X-35351Y1833319D02*
X-10631Y1833595D01*
G01X-35351Y1837256D02*
X-10631Y1837532D01*
G01X-35546Y1833689D02*
X-1D01*
G01X-24509Y1833768D02*
X-39607D01*
G01Y1835343D02*
X-24509D01*
G01X-35546Y1835422D02*
X-1D01*
G01X-39607Y1835835D02*
X-24844D01*
G01X-35546Y1837626D02*
X-1D01*
G01X-24509Y1837705D02*
X-39607D01*
G01X-27993Y1838985D02*
X-39607D01*
G01Y1839280D02*
X-24509D01*
G01X-35546Y1839359D02*
X-1D01*
G01X-35546Y1841563D02*
X-1D01*
G01X-24509Y1841642D02*
X-39607D01*
G01X-35351Y1831823D02*
X-10631Y1831548D01*
G01X-35351Y1835760D02*
X-10631Y1835485D01*
G01X-35351Y1839697D02*
X-10631Y1839422D01*
G01X-36192Y1831904D02*
X-35351Y1831823D01*
G01X-36192Y1835841D02*
X-35351Y1835760D01*
G01X-36192Y1839778D02*
X-35351Y1839697D01*
G01X-36192Y1833239D02*
X-35341Y1833320D01*
G01X-36192Y1837176D02*
X-35341Y1837257D01*
G01X-36192Y1841113D02*
X-35341Y1841194D01*
G01X-35351Y1841193D02*
X-10631Y1841469D01*
G01X-9607Y1844556D02*
X-34845D01*
G01X-27993Y1849221D02*
X-39607D01*
G01X-36561Y1845096D02*
G03X-34845Y1844556I1715J2452D01*
G01X-39607Y1852370D02*
X-1D01*
G01X-12993Y1806445D02*
Y1806130D01*
G01X-1Y1806445D02*
X-12993D01*
G01X-27993Y1815363D02*
Y1831111D01*
G01X-27265Y1833768D02*
Y1831406D01*
G01Y1829831D02*
Y1827469D01*
G01Y1825894D02*
Y1823532D01*
G01Y1821957D02*
Y1819595D01*
G01Y1818020D02*
Y1815658D01*
G01X-26511Y1829481D02*
Y1827788D01*
G01Y1825544D02*
Y1823851D01*
G01Y1817670D02*
Y1815977D01*
G01Y1821607D02*
Y1819914D01*
G01X-26242Y1829484D02*
Y1827785D01*
G01Y1825547D02*
Y1823848D01*
G01Y1817673D02*
Y1815974D01*
G01Y1821610D02*
Y1819911D01*
G01X-24844Y1815363D02*
Y1831111D01*
G01X-24509Y1833768D02*
Y1831406D01*
G01Y1829831D02*
Y1827469D01*
G01Y1825894D02*
Y1823532D01*
G01Y1821957D02*
Y1819595D01*
G01Y1818020D02*
Y1815658D01*
G01X-23998Y1815949D02*
Y1817698D01*
G01Y1819886D02*
Y1821635D01*
G01Y1823823D02*
Y1825572D01*
G01Y1827760D02*
Y1829509D01*
G01X-23519Y1829515D02*
Y1827754D01*
G01Y1825578D02*
Y1823817D01*
G01Y1821641D02*
Y1819880D01*
G01Y1817704D02*
Y1815943D01*
G01X-12993Y1831485D02*
Y1831170D01*
G01Y1827548D02*
Y1827233D01*
G01Y1830067D02*
Y1829752D01*
G01Y1823611D02*
Y1823296D01*
G01Y1826130D02*
Y1825815D01*
G01Y1819674D02*
Y1819359D01*
G01Y1822193D02*
Y1821878D01*
G01Y1818256D02*
Y1817941D01*
G01Y1815737D02*
Y1815422D01*
G01X-12445Y1833575D02*
Y1831568D01*
G01Y1829638D02*
Y1827631D01*
G01Y1825701D02*
Y1823694D01*
G01Y1817827D02*
Y1815820D01*
G01Y1821764D02*
Y1819757D01*
G01X-11967Y1819752D02*
Y1821769D01*
G01Y1815815D02*
Y1817832D01*
G01Y1823689D02*
Y1825706D01*
G01Y1827626D02*
Y1829643D01*
G01Y1831563D02*
Y1833580D01*
G01X-12993Y1815422D02*
X-1D01*
G01Y1818256D02*
X-12993D01*
G01Y1819359D02*
X-1D01*
G01Y1822193D02*
X-12993D01*
G01Y1823296D02*
X-1D01*
G01Y1826130D02*
X-12993D01*
G01Y1827233D02*
X-1D01*
G01Y1830067D02*
X-12993D01*
G01Y1831170D02*
X-1D01*
G01X-27993Y1835835D02*
Y1852370D01*
G01X-27265Y1841642D02*
Y1839280D01*
G01Y1837705D02*
Y1835343D01*
G01X-26511Y1841292D02*
Y1839599D01*
G01Y1833418D02*
Y1831725D01*
G01Y1837355D02*
Y1835662D01*
G01X-26242Y1841295D02*
Y1839596D01*
G01Y1833421D02*
Y1831722D01*
G01Y1837358D02*
Y1835659D01*
G01X-24844Y1835835D02*
Y1852370D01*
G01X-24509Y1841642D02*
Y1839280D01*
G01Y1837705D02*
Y1835343D01*
G01X-23998Y1831697D02*
Y1833446D01*
G01Y1835634D02*
Y1837383D01*
G01Y1839571D02*
Y1841320D01*
G01X-23519Y1841326D02*
Y1839565D01*
G01Y1837389D02*
Y1835628D01*
G01Y1833452D02*
Y1831691D01*
G01X-12993Y1841878D02*
Y1841563D01*
G01Y1839359D02*
Y1839044D01*
G01Y1837941D02*
Y1837626D01*
G01Y1835422D02*
Y1835107D01*
G01Y1834004D02*
Y1833689D01*
G01X-12445Y1841449D02*
Y1839442D01*
G01Y1837512D02*
Y1835505D01*
G01X-11967Y1835500D02*
Y1837517D01*
G01Y1839437D02*
Y1841454D01*
G01X-1Y1834004D02*
X-12993D01*
G01Y1835107D02*
X-1D01*
G01Y1837941D02*
X-12993D01*
G01Y1839044D02*
X-1D01*
G01Y1841878D02*
X-12993D01*
G01X1968Y1807283D02*
X281Y1805597D01*
G01D02*
X-1Y1805315D01*
G01X-9844Y1806390D02*
X-10631Y1806036D01*
G01X-1983Y1806445D02*
X-2197Y1806075D01*
G01X-6694Y1806390D02*
Y1805800D01*
G01X-6038Y1806445D02*
Y1806130D01*
G01X-4725Y1805800D02*
Y1806445D01*
G01X-3151Y1806075D02*
X-3364Y1806445D01*
G01X-1Y1805681D02*
X9000D01*
G01X-985D02*
X-1D01*
G01X-4725Y1805800D02*
X-6694D01*
G01X-3151Y1806075D02*
X-2197D01*
G01X-4259Y1806233D02*
X-4725D01*
G01X-6694Y1806390D02*
X-9844D01*
G01X1968Y1807283D02*
X19881D01*
G01X-1Y1807538D02*
X15550D01*
G01X-3467Y1806445D02*
X-4259Y1806233D01*
G01X-6351Y1806445D02*
X-6694Y1806390D01*
G01X-9844Y1830012D02*
X-10631Y1829658D01*
G01X-9844Y1826075D02*
X-10631Y1825721D01*
G01X-9844Y1822138D02*
X-10631Y1821784D01*
G01Y1817847D02*
X-9844Y1818201D01*
G01X-3346Y1831170D02*
X-3151Y1831508D01*
G01X-1983Y1830067D02*
X-2197Y1829697D01*
G01X-3346Y1827233D02*
X-3151Y1827571D01*
G01X-1983Y1826130D02*
X-2197Y1825760D01*
G01X-3346Y1823296D02*
X-3151Y1823634D01*
G01X-1983Y1822193D02*
X-2197Y1821823D01*
G01X-3346Y1819359D02*
X-3151Y1819697D01*
G01X-1983Y1818256D02*
X-2197Y1817886D01*
G01X-3346Y1815422D02*
X-3151Y1815760D01*
G01X-10531Y1833640D02*
Y1831503D01*
G01Y1829703D02*
Y1827566D01*
G01Y1825766D02*
Y1823629D01*
G01Y1821829D02*
Y1819692D01*
G01Y1817892D02*
Y1815755D01*
G01X-9607Y1814437D02*
Y1844556D01*
G01X-6694Y1831784D02*
Y1831193D01*
G01Y1830012D02*
Y1829422D01*
G01Y1827847D02*
Y1827256D01*
G01Y1826075D02*
Y1825485D01*
G01Y1823910D02*
Y1823319D01*
G01Y1822138D02*
Y1821548D01*
G01Y1819973D02*
Y1819382D01*
G01Y1818201D02*
Y1817611D01*
G01Y1816036D02*
Y1815445D01*
G01X-6038Y1831485D02*
Y1831170D01*
G01Y1827548D02*
Y1827233D01*
G01Y1830067D02*
Y1829752D01*
G01Y1823611D02*
Y1823296D01*
G01Y1826130D02*
Y1825815D01*
G01Y1819674D02*
Y1819359D01*
G01Y1822193D02*
Y1821878D01*
G01Y1818256D02*
Y1817941D01*
G01Y1815737D02*
Y1815422D01*
G01X-4725D02*
Y1816036D01*
G01Y1819359D02*
Y1819973D01*
G01Y1821548D02*
Y1822193D01*
G01Y1817611D02*
Y1818256D01*
G01Y1823296D02*
Y1823910D01*
G01Y1825485D02*
Y1826130D01*
G01Y1831170D02*
Y1831784D01*
G01Y1827233D02*
Y1827847D01*
G01Y1829422D02*
Y1830067D01*
G01X-3757Y1833689D02*
Y1831485D01*
G01Y1829752D02*
Y1827548D01*
G01Y1825815D02*
Y1823611D01*
G01Y1817941D02*
Y1815737D01*
G01Y1821878D02*
Y1819674D01*
G01X-2521Y1833689D02*
Y1831485D01*
G01Y1829752D02*
Y1827548D01*
G01Y1825815D02*
Y1823611D01*
G01Y1817941D02*
Y1815737D01*
G01Y1821878D02*
Y1819674D01*
G01X-2251Y1834004D02*
Y1831170D01*
G01Y1830067D02*
Y1827233D01*
G01Y1826130D02*
Y1823296D01*
G01Y1822193D02*
Y1819359D01*
G01Y1818256D02*
Y1815422D01*
G01X-985Y1829304D02*
Y1827965D01*
G01Y1825367D02*
Y1824028D01*
G01Y1821430D02*
Y1820091D01*
G01Y1817493D02*
Y1816154D01*
G01X196Y1829304D02*
Y1827965D01*
G01Y1825367D02*
Y1824028D01*
G01Y1821430D02*
Y1820091D01*
G01Y1817493D02*
Y1816154D01*
G01X-2197Y1815760D02*
X-2001Y1815422D01*
G01X-3151Y1817886D02*
X-3364Y1818256D01*
G01X-2197Y1819697D02*
X-2001Y1819359D01*
G01X-3151Y1821823D02*
X-3364Y1822193D01*
G01X-2197Y1823634D02*
X-2001Y1823296D01*
G01X-3151Y1825760D02*
X-3364Y1826130D01*
G01X-2197Y1827571D02*
X-2001Y1827233D01*
G01X-3151Y1829697D02*
X-3364Y1830067D01*
G01X-2197Y1831508D02*
X-2001Y1831170D01*
G01X387Y1816345D02*
X1968Y1814764D01*
G01X387Y1816345D02*
X-1Y1816732D01*
G01X-10631Y1815800D02*
X-9844Y1815445D01*
G01X-10631Y1819737D02*
X-9844Y1819382D01*
G01X-10631Y1823674D02*
X-9844Y1823319D01*
G01X-10631Y1827611D02*
X-9844Y1827256D01*
G01X-10631Y1831548D02*
X-9844Y1831193D01*
G01X-4259Y1815603D02*
X-3582Y1815422D01*
G01X-4259Y1819540D02*
X-3582Y1819359D01*
G01X-4259Y1823477D02*
X-3582Y1823296D01*
G01X-4259Y1827414D02*
X-3582Y1827233D01*
G01X-4259Y1831351D02*
X-3582Y1831170D01*
G01X-6545Y1815422D02*
X-6694Y1815445D01*
G01X-6545Y1819359D02*
X-6694Y1819382D01*
G01X-6545Y1823296D02*
X-6694Y1823319D01*
G01X-6545Y1827233D02*
X-6694Y1827256D01*
G01X-6545Y1831170D02*
X-6694Y1831193D01*
G01X-1Y1814546D02*
X15550D01*
G01X1968Y1814764D02*
X19881D01*
G01X-9844Y1815445D02*
X-6694D01*
G01X-4725Y1815603D02*
X-4259D01*
G01X-3151Y1815760D02*
X-2197D01*
G01X-4725Y1816036D02*
X-6694D01*
G01X9000Y1816154D02*
X-1D01*
G01D02*
X-985D01*
G01X-1Y1817493D02*
X9000D01*
G01X-985D02*
X-1D01*
G01X-4725Y1817611D02*
X-6694D01*
G01X-3151Y1817886D02*
X-2197D01*
G01X-4259Y1818044D02*
X-4725D01*
G01X-6694Y1818201D02*
X-9844D01*
G01Y1819382D02*
X-6694D01*
G01X-4725Y1819540D02*
X-4259D01*
G01X-3151Y1819697D02*
X-2197D01*
G01X-4725Y1819973D02*
X-6694D01*
G01X9000Y1820091D02*
X-1D01*
G01D02*
X-985D01*
G01X-1Y1821430D02*
X9000D01*
G01X-985D02*
X-1D01*
G01X-4725Y1821548D02*
X-6694D01*
G01X-3151Y1821823D02*
X-2197D01*
G01X-4259Y1821981D02*
X-4725D01*
G01X-6694Y1822138D02*
X-9844D01*
G01Y1823319D02*
X-6694D01*
G01X-4725Y1823477D02*
X-4259D01*
G01X-3151Y1823634D02*
X-2197D01*
G01X-4725Y1823910D02*
X-6694D01*
G01X9000Y1824028D02*
X-1D01*
G01D02*
X-985D01*
G01X-1Y1825367D02*
X9000D01*
G01X-985D02*
X-1D01*
G01X-4725Y1825485D02*
X-6694D01*
G01X-3151Y1825760D02*
X-2197D01*
G01X-4259Y1825918D02*
X-4725D01*
G01X-6694Y1826075D02*
X-9844D01*
G01Y1827256D02*
X-6694D01*
G01X-4725Y1827414D02*
X-4259D01*
G01X-3151Y1827571D02*
X-2197D01*
G01X-4725Y1827847D02*
X-6694D01*
G01X9000Y1827965D02*
X-1D01*
G01D02*
X-985D01*
G01X-1Y1829304D02*
X9000D01*
G01X-985D02*
X-1D01*
G01X-4725Y1829422D02*
X-6694D01*
G01X-3151Y1829697D02*
X-2197D01*
G01X-4259Y1829855D02*
X-4725D01*
G01X-6694Y1830012D02*
X-9844D01*
G01Y1831193D02*
X-6694D01*
G01X-4725Y1831351D02*
X-4259D01*
G01X-3151Y1831508D02*
X-2197D01*
G01X-6351Y1818256D02*
X-6694Y1818201D01*
G01X-6351Y1822193D02*
X-6694Y1822138D01*
G01X-6351Y1826130D02*
X-6694Y1826075D01*
G01X-6351Y1830067D02*
X-6694Y1830012D01*
G01X-3467Y1818256D02*
X-4259Y1818044D01*
G01X-3467Y1822193D02*
X-4259Y1821981D01*
G01X-3467Y1826130D02*
X-4259Y1825918D01*
G01X-3467Y1830067D02*
X-4259Y1829855D01*
G01X-9844Y1841823D02*
X-10631Y1841469D01*
G01Y1837532D02*
X-9844Y1837886D01*
G01X-10631Y1833595D02*
X-9844Y1833949D01*
G01X-1983Y1841878D02*
X-2197Y1841508D01*
G01X-3346Y1839044D02*
X-3151Y1839382D01*
G01X-1983Y1837941D02*
X-2197Y1837571D01*
G01X-3346Y1835107D02*
X-3151Y1835445D01*
G01X-1983Y1834004D02*
X-2197Y1833634D01*
G01X-10531Y1841514D02*
Y1839377D01*
G01Y1837577D02*
Y1835440D01*
G01X-6694Y1841823D02*
Y1841233D01*
G01Y1839658D02*
Y1839067D01*
G01Y1837886D02*
Y1837296D01*
G01Y1835721D02*
Y1835130D01*
G01Y1833949D02*
Y1833359D01*
G01X-6038Y1841878D02*
Y1841563D01*
G01Y1839359D02*
Y1839044D01*
G01Y1837941D02*
Y1837626D01*
G01Y1835422D02*
Y1835107D01*
G01Y1834004D02*
Y1833689D01*
G01X-4725Y1835107D02*
Y1835721D01*
G01Y1833359D02*
Y1834004D01*
G01Y1839044D02*
Y1839658D01*
G01Y1837296D02*
Y1837941D01*
G01Y1841233D02*
Y1841878D01*
G01X-3757Y1841563D02*
Y1839359D01*
G01Y1837626D02*
Y1835422D01*
G01X-2521Y1841563D02*
Y1839359D01*
G01Y1837626D02*
Y1835422D01*
G01X-2251Y1841878D02*
Y1839044D01*
G01Y1837941D02*
Y1835107D01*
G01X-985Y1841115D02*
Y1839776D01*
G01Y1837178D02*
Y1835839D01*
G01Y1833241D02*
Y1831902D01*
G01X196Y1841115D02*
Y1839776D01*
G01Y1837178D02*
Y1835839D01*
G01Y1833241D02*
Y1831902D01*
G01X-3151Y1833634D02*
X-3364Y1834004D01*
G01X-2197Y1835445D02*
X-2001Y1835107D01*
G01X-3151Y1837571D02*
X-3364Y1837941D01*
G01X-2197Y1839382D02*
X-2001Y1839044D01*
G01X-3151Y1841508D02*
X-3364Y1841878D01*
G01X-10631Y1835485D02*
X-9844Y1835130D01*
G01X-10631Y1839422D02*
X-9844Y1839067D01*
G01X-4259Y1835288D02*
X-3582Y1835107D01*
G01X-4259Y1839225D02*
X-3582Y1839044D01*
G01X-6545Y1835107D02*
X-6694Y1835130D01*
G01X-6545Y1839044D02*
X-6694Y1839067D01*
G01X-4725Y1831784D02*
X-6694D01*
G01X9000Y1831902D02*
X-1D01*
G01D02*
X-985D01*
G01X-1Y1833241D02*
X9000D01*
G01X-985D02*
X-1D01*
G01X-4725Y1833359D02*
X-6694D01*
G01X-3151Y1833634D02*
X-2197D01*
G01X-4259Y1833792D02*
X-4725D01*
G01X-6694Y1833949D02*
X-9844D01*
G01Y1835130D02*
X-6694D01*
G01X-4725Y1835288D02*
X-4259D01*
G01X-3151Y1835445D02*
X-2197D01*
G01X-4725Y1835721D02*
X-6694D01*
G01X9000Y1835839D02*
X-1D01*
G01D02*
X-985D01*
G01X-1Y1837178D02*
X9000D01*
G01X-985D02*
X-1D01*
G01X-4725Y1837296D02*
X-6694D01*
G01X-3151Y1837571D02*
X-2197D01*
G01X-4259Y1837729D02*
X-4725D01*
G01X-6694Y1837886D02*
X-9844D01*
G01X-6694Y1839067D02*
X-9844D01*
G01X-4259Y1839225D02*
X-4725D01*
G01X-3151Y1839382D02*
X-2197D01*
G01X-4725Y1839658D02*
X-6694D01*
G01X9000Y1839776D02*
X-1D01*
G01D02*
X-985D01*
G01X-1Y1841115D02*
X9000D01*
G01X-985D02*
X-1D01*
G01X-4725Y1841233D02*
X-6694D01*
G01X-3151Y1841508D02*
X-2197D01*
G01X-4725Y1841666D02*
X-4259D01*
G01X-9844Y1841823D02*
X-6694D01*
G01X-6351Y1834004D02*
X-6694Y1833949D01*
G01X-6351Y1837941D02*
X-6694Y1837886D01*
G01Y1841823D02*
X-6351Y1841878D01*
G01X24802Y1846071D02*
X-1D01*
G01X-3467Y1834004D02*
X-4259Y1833792D01*
G01X-3467Y1837941D02*
X-4259Y1837729D01*
G01X-3467Y1841878D02*
X-4259Y1841666D01*
G01X-9056Y1871662D02*
Y1852370D01*
G01X-1D02*
Y1871662D01*
G01D02*
Y1988189D01*
G01X-9056Y1864181D02*
X9842Y1863394D01*
G01Y1855520D02*
X-9056Y1854733D01*
G01X24802Y1871662D02*
X-9056D01*
G01X14369Y1859457D02*
G03I-4527J0D01*
G01X13779D02*
G03I-3937J0D01*
G01X-1Y1873630D02*
X26771D01*
G01X9000Y1805681D02*
X12829D01*
G01X9000Y1829304D02*
Y1827965D01*
G01Y1825367D02*
Y1824028D01*
G01Y1821430D02*
Y1820091D01*
G01Y1817493D02*
Y1816154D01*
G01X12829D02*
X9000D01*
G01Y1817493D02*
X12829D01*
G01Y1820091D02*
X9000D01*
G01Y1821430D02*
X12829D01*
G01Y1824028D02*
X9000D01*
G01Y1825367D02*
X12829D01*
G01Y1827965D02*
X9000D01*
G01Y1829304D02*
X12829D01*
G01X9000Y1841115D02*
Y1839776D01*
G01Y1837178D02*
Y1835839D01*
G01Y1833241D02*
Y1831902D01*
G01X12829D02*
X9000D01*
G01Y1833241D02*
X12829D01*
G01Y1835839D02*
X9000D01*
G01Y1837178D02*
X12829D01*
G01Y1839776D02*
X9000D01*
G01Y1841115D02*
X12829D01*
G01X-7875Y1889223D02*
Y1877953D01*
G01D02*
X-63741D01*
G01X-38812Y1928865D02*
G03I-4292J0D01*
G01X-41866Y1955322D02*
Y1939322D01*
G01D02*
X-25866D01*
G01X-36366Y1947322D02*
X-31366D01*
G01X-33866Y1949822D02*
Y1944822D01*
G01X-31366Y1949822D02*
Y1944822D01*
G01X-36366D02*
Y1949822D01*
G01X-31366D02*
X-36366D01*
G01Y1944822D02*
X-31366D01*
G01X-41866Y1955322D02*
X-25866D01*
G01Y1939322D02*
Y1955322D01*
G01X33464Y1903150D02*
G03I-15748J0D01*
G01X24704D02*
G03I-6988J0D01*
G01X-7875Y1912843D02*
Y1962926D01*
G01Y1912843D02*
G03X-1I3937J0D01*
G01Y1889223D02*
G03X-7875I-3937J0D01*
G01Y1912843D02*
G03X-1I3937J0D01*
G01Y1889223D02*
G03X-7875I-3937J0D01*
G01X-1Y1962926D02*
G03X-7875I-3937J0D01*
G01X-1D02*
G03X-7875I-3937J0D01*
G01X3936Y1992126D02*
X1029527D01*
G01X3936D02*
G03X-1Y1988189I0J-3937D01*
G01X-7875Y1986546D02*
Y1992126D01*
G01D02*
X-63741D01*
G01X-7875Y1986546D02*
G03X-1I3937J0D01*
G01X-7875D02*
G03X-1I3937J0D01*
G01X634Y2123670D02*
Y2135077D01*
X-4642Y2126902D01*
X2488D01*
G01X88850Y-38936D02*
X1270445D01*
G01X80167Y27283D02*
G03Y30433I-2017J1575D01*
G01X76133D02*
G03Y27283I2017J-1575D01*
G01X75780Y31220D02*
G03Y26496I2370J-2362D01*
G01X80520D02*
G03Y31220I-2370J2362D01*
G01X81654Y28858D02*
G03I-3504J0D01*
G01X75472Y32008D02*
G03Y25708I2678J-3150D01*
G01X80827D02*
G03Y32008I-2677J3150D01*
G01X72638Y17047D02*
G03I-3740J0D01*
G01X79528Y42047D02*
X82677Y43228D01*
G01X79528Y47047D02*
X82677Y48228D01*
G01X79528Y52047D02*
X82677Y53228D01*
G01X79528Y62047D02*
X82677Y63228D01*
G01X35300Y32421D02*
X31890Y30452D01*
G01X39764Y37342D02*
X38583Y36161D01*
G01X94488Y20137D02*
Y187185D01*
G01X90551Y24074D02*
Y37342D01*
G01X89567Y56948D02*
Y55374D01*
G01X88110Y41948D02*
Y40374D01*
G01Y46948D02*
Y45374D01*
G01Y51948D02*
Y50374D01*
G01Y61948D02*
Y60374D01*
G01Y66948D02*
Y65374D01*
G01X83189D02*
Y66948D01*
G01Y60374D02*
Y61948D01*
G01Y55374D02*
Y56948D01*
G01Y50374D02*
Y51948D01*
G01Y45374D02*
Y46948D01*
G01Y40374D02*
Y41948D01*
G01X82795D02*
Y40374D01*
G01Y46948D02*
Y45374D01*
G01Y51948D02*
Y50374D01*
G01Y56948D02*
Y55374D01*
G01Y61948D02*
Y60374D01*
G01Y66948D02*
Y65374D01*
G01X82677Y20137D02*
Y7185D01*
G01Y39094D02*
Y37342D01*
G01Y44094D02*
Y43228D01*
G01Y49094D02*
Y48228D01*
G01Y54094D02*
Y53228D01*
G01Y59094D02*
Y58228D01*
G01Y64094D02*
Y63228D01*
G01X82008Y41948D02*
Y40374D01*
G01Y46948D02*
Y45374D01*
G01Y51948D02*
Y50374D01*
G01Y56948D02*
Y55374D01*
G01Y61948D02*
Y60374D01*
G01Y66948D02*
Y65374D01*
G01X80433Y41948D02*
Y40374D01*
G01Y46948D02*
Y45374D01*
G01Y51948D02*
Y50374D01*
G01Y56948D02*
Y55374D01*
G01Y61948D02*
Y60374D01*
G01Y66948D02*
Y65374D01*
G01X78740Y11122D02*
Y24074D01*
G01X78543Y16259D02*
Y17834D01*
G01X77756Y57283D02*
Y60039D01*
G01X74803Y40374D02*
Y40275D01*
G01Y42047D02*
Y41948D01*
G01D02*
Y40374D01*
G01Y45374D02*
Y45275D01*
G01Y47047D02*
Y46948D01*
G01D02*
Y45374D01*
G01Y50374D02*
Y50275D01*
G01Y52047D02*
Y51948D01*
G01D02*
Y50374D01*
G01Y60374D02*
Y60275D01*
G01Y62047D02*
Y61948D01*
G01D02*
Y60374D01*
G01Y65374D02*
Y65275D01*
G01Y66948D02*
Y65374D01*
G01X73189Y17834D02*
Y16259D01*
G01X72835Y55374D02*
Y55275D01*
G01Y57047D02*
Y56948D01*
G01D02*
Y55374D01*
G01X71850Y17834D02*
Y18031D01*
G01Y17834D02*
Y16259D01*
G01X71654Y17834D02*
Y16259D01*
G01X70866Y55374D02*
Y56948D01*
G01D02*
Y95374D01*
G01Y35570D02*
Y55374D01*
G01X70079Y24074D02*
Y32421D01*
G01Y16259D02*
Y17834D01*
G01X69685Y58523D02*
Y53799D01*
G01X69587Y37342D02*
Y169980D01*
G01X68209D02*
Y37342D01*
G01X67717Y16259D02*
Y17834D01*
G01X66929Y37342D02*
Y169980D01*
G01X66142Y16259D02*
Y17834D01*
G01X65945Y16259D02*
Y17834D01*
G01Y18031D02*
Y17834D01*
G01X64606Y16259D02*
Y17834D01*
G01X59252D02*
Y16259D01*
G01X59055Y24074D02*
Y183248D01*
G01Y11122D02*
Y24074D01*
G01X55118Y7185D02*
Y20137D01*
G01X46553Y41948D02*
Y40374D01*
G01Y46948D02*
Y45374D01*
G01Y51948D02*
Y50374D01*
G01Y56948D02*
Y55374D01*
G01Y61948D02*
Y60374D01*
G01Y66948D02*
Y65374D01*
G01X45447Y41948D02*
Y40374D01*
G01Y46948D02*
Y45374D01*
G01Y51948D02*
Y50374D01*
G01Y56948D02*
Y55374D01*
G01Y61948D02*
Y60374D01*
G01Y66948D02*
Y65374D01*
G01X45201Y41948D02*
Y40374D01*
G01Y46948D02*
Y45374D01*
G01Y51948D02*
Y50374D01*
G01Y56948D02*
Y55374D01*
G01Y61948D02*
Y60374D01*
G01Y66948D02*
Y65374D01*
G01X41535Y42047D02*
Y40275D01*
G01Y47047D02*
Y45275D01*
G01Y52047D02*
Y50275D01*
G01Y57047D02*
Y55275D01*
G01Y62047D02*
Y60275D01*
G01Y67047D02*
Y65275D01*
G01X41026Y65374D02*
Y66948D01*
G01Y60374D02*
Y61948D01*
G01Y55374D02*
Y56948D01*
G01Y50374D02*
Y51948D01*
G01Y45374D02*
Y46948D01*
G01Y40374D02*
Y41948D01*
G01X40344D02*
Y40374D01*
G01Y46948D02*
Y45374D01*
G01Y51948D02*
Y50374D01*
G01Y56948D02*
Y55374D01*
G01Y61948D02*
Y60374D01*
G01Y66948D02*
Y65374D01*
G01X39764Y37342D02*
Y169980D01*
G01X38583Y32421D02*
Y174901D01*
G01X36614Y25256D02*
Y32421D01*
G01X31890Y28720D02*
Y30452D01*
G01X27953Y187185D02*
Y20137D01*
G01X77559Y57047D02*
X82677Y58228D01*
G01X70866Y65374D02*
X88110D01*
G01X40344D02*
X70866D01*
G01X74803Y65275D02*
X79528D01*
G01X38583D02*
X70866D01*
G01X38583Y62047D02*
X70866D01*
G01X79528D02*
X74803D01*
G01X70866Y61948D02*
X88110D01*
G01X40344D02*
X70866D01*
G01Y60374D02*
X88110D01*
G01X40344D02*
X70866D01*
G01X74803Y60275D02*
X79528D01*
G01X38583D02*
X70866D01*
G01Y60039D02*
X77756D01*
G01X70866Y58523D02*
X69685D01*
G01X77756Y57283D02*
X70866D01*
G01X38583Y57047D02*
X69685D01*
G01X77559D02*
X72835D01*
G01X69685Y56948D02*
X89567D01*
G01X40344D02*
X69685D01*
G01Y55374D02*
X89567D01*
G01X40344D02*
X69685D01*
G01X72835Y55275D02*
X77559D01*
G01X38583D02*
X69685D01*
G01Y53799D02*
X70866D01*
G01X38583Y52047D02*
X70866D01*
G01X79528D02*
X74803D01*
G01X70866Y51948D02*
X88110D01*
G01X40344D02*
X70866D01*
G01Y50374D02*
X88110D01*
G01X40344D02*
X70866D01*
G01X74803Y50275D02*
X79528D01*
G01X38583D02*
X70866D01*
G01X38583Y47047D02*
X70866D01*
G01X79528D02*
X74803D01*
G01X70866Y46948D02*
X88110D01*
G01X40344D02*
X70866D01*
G01Y45374D02*
X88110D01*
G01X40344D02*
X70866D01*
G01X74803Y45275D02*
X79528D01*
G01X38583D02*
X70866D01*
G01X38583Y42047D02*
X70866D01*
G01X79528D02*
X74803D01*
G01X70866Y41948D02*
X88110D01*
G01X40344D02*
X70866D01*
G01Y40374D02*
X88110D01*
G01X40344D02*
X70866D01*
G01X74803Y40275D02*
X79528D01*
G01X38583D02*
X70866D01*
G01X69587Y37342D02*
X70866D01*
G01X39764D02*
X68209D01*
G01X90551D02*
X70866D01*
G01Y35570D02*
X90551D01*
G01X40551Y32421D02*
X90551D01*
G01X35300D02*
X38583D01*
G01X75472Y32008D02*
X80827D01*
G01X80520Y31220D02*
X75780D01*
G01X80167Y30433D02*
X76133D01*
G01X70079Y29468D02*
X90551D01*
G01X59055D02*
X70079D01*
G01X80167Y27283D02*
X76133D01*
G01X75780Y26496D02*
X80520D01*
G01X80827Y25708D02*
X75472D01*
G01X70079Y25256D02*
X36614D01*
G01Y24074D02*
X90551D01*
G01X59055Y22106D02*
X78740D01*
G01X82677Y20137D02*
X94488D01*
G01X55118D02*
X27953D01*
G01X78740Y19015D02*
X59055D01*
G01Y18031D02*
X78740D01*
G01X59252Y17834D02*
X78543D01*
G01X59252Y16259D02*
X78543D01*
G01X38583Y34389D02*
X40551Y32421D01*
G01X31890Y29824D02*
X36610Y25182D01*
G01X36614Y24074D02*
X31890Y28720D01*
G01X82677Y64094D02*
X79528Y65275D01*
G01X82677Y59094D02*
X79528Y60275D01*
G01X82677Y49094D02*
X79528Y50275D01*
G01X82677Y44094D02*
X79528Y45275D01*
G01X82677Y39094D02*
X79528Y40275D01*
G01X82677Y54094D02*
X77559Y55275D01*
G01X78740Y16063D02*
X59055D01*
G01Y15078D02*
X78740D01*
G01X59055Y13090D02*
X78740D01*
G01X59055Y11122D02*
X78740D01*
G01X82677Y7185D02*
X55118D01*
G01X22851Y166544D02*
Y140953D01*
G01X24802Y166544D02*
Y140953D01*
G01X26771Y279930D02*
Y138985D01*
G01X73228Y114901D02*
X75591Y115590D01*
G01X73228Y118051D02*
X75591Y118740D01*
G01X73228Y121200D02*
X75591Y121889D01*
G01X73228Y124350D02*
X75591Y125039D01*
G01X73228Y127500D02*
X75591Y128189D01*
G01X73228Y130649D02*
X75591Y131338D01*
G01X73228Y133799D02*
X75591Y134488D01*
G01X85818Y110872D02*
X85918Y110905D01*
G01X85885Y111102D02*
X85784Y111069D01*
G01X79528Y67047D02*
X82677Y68228D01*
G01X79528Y72047D02*
X82677Y73228D01*
G01X79528Y77047D02*
X82677Y78228D01*
G01X79528Y82047D02*
X82677Y83228D01*
G01X79528Y87047D02*
X82677Y88228D01*
G01X78473Y134114D02*
X78372Y134081D01*
G01X79528Y92047D02*
X82677Y93228D01*
G01X79528Y102047D02*
X82677Y103228D01*
G01X79528Y107047D02*
X82677Y108228D01*
G01X79528Y137047D02*
X82677Y138228D01*
G01X79528Y142047D02*
X82677Y143228D01*
G01X79528Y147047D02*
X82677Y148228D01*
G01X79411Y131817D02*
X79244Y131752D01*
G01X78976Y132867D02*
X79143Y132933D01*
G01X78306Y132834D02*
X78473Y132900D01*
G01X78708Y131850D02*
X78574Y131784D01*
G01X79411Y133261D02*
X79277Y133195D01*
G01X78641Y132014D02*
X78540Y131948D01*
G01X78372Y132670D02*
X78473Y132736D01*
G01X79244Y133392D02*
X79344Y133458D01*
G01X85918Y110905D02*
X86052Y111004D01*
G01X79378Y132014D02*
X79244Y131916D01*
G01X79009Y132670D02*
X79143Y132769D01*
G01X85583Y110413D02*
X85818Y110610D01*
G01X85550D02*
X85315Y110413D01*
G01X85952Y111168D02*
X85885Y111102D01*
G01X79512Y131916D02*
X79411Y131817D01*
G01X78808Y131948D02*
X78708Y131850D01*
G01X79545Y133392D02*
X79411Y133261D01*
G01X78205Y132736D02*
X78306Y132834D01*
G01X78172Y134146D02*
X78306Y134278D01*
G01X40551Y113897D02*
X38583Y111929D01*
G01X86052Y111004D02*
X86153Y111135D01*
G01X78741Y132145D02*
X78641Y132014D01*
G01X78875Y132736D02*
X78976Y132867D01*
G01X78272Y132539D02*
X78372Y132670D01*
G01X79344Y133458D02*
X79411Y133556D01*
G01X78372Y134081D02*
X78306Y133983D01*
G01X79612Y132080D02*
X79512Y131916D01*
G01X78104Y132572D02*
X78205Y132736D01*
G01X79445Y132145D02*
X79378Y132014D01*
G01X78842D02*
X78808Y131948D01*
G01X79612Y133523D02*
X79545Y133392D01*
G01X78942Y132539D02*
X79009Y132670D01*
G01X78842D02*
X78875Y132736D01*
G01X78104Y134015D02*
X78172Y134146D01*
G01X85985Y111266D02*
X85952Y111168D01*
G01X78306Y133983D02*
X78272Y133884D01*
G01X79478Y132276D02*
X79445Y132145D01*
G01X79411Y133556D02*
X79445Y133687D01*
G01X78909Y132408D02*
X78937Y132519D01*
G01D02*
X78942Y132539D01*
G01X78775Y132276D02*
X78741Y132145D01*
G01X78239Y132408D02*
X78267Y132519D01*
G01D02*
X78272Y132539D01*
G01X78071Y133884D02*
X78104Y134015D01*
G01X86153Y111135D02*
X86186Y111299D01*
G01X79646Y132244D02*
X79612Y132080D01*
G01X79646Y133687D02*
X79612Y133523D01*
G01X78071Y132408D02*
X78094Y132519D01*
G01D02*
X78104Y132572D01*
G01X89567Y96948D02*
Y95374D01*
G01Y111948D02*
Y110374D01*
G01X88110Y71948D02*
Y70374D01*
G01Y76948D02*
Y75374D01*
G01Y81948D02*
Y80374D01*
G01Y86948D02*
Y85374D01*
G01Y91948D02*
Y90374D01*
G01Y101948D02*
Y100374D01*
G01Y106948D02*
Y105374D01*
G01Y136948D02*
Y135374D01*
G01Y141948D02*
Y140374D01*
G01Y146948D02*
Y145374D01*
G01X86890Y110216D02*
Y110374D01*
G01Y111948D02*
Y112086D01*
G01Y110374D02*
Y110413D01*
G01Y111889D02*
Y111948D01*
G01X86186Y111299D02*
Y111889D01*
G01X85985D02*
Y111266D01*
G01X85483D02*
Y111889D01*
G01X85315Y110374D02*
Y110216D01*
G01Y112086D02*
Y111948D01*
G01Y110413D02*
Y110374D01*
G01Y111948D02*
Y111299D01*
G01X83189Y145374D02*
Y146948D01*
G01Y140374D02*
Y141948D01*
G01Y135374D02*
Y136948D01*
G01Y110374D02*
Y111948D01*
G01Y105374D02*
Y106948D01*
G01Y100374D02*
Y101948D01*
G01Y95374D02*
Y96948D01*
G01Y90374D02*
Y91948D01*
G01Y85374D02*
Y86948D01*
G01Y80374D02*
Y81948D01*
G01Y75374D02*
Y76948D01*
G01Y70374D02*
Y71948D01*
G01X82795D02*
Y70374D01*
G01Y76948D02*
Y75374D01*
G01Y81948D02*
Y80374D01*
G01Y86948D02*
Y85374D01*
G01Y91948D02*
Y90374D01*
G01Y96948D02*
Y95374D01*
G01Y101948D02*
Y100374D01*
G01Y106948D02*
Y105374D01*
G01Y111948D02*
Y110374D01*
G01Y136948D02*
Y135374D01*
G01Y141948D02*
Y140374D01*
G01Y146948D02*
Y145374D01*
G01X82677Y69094D02*
Y68228D01*
G01Y74094D02*
Y73228D01*
G01Y79094D02*
Y78228D01*
G01Y84094D02*
Y83228D01*
G01Y89094D02*
Y88228D01*
G01Y94094D02*
Y93228D01*
G01Y99094D02*
Y98228D01*
G01Y104094D02*
Y103228D01*
G01Y109094D02*
Y108228D01*
G01Y139094D02*
Y138228D01*
G01Y144094D02*
Y143228D01*
G01Y149094D02*
Y148228D01*
G01X82008Y71948D02*
Y70374D01*
G01Y76948D02*
Y75374D01*
G01Y81948D02*
Y80374D01*
G01Y86948D02*
Y85374D01*
G01Y91948D02*
Y90374D01*
G01Y96948D02*
Y95374D01*
G01Y101948D02*
Y100374D01*
G01Y106948D02*
Y105374D01*
G01Y111948D02*
Y110374D01*
G01Y136948D02*
Y135374D01*
G01Y141948D02*
Y140374D01*
G01Y146948D02*
Y145374D01*
G01X80433Y71948D02*
Y70374D01*
G01Y76948D02*
Y75374D01*
G01Y81948D02*
Y80374D01*
G01Y86948D02*
Y85374D01*
G01Y91948D02*
Y90374D01*
G01Y96948D02*
Y95374D01*
G01Y101948D02*
Y100374D01*
G01Y106948D02*
Y105374D01*
G01Y111948D02*
Y110374D01*
G01Y136948D02*
Y135374D01*
G01Y141948D02*
Y140374D01*
G01Y146948D02*
Y145374D01*
G01X80118Y114803D02*
Y113622D01*
G01Y117952D02*
Y116771D01*
G01Y121102D02*
Y119921D01*
G01Y127401D02*
Y126220D01*
G01Y124252D02*
Y123070D01*
G01Y130551D02*
Y129370D01*
G01Y133700D02*
Y132519D01*
G01X79646Y133950D02*
Y133700D01*
G01Y132441D02*
Y132244D01*
G01Y133700D02*
Y133687D01*
G01X79478Y132408D02*
Y132276D01*
G01X79445Y133700D02*
Y133950D01*
G01Y133687D02*
Y133700D01*
G01X79210Y134212D02*
Y134409D01*
G01X78942Y133884D02*
Y133700D01*
G01D02*
Y133687D01*
G01X78937Y112637D02*
Y112047D01*
G01Y135275D02*
Y134685D01*
G01X78909Y132276D02*
Y132408D01*
G01X78775D02*
Y132276D01*
G01X78741Y133700D02*
Y133884D01*
G01Y133687D02*
Y133700D01*
G01X78440Y133491D02*
Y133294D01*
G01X78272Y133884D02*
Y133700D01*
G01D02*
Y133687D01*
G01X78239Y132276D02*
Y132408D01*
G01X78071Y133720D02*
Y133884D01*
G01Y132276D02*
Y132408D01*
G01X77756Y142283D02*
Y145039D01*
G01Y107283D02*
Y110039D01*
G01Y82283D02*
Y85039D01*
G01X75591Y112834D02*
Y112637D01*
G01Y115984D02*
Y115590D01*
G01Y122283D02*
Y121889D01*
G01Y119133D02*
Y118740D01*
G01Y125433D02*
Y125039D01*
G01Y131732D02*
Y131338D01*
G01Y128582D02*
Y128189D01*
G01Y134685D02*
Y134488D01*
G01X75512Y132519D02*
Y133700D01*
G01Y129370D02*
Y130551D01*
G01Y123070D02*
Y124252D01*
G01Y126220D02*
Y127401D01*
G01Y119921D02*
Y121102D01*
G01Y113622D02*
Y114803D01*
G01Y116771D02*
Y117952D01*
G01X75118D02*
Y116771D01*
G01Y114803D02*
Y113622D01*
G01Y121102D02*
Y119921D01*
G01Y127401D02*
Y126220D01*
G01Y124252D02*
Y123070D01*
G01Y130551D02*
Y129370D01*
G01Y133700D02*
Y132519D01*
G01X74803Y67047D02*
Y66948D01*
G01Y70374D02*
Y70275D01*
G01Y72047D02*
Y71948D01*
G01Y75374D02*
Y75275D01*
G01Y71948D02*
Y70374D01*
G01Y77047D02*
Y76948D01*
G01Y80374D02*
Y80275D01*
G01Y76948D02*
Y75374D01*
G01Y82047D02*
Y81948D01*
G01Y85374D02*
Y85275D01*
G01Y81948D02*
Y80374D01*
G01Y87047D02*
Y86948D01*
G01D02*
Y85374D01*
G01Y90374D02*
Y90275D01*
G01Y92047D02*
Y91948D01*
G01D02*
Y90374D01*
G01Y100374D02*
Y100275D01*
G01Y102047D02*
Y101948D01*
G01D02*
Y100374D01*
G01Y105374D02*
Y105275D01*
G01Y107047D02*
Y106948D01*
G01D02*
Y105374D01*
G01Y110374D02*
Y110275D01*
G01Y112047D02*
Y111948D01*
G01D02*
Y110374D01*
G01Y135374D02*
Y135275D01*
G01Y137047D02*
Y136948D01*
G01D02*
Y135374D01*
G01Y140374D02*
Y140275D01*
G01Y142047D02*
Y141948D01*
G01Y145374D02*
Y145275D01*
G01Y141948D02*
Y140374D01*
G01Y147047D02*
Y146948D01*
G01D02*
Y145374D01*
G01X74331Y114803D02*
Y113622D01*
G01Y117952D02*
Y116771D01*
G01Y121102D02*
Y119921D01*
G01Y124252D02*
Y123070D01*
G01Y127401D02*
Y126220D01*
G01Y130551D02*
Y129370D01*
G01Y133700D02*
Y132519D01*
G01X72835Y95374D02*
Y95275D01*
G01Y97047D02*
Y96948D01*
G01D02*
Y95374D01*
G01X72756Y114803D02*
Y113622D01*
G01Y117952D02*
Y116771D01*
G01Y121102D02*
Y119921D01*
G01Y124252D02*
Y123070D01*
G01Y127401D02*
Y126220D01*
G01Y130551D02*
Y129370D01*
G01Y133700D02*
Y132519D01*
G01X70866Y133700D02*
Y171752D01*
G01Y130551D02*
Y132519D01*
G01D02*
Y133700D01*
G01Y127401D02*
Y129370D01*
G01D02*
Y130551D01*
G01Y124252D02*
Y126220D01*
G01D02*
Y127401D01*
G01Y123070D02*
Y124252D01*
G01Y121102D02*
Y123070D01*
G01Y117952D02*
Y119921D01*
G01D02*
Y121102D01*
G01Y114803D02*
Y116771D01*
G01D02*
Y117952D01*
G01Y113622D02*
Y114803D01*
G01Y95374D02*
Y96948D01*
G01D02*
Y113622D01*
G01X69685Y98523D02*
Y93799D01*
G01X68110Y135866D02*
Y111456D01*
G01X51039Y114803D02*
Y113622D01*
G01Y117952D02*
Y116771D01*
G01Y121102D02*
Y119921D01*
G01Y124252D02*
Y123070D01*
G01Y127401D02*
Y126220D01*
G01Y130551D02*
Y129370D01*
G01Y133700D02*
Y132519D01*
G01X48800Y114803D02*
Y113622D01*
G01Y117952D02*
Y116771D01*
G01Y121102D02*
Y119921D01*
G01Y124252D02*
Y123070D01*
G01Y127401D02*
Y126220D01*
G01Y130551D02*
Y129370D01*
G01Y133700D02*
Y132519D01*
G01X48302D02*
Y133700D01*
G01Y129370D02*
Y130551D01*
G01Y126220D02*
Y127401D01*
G01Y123070D02*
Y124252D01*
G01Y119921D02*
Y121102D01*
G01Y113622D02*
Y114803D01*
G01Y116771D02*
Y117952D01*
G01X47559Y132421D02*
Y133799D01*
G01Y113523D02*
Y114901D01*
G01Y118051D02*
Y116673D01*
G01Y121200D02*
Y119822D01*
G01Y127500D02*
Y126122D01*
G01Y124350D02*
Y122972D01*
G01Y130649D02*
Y129271D01*
G01X46553Y71948D02*
Y70374D01*
G01Y76948D02*
Y75374D01*
G01Y81948D02*
Y80374D01*
G01Y86948D02*
Y85374D01*
G01Y91948D02*
Y90374D01*
G01Y96948D02*
Y95374D01*
G01Y101948D02*
Y100374D01*
G01Y106948D02*
Y105374D01*
G01Y111948D02*
Y110374D01*
G01Y136948D02*
Y135374D01*
G01Y141948D02*
Y140374D01*
G01Y146948D02*
Y145374D01*
G01X45447Y71948D02*
Y70374D01*
G01Y76948D02*
Y75374D01*
G01Y81948D02*
Y80374D01*
G01Y86948D02*
Y85374D01*
G01Y91948D02*
Y90374D01*
G01Y96948D02*
Y95374D01*
G01Y101948D02*
Y100374D01*
G01Y106948D02*
Y105374D01*
G01Y111948D02*
Y110374D01*
G01Y136948D02*
Y135374D01*
G01Y141948D02*
Y140374D01*
G01Y146948D02*
Y145374D01*
G01X45201Y135374D02*
Y136948D01*
G01Y110374D02*
Y111948D01*
G01Y71948D02*
Y70374D01*
G01Y76948D02*
Y75374D01*
G01Y81948D02*
Y80374D01*
G01Y86948D02*
Y85374D01*
G01Y91948D02*
Y90374D01*
G01Y96948D02*
Y95374D01*
G01Y101948D02*
Y100374D01*
G01Y106948D02*
Y105374D01*
G01Y141948D02*
Y140374D01*
G01Y146948D02*
Y145374D01*
G01X42744Y114803D02*
Y113622D01*
G01Y117952D02*
Y116771D01*
G01Y121102D02*
Y119921D01*
G01Y127401D02*
Y126220D01*
G01Y124252D02*
Y123070D01*
G01Y130551D02*
Y129370D01*
G01Y133700D02*
Y132519D01*
G01X42006D02*
Y133700D01*
G01Y129370D02*
Y130551D01*
G01Y126220D02*
Y127401D01*
G01Y123070D02*
Y124252D01*
G01Y119921D02*
Y121102D01*
G01Y113622D02*
Y114803D01*
G01Y116771D02*
Y117952D01*
G01X41535Y72047D02*
Y70275D01*
G01Y77047D02*
Y75275D01*
G01Y82047D02*
Y80275D01*
G01Y87047D02*
Y85275D01*
G01Y92047D02*
Y90275D01*
G01Y97047D02*
Y95275D01*
G01Y102047D02*
Y100275D01*
G01Y107047D02*
Y105275D01*
G01Y112047D02*
Y110275D01*
G01Y137047D02*
Y135275D01*
G01Y142047D02*
Y140275D01*
G01Y147047D02*
Y145275D01*
G01X41454Y135374D02*
Y136948D01*
G01Y110374D02*
Y111948D01*
G01X41026Y145374D02*
Y146948D01*
G01Y140374D02*
Y141948D01*
G01Y105374D02*
Y106948D01*
G01Y100374D02*
Y101948D01*
G01Y95374D02*
Y96948D01*
G01Y90374D02*
Y91948D01*
G01Y85374D02*
Y86948D01*
G01Y80374D02*
Y81948D01*
G01Y75374D02*
Y76948D01*
G01Y70374D02*
Y71948D01*
G01X40551Y111456D02*
Y135866D01*
G01X40465Y111948D02*
Y110374D01*
G01Y136948D02*
Y135374D01*
G01X40344Y71948D02*
Y70374D01*
G01Y76948D02*
Y75374D01*
G01Y81948D02*
Y80374D01*
G01Y86948D02*
Y85374D01*
G01Y91948D02*
Y90374D01*
G01Y96948D02*
Y95374D01*
G01Y101948D02*
Y100374D01*
G01Y106948D02*
Y105374D01*
G01Y141948D02*
Y140374D01*
G01Y146948D02*
Y145374D01*
G01X38780Y132421D02*
Y133799D01*
G01Y129271D02*
Y130649D01*
G01Y122972D02*
Y124350D01*
G01Y126122D02*
Y127500D01*
G01Y119822D02*
Y121200D01*
G01Y116673D02*
Y118051D01*
G01Y114901D02*
Y113523D01*
G01X85315Y111299D02*
X85348Y111135D01*
G01X79612Y134114D02*
X79646Y133950D01*
G01X79630Y132519D02*
X79646Y132441D01*
G01X79612Y132605D02*
X79630Y132519D01*
G01X78775Y133523D02*
X78741Y133687D01*
G01X78075Y133700D02*
X78071Y133720D01*
G01X78104Y133556D02*
X78075Y133700D01*
G01X78104Y132113D02*
X78071Y132276D01*
G01X79445Y133950D02*
X79411Y134081D01*
G01X79450Y132519D02*
X79478Y132408D01*
G01X79445Y132539D02*
X79450Y132519D01*
G01X78909Y134015D02*
X78942Y133884D01*
G01Y133687D02*
X78976Y133556D01*
G01X78942Y132145D02*
X78909Y132276D01*
G01X78746Y132519D02*
X78775Y132408D01*
G01X78741Y132539D02*
X78746Y132519D01*
G01X78272Y132145D02*
X78239Y132276D01*
G01X78741Y133884D02*
X78708Y133983D01*
G01X78272Y133687D02*
X78306Y133589D01*
G01X85516Y111168D02*
X85483Y111266D01*
G01X78306Y134278D02*
X78440Y134311D01*
G01X78842Y134146D02*
X78909Y134015D01*
G01X79378Y132670D02*
X79445Y132539D01*
G01X78842Y133392D02*
X78775Y133523D01*
G01X78808Y132736D02*
X78842Y132670D01*
G01X79009Y132014D02*
X78942Y132145D01*
G01X78875Y131948D02*
X78842Y132014D01*
G01X79512Y134278D02*
X79612Y134114D01*
G01X79512Y132769D02*
X79612Y132605D01*
G01X77559Y97047D02*
X82677Y98228D01*
G01X78205Y131948D02*
X78104Y132113D01*
G01X78708Y133983D02*
X78641Y134081D01*
G01X78976Y133556D02*
X79043Y133458D01*
G01X78205Y133425D02*
X78104Y133556D01*
G01X78641Y132670D02*
X78741Y132539D01*
G01X78976Y131817D02*
X78875Y131948D01*
G01X78372Y132014D02*
X78272Y132145D01*
G01X85348Y111135D02*
X85449Y111004D01*
G01X38583Y147047D02*
X70866D01*
G01X79528D02*
X74803D01*
G01X70866Y146948D02*
X88110D01*
G01X40344D02*
X70866D01*
G01Y145374D02*
X88110D01*
G01X40344D02*
X70866D01*
G01X74803Y145275D02*
X79528D01*
G01X38583D02*
X70866D01*
G01Y145039D02*
X77756D01*
G01Y142283D02*
X70866D01*
G01X38583Y142047D02*
X70866D01*
G01X79528D02*
X74803D01*
G01X70866Y141948D02*
X88110D01*
G01X40344D02*
X70866D01*
G01Y140374D02*
X88110D01*
G01X40344D02*
X70866D01*
G01X74803Y140275D02*
X79528D01*
G01X38583D02*
X70866D01*
G01X41535Y137047D02*
X70866D01*
G01X79528D02*
X74803D01*
G01X70866Y136948D02*
X88110D01*
G01X40465D02*
X70866D01*
G01X38583Y135866D02*
X70866D01*
G01Y135374D02*
X88110D01*
G01X40465D02*
X70866D01*
G01X74803Y135275D02*
X78937D01*
G01X41535D02*
X70866D01*
G01X78937Y134685D02*
X75591D01*
G01X78440Y134311D02*
X78574D01*
G01X78540Y134114D02*
X78473D01*
G01X38780Y133799D02*
X68110D01*
G01X38780D02*
X38583D01*
G01X73228D02*
X70866D01*
G01X68110Y133700D02*
X80118D01*
G01X42006D02*
X68110D01*
G01X40551Y133425D02*
X59055D01*
G01X79143Y133392D02*
X79244D01*
G01X79277Y133195D02*
X79110D01*
G01X79143Y132933D02*
X79244D01*
G01X78473Y132900D02*
X78574D01*
G01X79143Y132769D02*
X79244D01*
G01X78473Y132736D02*
X78540D01*
G01X68110Y132519D02*
X80118D01*
G01X68110D02*
X42006D01*
G01X38780Y132421D02*
X68110D01*
G01X38583D02*
X38780D01*
G01X73228D02*
X70866D01*
G01X78540Y131948D02*
X78473D01*
G01X79244Y131916D02*
X79143D01*
G01X78574Y131784D02*
X78473D01*
G01X79244Y131752D02*
X79143D01*
G01X38780Y130649D02*
X68110D01*
G01X38780D02*
X38583D01*
G01X73228D02*
X70866D01*
G01X68110Y130551D02*
X80118D01*
G01X42006D02*
X68110D01*
G01Y129370D02*
X80118D01*
G01X68110D02*
X42006D01*
G01X38780Y129271D02*
X68110D01*
G01X38583D02*
X38780D01*
G01X73228D02*
X70866D01*
G01X38780Y127500D02*
X68110D01*
G01X38780D02*
X38583D01*
G01X73228D02*
X70866D01*
G01X68110Y127401D02*
X80118D01*
G01X42006D02*
X68110D01*
G01Y126220D02*
X80118D01*
G01X68110D02*
X42006D01*
G01X38780Y126122D02*
X68110D01*
G01X38583D02*
X38780D01*
G01X73228D02*
X70866D01*
G01X38780Y124350D02*
X68110D01*
G01X38780D02*
X38583D01*
G01X73228D02*
X70866D01*
G01X68110Y124252D02*
X80118D01*
G01X42006D02*
X68110D01*
G01Y123070D02*
X80118D01*
G01X68110D02*
X42006D01*
G01X38780Y122972D02*
X68110D01*
G01X38583D02*
X38780D01*
G01X73228D02*
X70866D01*
G01X38780Y121200D02*
X68110D01*
G01X38780D02*
X38583D01*
G01X73228D02*
X70866D01*
G01X68110Y121102D02*
X80118D01*
G01X42006D02*
X68110D01*
G01Y119921D02*
X80118D01*
G01X68110D02*
X42006D01*
G01X38780Y119822D02*
X68110D01*
G01X38583D02*
X38780D01*
G01X73228D02*
X70866D01*
G01X38780Y118051D02*
X68110D01*
G01X38780D02*
X38583D01*
G01X73228D02*
X70866D01*
G01X68110Y117952D02*
X80118D01*
G01X42006D02*
X68110D01*
G01Y116771D02*
X80118D01*
G01X68110D02*
X42006D01*
G01X38780Y116673D02*
X68110D01*
G01X38583D02*
X38780D01*
G01X73228D02*
X70866D01*
G01X38780Y114901D02*
X38583D01*
G01X68110D02*
X38780D01*
G01X73228D02*
X70866D01*
G01X68110Y114803D02*
X80118D01*
G01X42006D02*
X68110D01*
G01X59055Y113897D02*
X40551D01*
G01X68110Y113622D02*
X80118D01*
G01X68110D02*
X42006D01*
G01X38583Y113523D02*
X38780D01*
G01X68110D02*
X38780D01*
G01X73228D02*
X70866D01*
G01X75591Y112637D02*
X78937D01*
G01X86890Y112086D02*
X85315D01*
G01X70866Y112047D02*
X41535D01*
G01X78937D02*
X74803D01*
G01X70866Y111948D02*
X89567D01*
G01X40465D02*
X70866D01*
G01X85483Y111889D02*
X85985D01*
G01X86186D02*
X86890D01*
G01X38583Y111456D02*
X70866D01*
G01X85784Y111069D02*
X85684D01*
G01Y110872D02*
X85818D01*
G01Y110610D02*
X85550D01*
G01X86890Y110413D02*
X85583D01*
G01X70866Y110374D02*
X89567D01*
G01X40465D02*
X70866D01*
G01X74803Y110275D02*
X79528D01*
G01X41535D02*
X70866D01*
G01X85315Y110216D02*
X86890D01*
G01X70866Y110039D02*
X77756D01*
G01Y107283D02*
X70866D01*
G01X38583Y107047D02*
X70866D01*
G01X79528D02*
X74803D01*
G01X70866Y106948D02*
X88110D01*
G01X40344D02*
X70866D01*
G01Y105374D02*
X88110D01*
G01X40344D02*
X70866D01*
G01X74803Y105275D02*
X79528D01*
G01X38583D02*
X70866D01*
G01X38583Y102047D02*
X70866D01*
G01X79528D02*
X74803D01*
G01X70866Y101948D02*
X88110D01*
G01X40344D02*
X70866D01*
G01Y100374D02*
X88110D01*
G01X40344D02*
X70866D01*
G01X74803Y100275D02*
X79528D01*
G01X38583D02*
X70866D01*
G01Y98523D02*
X69685D01*
G01X38583Y97047D02*
X69685D01*
G01X77559D02*
X72835D01*
G01X69685Y96948D02*
X89567D01*
G01X40344D02*
X69685D01*
G01Y95374D02*
X89567D01*
G01X40344D02*
X69685D01*
G01X72835Y95275D02*
X77559D01*
G01X38583D02*
X69685D01*
G01Y93799D02*
X70866D01*
G01X40551Y133425D02*
X38583Y135393D01*
G01X79411Y134081D02*
X79311Y134180D01*
G01X78708Y134278D02*
X78842Y134146D01*
G01X79411Y132867D02*
X79512Y132769D01*
G01X78976Y133261D02*
X78842Y133392D01*
G01X78306Y133589D02*
X78372Y133523D01*
G01X78708Y132834D02*
X78808Y132736D01*
G01X78306Y131850D02*
X78205Y131948D01*
G01X85583Y111102D02*
X85516Y111168D01*
G01X79244Y132769D02*
X79378Y132670D01*
G01X78339Y133326D02*
X78205Y133425D01*
G01X79143Y131916D02*
X79009Y132014D01*
G01X85449Y111004D02*
X85583Y110905D01*
G01X79043Y133458D02*
X79143Y133392D01*
G01X78540Y132736D02*
X78641Y132670D01*
G01X78473Y131948D02*
X78372Y132014D01*
G01X79344Y134376D02*
X79512Y134278D01*
G01X79110Y133195D02*
X78976Y133261D01*
G01X78372Y133523D02*
X78440Y133491D01*
G01X78574Y132900D02*
X78708Y132834D01*
G01X79244Y132933D02*
X79411Y132867D01*
G01X79143Y131752D02*
X78976Y131817D01*
G01X78473Y131784D02*
X78306Y131850D01*
G01X82677Y149094D02*
X79528Y150275D01*
G01X82677Y144094D02*
X79528Y145275D01*
G01X82677Y139094D02*
X79528Y140275D01*
G01X79311Y134180D02*
X79210Y134212D01*
G01X78641Y134081D02*
X78540Y134114D01*
G01X78440Y133294D02*
X78339Y133326D01*
G01X85684Y111069D02*
X85583Y111102D01*
G01Y110905D02*
X85684Y110872D01*
G01X75591Y131732D02*
X73228Y132421D01*
G01X75591Y128582D02*
X73228Y129271D01*
G01X75591Y125433D02*
X73228Y126122D01*
G01X75591Y122283D02*
X73228Y122972D01*
G01X75591Y119133D02*
X73228Y119822D01*
G01X75591Y115984D02*
X73228Y116673D01*
G01X75591Y112834D02*
X73228Y113523D01*
G01X79210Y134409D02*
X79344Y134376D01*
G01X78574Y134311D02*
X78708Y134278D01*
G01X82677Y94094D02*
X77559Y95275D01*
G01X38583Y92047D02*
X70866D01*
G01X79528D02*
X74803D01*
G01X70866Y91948D02*
X88110D01*
G01X40344D02*
X70866D01*
G01Y90374D02*
X88110D01*
G01X40344D02*
X70866D01*
G01X74803Y90275D02*
X79528D01*
G01X38583D02*
X70866D01*
G01X38583Y87047D02*
X70866D01*
G01X79528D02*
X74803D01*
G01X70866Y86948D02*
X88110D01*
G01X40344D02*
X70866D01*
G01Y85374D02*
X88110D01*
G01X40344D02*
X70866D01*
G01X74803Y85275D02*
X79528D01*
G01X38583D02*
X70866D01*
G01Y85039D02*
X77756D01*
G01Y82283D02*
X70866D01*
G01X38583Y82047D02*
X70866D01*
G01X79528D02*
X74803D01*
G01X70866Y81948D02*
X88110D01*
G01X40344D02*
X70866D01*
G01Y80374D02*
X88110D01*
G01X40344D02*
X70866D01*
G01X74803Y80275D02*
X79528D01*
G01X38583D02*
X70866D01*
G01X38583Y77047D02*
X70866D01*
G01X79528D02*
X74803D01*
G01X70866Y76948D02*
X88110D01*
G01X40344D02*
X70866D01*
G01Y75374D02*
X88110D01*
G01X40344D02*
X70866D01*
G01X74803Y75275D02*
X79528D01*
G01X38583D02*
X70866D01*
G01X38583Y72047D02*
X70866D01*
G01X79528D02*
X74803D01*
G01X70866Y71948D02*
X88110D01*
G01X40344D02*
X70866D01*
G01Y70374D02*
X88110D01*
G01X40344D02*
X70866D01*
G01X74803Y70275D02*
X79528D01*
G01X38583D02*
X70866D01*
G01X38583Y67047D02*
X70866D01*
G01X79528D02*
X74803D01*
G01X70866Y66948D02*
X88110D01*
G01X40344D02*
X70866D01*
G01X82677Y109094D02*
X79528Y110275D01*
G01X82677Y104094D02*
X79528Y105275D01*
G01X82677Y99094D02*
X79528Y100275D01*
G01X82677Y89094D02*
X79528Y90275D01*
G01X82677Y84094D02*
X79528Y85275D01*
G01X82677Y79094D02*
X79528Y80275D01*
G01X82677Y74094D02*
X79528Y75275D01*
G01X82677Y69094D02*
X79528Y70275D01*
G01X14688Y172611D02*
X15464Y172414D01*
G01X16248D02*
X15472Y172611D01*
G01X14688Y176548D02*
X15464Y176351D01*
G01X16248D02*
X15472Y176548D01*
G01X14688Y180485D02*
X15464Y180288D01*
G01X16248D02*
X15472Y180485D01*
G01Y171272D02*
X12829D01*
G01X16248Y171469D02*
X15464D01*
G01X16248Y172414D02*
X15464D01*
G01X15472Y172611D02*
X12829D01*
G01X15472Y175209D02*
X12829D01*
G01X16248Y175406D02*
X15464D01*
G01X16248Y176351D02*
X15464D01*
G01X15472Y176548D02*
X12829D01*
G01X15472Y179146D02*
X12829D01*
G01X16248Y179343D02*
X15464D01*
G01X16248Y180288D02*
X15464D01*
G01X15472Y180485D02*
X12829D01*
G01X15472Y183083D02*
X12829D01*
G01X16248Y183280D02*
X15464D01*
G01X15472Y171272D02*
X16248Y171469D01*
G01X15464D02*
X14688Y171272D01*
G01X15472Y175209D02*
X16248Y175406D01*
G01X15464D02*
X14688Y175209D01*
G01X15472Y179146D02*
X16248Y179343D01*
G01X15464D02*
X14688Y179146D01*
G01X15472Y183083D02*
X16248Y183280D01*
G01X15464D02*
X14688Y183083D01*
G01X12829Y171272D02*
Y172611D01*
G01Y175209D02*
Y176548D01*
G01Y179146D02*
Y180485D01*
G01Y183083D02*
Y184422D01*
G01X13613D02*
Y183083D01*
G01Y180485D02*
Y179146D01*
G01Y176548D02*
Y175209D01*
G01Y172611D02*
Y171272D01*
G01X15464Y184225D02*
Y183280D01*
G01Y180288D02*
Y179343D01*
G01Y176351D02*
Y175406D01*
G01Y172414D02*
Y171469D01*
G01X16248D02*
Y172414D01*
G01Y175406D02*
Y176351D01*
G01Y179343D02*
Y180288D01*
G01Y183280D02*
Y184225D01*
G01X14688Y184422D02*
X15464Y184225D01*
G01X16248D02*
X15472Y184422D01*
G01X14688Y188359D02*
X15464Y188162D01*
G01X16248D02*
X15472Y188359D01*
G01X14688Y192296D02*
X15464Y192099D01*
G01X16248D02*
X15472Y192296D01*
G01X14688Y196233D02*
X15464Y196036D01*
G01X16248D02*
X15472Y196233D01*
G01X14688Y200170D02*
X15464Y199973D01*
G01X16248D02*
X15472Y200170D01*
G01X14688Y204107D02*
X15464Y203910D01*
G01X16248D02*
X15472Y204107D01*
G01X16248Y184225D02*
X15464D01*
G01X15472Y184422D02*
X12829D01*
G01X15472Y187020D02*
X12829D01*
G01X16248Y187217D02*
X15464D01*
G01X16248Y188162D02*
X15464D01*
G01X15472Y188359D02*
X12829D01*
G01X15472Y190957D02*
X12829D01*
G01X16248Y191154D02*
X15464D01*
G01X16248Y192099D02*
X15464D01*
G01X15472Y192296D02*
X12829D01*
G01X15472Y194894D02*
X12829D01*
G01X16248Y195091D02*
X15464D01*
G01X16248Y196036D02*
X15464D01*
G01X15472Y196233D02*
X12829D01*
G01X15472Y198831D02*
X12829D01*
G01X16248Y199028D02*
X15464D01*
G01X16248Y199973D02*
X15464D01*
G01X15472Y200170D02*
X12829D01*
G01X15472Y202768D02*
X12829D01*
G01X16248Y202965D02*
X15464D01*
G01X16248Y203910D02*
X15464D01*
G01X15472Y204107D02*
X12829D01*
G01X15472Y187020D02*
X16248Y187217D01*
G01X15464D02*
X14688Y187020D01*
G01X15472Y190957D02*
X16248Y191154D01*
G01X15464D02*
X14688Y190957D01*
G01X15472Y194894D02*
X16248Y195091D01*
G01X15464D02*
X14688Y194894D01*
G01X15472Y198831D02*
X16248Y199028D01*
G01X15464D02*
X14688Y198831D01*
G01X15472Y202768D02*
X16248Y202965D01*
G01X15464D02*
X14688Y202768D01*
G01X12829Y187020D02*
Y188359D01*
G01Y190957D02*
Y192296D01*
G01Y194894D02*
Y196233D01*
G01Y198831D02*
Y200170D01*
G01Y202768D02*
Y204107D01*
G01X13613D02*
Y202768D01*
G01Y200170D02*
Y198831D01*
G01Y196233D02*
Y194894D01*
G01Y192296D02*
Y190957D01*
G01Y188359D02*
Y187020D01*
G01X15464Y203910D02*
Y202965D01*
G01Y199973D02*
Y199028D01*
G01Y196036D02*
Y195091D01*
G01Y192099D02*
Y191154D01*
G01Y188162D02*
Y187217D01*
G01X16248D02*
Y188162D01*
G01Y191154D02*
Y192099D01*
G01Y195091D02*
Y196036D01*
G01Y199028D02*
Y199973D01*
G01Y202965D02*
Y203910D01*
G01X14688Y208044D02*
X15464Y207847D01*
G01X16248D02*
X15472Y208044D01*
G01X14688Y211981D02*
X15464Y211784D01*
G01X16248D02*
X15472Y211981D01*
G01X14688Y223792D02*
X15464Y223595D01*
G01X16248D02*
X15472Y223792D01*
G01X15550Y220845D02*
X18700Y219711D01*
G01X15472Y206705D02*
X12829D01*
G01X16248Y206902D02*
X15464D01*
G01X16248Y207847D02*
X15464D01*
G01X15472Y208044D02*
X12829D01*
G01X15472Y210642D02*
X12829D01*
G01X16248Y210839D02*
X15464D01*
G01X16248Y211784D02*
X15464D01*
G01X15472Y211981D02*
X12829D01*
G01X15472Y222453D02*
X12829D01*
G01X16248Y222650D02*
X15464D01*
G01X16248Y223595D02*
X15464D01*
G01X15472Y223792D02*
X12829D01*
G01X15472Y206705D02*
X16248Y206902D01*
G01X15464D02*
X14688Y206705D01*
G01X15472Y210642D02*
X16248Y210839D01*
G01X15464D02*
X14688Y210642D01*
G01X15472Y222453D02*
X16248Y222650D01*
G01X15464D02*
X14688Y222453D01*
G01X12829Y210642D02*
Y211981D01*
G01Y206705D02*
Y208044D01*
G01Y222453D02*
Y223792D01*
G01X13613D02*
Y222453D01*
G01Y211981D02*
Y210642D01*
G01Y208044D02*
Y206705D01*
G01X15464Y223595D02*
Y222650D01*
G01Y211784D02*
Y210839D01*
G01Y207847D02*
Y206902D01*
G01X15550Y220845D02*
Y213837D01*
G01X16248Y210839D02*
Y211784D01*
G01Y206902D02*
Y207847D01*
G01Y222650D02*
Y223595D01*
G01X18700Y219711D02*
Y214971D01*
G01X15550Y213837D02*
X18700Y214971D01*
G01X19881Y213583D02*
G03Y221063I0J3740D01*
G01X14688Y227729D02*
X15464Y227532D01*
G01X16248D02*
X15472Y227729D01*
G01X14688Y231666D02*
X15464Y231469D01*
G01X16248D02*
X15472Y231666D01*
G01Y226390D02*
X12829D01*
G01X16248Y226587D02*
X15464D01*
G01X16248Y227532D02*
X15464D01*
G01X15472Y227729D02*
X12829D01*
G01X15472Y230327D02*
X12829D01*
G01X16248Y230524D02*
X15464D01*
G01X16248Y231469D02*
X15464D01*
G01X15472Y231666D02*
X12829D01*
G01X15472Y226390D02*
X16248Y226587D01*
G01X15464D02*
X14688Y226390D01*
G01X15472Y230327D02*
X16248Y230524D01*
G01X15464D02*
X14688Y230327D01*
G01X12829Y226390D02*
Y227729D01*
G01Y230327D02*
Y231666D01*
G01X13613D02*
Y230327D01*
G01Y227729D02*
Y226390D01*
G01X15464Y231469D02*
Y230524D01*
G01Y227532D02*
Y226587D01*
G01X16248D02*
Y227532D01*
G01Y230524D02*
Y231469D01*
G01X98424Y204094D02*
X66495D01*
G01Y263150D02*
Y204094D01*
G01X65747Y205472D02*
X72046D01*
G01X67322Y205768D02*
X65747D01*
G01D02*
X64172D01*
G01X65851Y206244D02*
X65758D01*
G01Y206992D02*
X65851D01*
G01X65747Y207736D02*
X67322D01*
G01X64172D02*
X65747D01*
G01Y208327D02*
X67322D01*
G01X64172D02*
X65747D01*
G01X67322Y210295D02*
X65747D01*
G01D02*
X64172D01*
G01X65747Y210591D02*
X72046D01*
G01X64172Y210295D02*
Y208327D01*
G01Y205768D02*
Y207736D01*
G01X65664Y206754D02*
Y206881D01*
G01X65747Y210591D02*
Y210000D01*
G01Y208819D02*
Y207244D01*
G01Y206063D02*
Y205472D01*
G01X65758Y206244D02*
Y206865D01*
G01X65851Y206992D02*
Y206244D01*
G01X66731Y205472D02*
Y210591D01*
G01X66928D02*
Y205472D01*
G01X67322Y207736D02*
Y205768D01*
G01Y208327D02*
Y210295D01*
G01X65664Y206881D02*
X65758Y206992D01*
G01Y206865D02*
X65664Y206754D01*
G01X65747Y208819D02*
G03Y210000I0J590D01*
G01Y206063D02*
G03Y207244I0J590D01*
G01X81518Y223598D02*
X82146Y223187D01*
G01X70471Y205768D02*
X72046D01*
G01D02*
X73621D01*
G01X72046Y207736D02*
X70471D01*
G01X73621D02*
X72046D01*
G01Y208327D02*
X70471D01*
G01X73621D02*
X72046D01*
G01X85078Y209449D02*
X75235D01*
G01X70471Y210295D02*
X72046D01*
G01D02*
X73621D01*
G01X75235Y210679D02*
X79214D01*
G01X80471D02*
X85078D01*
G01Y216420D02*
X80471D01*
G01X79214D02*
X75235D01*
G01Y217651D02*
X85078D01*
G01X80052Y219291D02*
X77958Y223187D01*
G01X78586Y223598D02*
X80052Y220727D01*
G01X70471Y207736D02*
Y205768D01*
G01Y208327D02*
Y210295D01*
G01X70865Y210591D02*
Y205472D01*
G01X71062D02*
Y210591D01*
G01X72046Y205472D02*
Y206063D01*
G01Y210000D02*
Y210591D01*
G01Y207244D02*
Y208819D01*
G01X73621Y210295D02*
Y208327D01*
G01Y205768D02*
Y207736D01*
G01X75235Y209449D02*
Y210679D01*
G01Y216420D02*
Y217651D01*
G01X79214Y210679D02*
Y216420D01*
G01X80471D02*
Y210679D01*
G01X85078Y217651D02*
Y216420D01*
G01Y210679D02*
Y209449D01*
G01X80052Y220727D02*
X81518Y223598D01*
G01X82146Y223187D02*
X80052Y219291D01*
G01X77958Y223187D02*
X78586Y223598D01*
G01X72046Y210000D02*
G03Y208819I0J-591D01*
G01Y207244D02*
G03Y206063I0J-591D01*
G01X77539Y229544D02*
X76701Y229749D01*
G01X76911Y230980D02*
X77539Y230569D01*
G01X76701Y225238D02*
X75235Y226468D01*
G01X76911D02*
X78377Y225238D01*
G01X76701Y229749D02*
X75864Y230569D01*
G01X84031Y229339D02*
X78795Y235080D01*
G01X79424Y236106D02*
X84031Y230980D01*
G01X78377Y225238D02*
X76701D01*
G01X85078Y226468D02*
X76911D01*
G01X75235Y227698D02*
X85078D01*
G01Y229339D02*
X84031D01*
G01X76492Y231594D02*
X76911Y230980D01*
G01X75864Y230569D02*
X75445Y231389D01*
G01X76282Y232620D02*
X76492Y231594D01*
G01X75445Y231389D02*
X75235Y232825D01*
G01Y226468D02*
Y227698D01*
G01X77539Y230569D02*
Y229544D01*
G01X84031Y230980D02*
Y236721D01*
G01X85078D02*
Y229339D01*
G01Y227698D02*
Y226468D01*
G01X78224Y174331D02*
X78150Y174330D01*
G01X78075Y182598D02*
X78150D01*
G01X80709Y178464D02*
G03I-2559J0D01*
G01X81496D02*
G03I-3346J0D01*
G01X81654D02*
G03I-3504J0D01*
G01X78075Y182597D02*
G03X78150Y174330I74J-4133D01*
G01X78224Y174331D02*
G03X78150Y182598I-73J4133D01*
G01X72638Y190275D02*
G03I-3740J0D01*
G01X85757Y166830D02*
X85656Y166798D01*
G01X79528Y152047D02*
X82677Y153228D01*
G01X79528Y157047D02*
X82677Y158228D01*
G01X79528Y162047D02*
X82677Y163228D01*
G01X79528Y167047D02*
X82677Y168228D01*
G01X86695Y165977D02*
X86561Y165912D01*
G01X86527Y166109D02*
X86628Y166174D01*
G01X85622Y165452D02*
X85857Y165649D01*
G01X85589D02*
X85354Y165452D01*
G01X86829Y166109D02*
X86695Y165977D01*
G01X85542Y166948D02*
X85589Y166995D01*
G01X85455Y166863D02*
X85542Y166948D01*
G01X36610Y182140D02*
X31890Y177499D01*
G01Y178602D02*
X36614Y183248D01*
G01X40551Y174901D02*
X38583Y172933D01*
G01X86628Y166174D02*
X86695Y166272D01*
G01X85656Y166798D02*
X85589Y166699D01*
G01X86896Y166240D02*
X86829Y166109D01*
G01X85388Y166732D02*
X85455Y166863D01*
G01X85589Y166699D02*
X85556Y166601D01*
G01X86695Y166272D02*
X86728Y166404D01*
G01X85354Y166601D02*
X85388Y166732D01*
G01X86929Y166404D02*
X86896Y166240D01*
G01X90551Y169980D02*
Y183248D01*
G01X88110Y151948D02*
Y150374D01*
G01Y156948D02*
Y155374D01*
G01Y161948D02*
Y160374D01*
G01Y166948D02*
Y165374D01*
G01X86929Y165256D02*
Y165374D01*
G01D02*
Y165452D01*
G01Y166666D02*
Y166404D01*
G01X86728D02*
Y166666D01*
G01X86494Y166948D02*
Y167126D01*
G01Y166929D02*
Y166948D01*
G01X86226Y166601D02*
Y166404D01*
G01X86024D02*
Y166601D01*
G01X85723Y166207D02*
Y166010D01*
G01X85556Y166601D02*
Y166404D01*
G01X85354Y166437D02*
Y166601D01*
G01Y165374D02*
Y165256D01*
G01Y165452D02*
Y165374D01*
G01X83189D02*
Y166948D01*
G01Y160374D02*
Y161948D01*
G01Y155374D02*
Y156948D01*
G01Y150374D02*
Y151948D01*
G01X82795D02*
Y150374D01*
G01Y156948D02*
Y155374D01*
G01Y161948D02*
Y160374D01*
G01Y166948D02*
Y165374D01*
G01X82677Y154094D02*
Y153228D01*
G01Y159094D02*
Y158228D01*
G01Y164094D02*
Y163228D01*
G01Y169980D02*
Y168228D01*
G01Y200137D02*
Y187185D01*
G01X82008Y151948D02*
Y150374D01*
G01Y156948D02*
Y155374D01*
G01Y161948D02*
Y160374D01*
G01Y166948D02*
Y165374D01*
G01X80433Y151948D02*
Y150374D01*
G01Y156948D02*
Y155374D01*
G01Y161948D02*
Y160374D01*
G01Y166948D02*
Y165374D01*
G01X78740Y183248D02*
Y196200D01*
G01X78543Y189488D02*
Y191063D01*
G01X74803Y150374D02*
Y150275D01*
G01Y152047D02*
Y151948D01*
G01Y155374D02*
Y155275D01*
G01Y151948D02*
Y150374D01*
G01Y157047D02*
Y156948D01*
G01Y160374D02*
Y160275D01*
G01Y156948D02*
Y155374D01*
G01Y162047D02*
Y161948D01*
G01D02*
Y160374D01*
G01Y165374D02*
Y165275D01*
G01Y167047D02*
Y166948D01*
G01D02*
Y165374D01*
G01X73189Y191063D02*
Y189488D01*
G01X71850Y191063D02*
Y191259D01*
G01Y189488D02*
Y189291D01*
G01Y191063D02*
Y189488D01*
G01X71654Y191063D02*
Y189488D01*
G01X70079D02*
Y191063D01*
G01Y183248D02*
Y174901D01*
G01X67717Y189488D02*
Y191063D01*
G01X66142Y189488D02*
Y191063D01*
G01X65945Y189488D02*
Y191063D01*
G01Y189488D02*
Y189291D01*
G01Y191259D02*
Y191063D01*
G01X64606Y189488D02*
Y191063D01*
G01X59252D02*
Y189488D01*
G01X59055Y183248D02*
Y196200D01*
G01X55118Y187185D02*
Y200137D01*
G01X46553Y151948D02*
Y150374D01*
G01Y156948D02*
Y155374D01*
G01Y161948D02*
Y160374D01*
G01Y166948D02*
Y165374D01*
G01X45447Y151948D02*
Y150374D01*
G01Y156948D02*
Y155374D01*
G01Y161948D02*
Y160374D01*
G01Y166948D02*
Y165374D01*
G01X45201Y151948D02*
Y150374D01*
G01Y156948D02*
Y155374D01*
G01Y161948D02*
Y160374D01*
G01Y166948D02*
Y165374D01*
G01X41535Y152047D02*
Y150275D01*
G01Y157047D02*
Y155275D01*
G01Y162047D02*
Y160275D01*
G01Y167047D02*
Y165275D01*
G01X41026Y165374D02*
Y166948D01*
G01Y160374D02*
Y161948D01*
G01Y155374D02*
Y156948D01*
G01Y150374D02*
Y151948D01*
G01X40344D02*
Y150374D01*
G01Y156948D02*
Y155374D01*
G01Y161948D02*
Y160374D01*
G01Y166948D02*
Y165374D01*
G01X36614Y174901D02*
Y182067D01*
G01X31890Y176870D02*
Y178602D01*
G01X86896Y166830D02*
X86929Y166666D01*
G01X86058Y166240D02*
X86024Y166404D01*
G01X85388Y166272D02*
X85354Y166437D01*
G01X86728Y166666D02*
X86695Y166798D01*
G01X86192Y166732D02*
X86226Y166601D01*
G01Y166404D02*
X86259Y166272D01*
G01X86024Y166601D02*
X85991Y166699D01*
G01X85556Y166404D02*
X85589Y166306D01*
G01Y166995D02*
X85723Y167027D01*
G01X86125Y166863D02*
X86192Y166732D01*
G01X86125Y166109D02*
X86058Y166240D01*
G01X86795Y166995D02*
X86823Y166948D01*
G01D02*
X86896Y166830D01*
G01X85991Y166699D02*
X85924Y166798D01*
G01X86259Y166272D02*
X86326Y166174D01*
G01X55118Y200137D02*
X82677D01*
G01X78740Y196200D02*
X59055D01*
G01X78740Y194232D02*
X59055D01*
G01X78740Y192244D02*
X59055D01*
G01Y191259D02*
X78740D01*
G01X59252Y191063D02*
X78543D01*
G01X59252Y189488D02*
X78543D01*
G01X78740Y189291D02*
X59055D01*
G01Y188307D02*
X78740D01*
G01X27953Y187185D02*
X55118D01*
G01X94488D02*
X82677D01*
G01X78740Y185216D02*
X59055D01*
G01X36614Y183248D02*
X90551D01*
G01X36614Y182067D02*
X70079D01*
G01Y177854D02*
X59055D01*
G01X90551D02*
X70079D01*
G01X35300Y174901D02*
X38583D01*
G01X90551D02*
X40551D01*
G01X90551Y171752D02*
X70866D01*
G01Y169980D02*
X90551D01*
G01X69587D02*
X70866D01*
G01X68209D02*
X39764D01*
G01X85489Y166141D02*
X85388Y166272D01*
G01X86695Y166798D02*
X86594Y166896D01*
G01X85991Y166995D02*
X86038Y166948D01*
G01D02*
X86125Y166863D01*
G01X86259Y165977D02*
X86125Y166109D01*
G01X85589Y166306D02*
X85656Y166240D01*
G01X38583Y167047D02*
X70866D01*
G01X79528D02*
X74803D01*
G01X85723Y167027D02*
X85857D01*
G01X70866Y166948D02*
X88110D01*
G01X40344D02*
X70866D01*
G01X85824Y166830D02*
X85757D01*
G01X86427Y166109D02*
X86527D01*
G01X86561Y165912D02*
X86393D01*
G01X85857Y165649D02*
X85589D01*
G01X86929Y165452D02*
X85622D01*
G01X70866Y165374D02*
X88110D01*
G01X40344D02*
X70866D01*
G01X74803Y165275D02*
X79528D01*
G01X38583D02*
X70866D01*
G01X85354Y165256D02*
X86929D01*
G01X38583Y162047D02*
X70866D01*
G01X79528D02*
X74803D01*
G01X70866Y161948D02*
X88110D01*
G01X40344D02*
X70866D01*
G01Y160374D02*
X88110D01*
G01X40344D02*
X70866D01*
G01X74803Y160275D02*
X79528D01*
G01X38583D02*
X70866D01*
G01X38583Y157047D02*
X70866D01*
G01X79528D02*
X74803D01*
G01X70866Y156948D02*
X88110D01*
G01X40344D02*
X70866D01*
G01Y155374D02*
X88110D01*
G01X40344D02*
X70866D01*
G01X74803Y155275D02*
X79528D01*
G01X38583D02*
X70866D01*
G01X38583Y152047D02*
X70866D01*
G01X79528D02*
X74803D01*
G01X70866Y151948D02*
X88110D01*
G01X40344D02*
X70866D01*
G01Y150374D02*
X88110D01*
G01X40344D02*
X70866D01*
G01X74803Y150275D02*
X79528D01*
G01X38583D02*
X70866D01*
G01X39764Y169980D02*
X38583Y171161D01*
G01X85622Y166043D02*
X85489Y166141D01*
G01X86326Y166174D02*
X86427Y166109D01*
G01X86628Y167093D02*
X86795Y166995D01*
G01X31890Y176870D02*
X35300Y174901D01*
G01X86393Y165912D02*
X86259Y165977D01*
G01X85656Y166240D02*
X85723Y166207D01*
G01X82677Y164094D02*
X79528Y165275D01*
G01X82677Y159094D02*
X79528Y160275D01*
G01X82677Y154094D02*
X79528Y155275D01*
G01X86594Y166896D02*
X86494Y166929D01*
G01X85924Y166798D02*
X85824Y166830D01*
G01X85723Y166010D02*
X85622Y166043D01*
G01X86494Y167126D02*
X86628Y167093D01*
G01X85857Y167027D02*
X85991Y166995D01*
G01X14688Y235603D02*
X15464Y235406D01*
G01X16248D02*
X15472Y235603D01*
G01X14688Y239540D02*
X15464Y239343D01*
G01X16248D02*
X15472Y239540D01*
G01X14688Y243477D02*
X15464Y243280D01*
G01X16248D02*
X15472Y243477D01*
G01Y234264D02*
X12829D01*
G01X16248Y234461D02*
X15464D01*
G01X16248Y235406D02*
X15464D01*
G01X15472Y235603D02*
X12829D01*
G01X15472Y238201D02*
X12829D01*
G01X16248Y238398D02*
X15464D01*
G01X16248Y239343D02*
X15464D01*
G01X15472Y239540D02*
X12829D01*
G01X15472Y242138D02*
X12829D01*
G01X16248Y242335D02*
X15464D01*
G01X16248Y243280D02*
X15464D01*
G01X15472Y243477D02*
X12829D01*
G01X15472Y234264D02*
X16248Y234461D01*
G01X15464D02*
X14688Y234264D01*
G01X15472Y238201D02*
X16248Y238398D01*
G01X15464D02*
X14688Y238201D01*
G01X15472Y242138D02*
X16248Y242335D01*
G01X15464D02*
X14688Y242138D01*
G01X12829Y234264D02*
Y235603D01*
G01Y238201D02*
Y239540D01*
G01Y242138D02*
Y243477D01*
G01X13613D02*
Y242138D01*
G01Y239540D02*
Y238201D01*
G01Y235603D02*
Y234264D01*
G01X15464Y243280D02*
Y242335D01*
G01Y239343D02*
Y238398D01*
G01Y235406D02*
Y234461D01*
G01X16248D02*
Y235406D01*
G01Y238398D02*
Y239343D01*
G01Y242335D02*
Y243280D01*
G01X14688Y247414D02*
X15464Y247217D01*
G01X16248D02*
X15472Y247414D01*
G01Y246075D02*
X12829D01*
G01X16248Y246272D02*
X15464D01*
G01X16248Y247217D02*
X15464D01*
G01X15472Y247414D02*
X12829D01*
G01X15472Y246075D02*
X16248Y246272D01*
G01X15464D02*
X14688Y246075D01*
G01X12829D02*
Y247414D01*
G01X13613D02*
Y246075D01*
G01X15464Y247217D02*
Y246272D01*
G01X16248D02*
Y247217D01*
G01X22851Y277961D02*
Y252370D01*
G01X24802Y277961D02*
Y252370D01*
G01X45275Y309567D02*
G03I-15748J0D01*
G01X36515D02*
G03I-6988J0D01*
G01X125983Y263150D02*
X66495D01*
G01X77958Y236721D02*
X78795Y236516D01*
G01Y235080D02*
X77958Y235491D01*
G01X79633Y242872D02*
X80052Y242667D01*
G01X78795Y236516D02*
X79424Y236106D01*
G01X79005Y239387D02*
X78586Y239796D01*
G01X79424D02*
X79842Y239387D01*
G01X79214Y242462D02*
X78586Y243078D01*
G01X79424D02*
X79633Y242872D01*
G01X77958Y235491D02*
X77539D01*
G01Y236721D02*
X77958D01*
G01X84031D02*
X85078D01*
G01Y238361D02*
X78377D01*
G01X79842Y239387D02*
X85078D01*
G01X78377D02*
X79005D01*
G01X85078Y241642D02*
X80052D01*
G01Y242667D02*
X85078D01*
G01X79214Y243487D02*
X79424Y243078D01*
G01X76701Y236516D02*
X77539Y236721D01*
G01X78586Y239796D02*
X78377Y240412D01*
G01X79214D02*
X79424Y239796D01*
G01X78586Y243078D02*
X78377Y243693D01*
G01X75235Y232825D02*
Y233645D01*
G01X76282Y233440D02*
Y232620D01*
G01X78377Y238361D02*
Y239387D01*
G01Y243693D02*
Y244513D01*
G01Y240412D02*
Y241232D01*
G01X79214Y240822D02*
Y240412D01*
G01Y244103D02*
Y243487D01*
G01X85078Y242667D02*
Y241642D01*
G01Y239387D02*
Y238361D01*
G01X75235Y233645D02*
X75445Y234875D01*
G01X76492Y234465D02*
X76282Y233440D01*
G01X78377Y241232D02*
X78586Y241847D01*
G01X79424Y244513D02*
X79214Y244103D01*
G01X75445Y234875D02*
X75864Y235696D01*
G01X79424Y241232D02*
X79214Y240822D01*
G01X76911Y235080D02*
X76492Y234465D01*
G01X78586Y241847D02*
X79214Y242462D01*
G01X79633Y241437D02*
X79424Y241232D01*
G01X75864Y235696D02*
X76701Y236516D01*
G01X77539Y235491D02*
X76911Y235080D01*
G01X80052Y241642D02*
X79633Y241437D01*
G01Y252100D02*
X80052Y251895D01*
G01X79005Y248614D02*
X78586Y249024D01*
G01X79424D02*
X79842Y248614D01*
G01X79214Y251690D02*
X78586Y252305D01*
G01X79424D02*
X79633Y252100D01*
G01X85078Y244923D02*
X80052D01*
G01Y245948D02*
X85078D01*
G01Y247589D02*
X78377D01*
G01X79842Y248614D02*
X85078D01*
G01X78377D02*
X79005D01*
G01X85078Y250869D02*
X80052D01*
G01Y251895D02*
X85078D01*
G01Y254150D02*
X80052D01*
G01Y255176D02*
X85078D01*
G01X79214Y252715D02*
X79424Y252305D01*
G01X78586Y249024D02*
X78377Y249639D01*
G01X79214D02*
X79424Y249024D01*
G01X78586Y252305D02*
X78377Y252920D01*
G01Y247589D02*
Y248614D01*
G01Y252920D02*
Y253740D01*
G01Y249639D02*
Y250459D01*
G01X79214Y250049D02*
Y249639D01*
G01Y253330D02*
Y252715D01*
G01X85078Y255176D02*
Y254150D01*
G01Y251895D02*
Y250869D01*
G01Y245948D02*
Y244923D01*
G01Y248614D02*
Y247589D01*
G01X78377Y253740D02*
X78586Y254356D01*
G01X78377Y250459D02*
X78586Y251074D01*
G01X78377Y244513D02*
X78586Y245128D01*
G01X79424Y253740D02*
X79214Y253330D01*
G01X79424Y250459D02*
X79214Y250049D01*
G01X78586Y254356D02*
X79005Y254765D01*
G01X79633Y253945D02*
X79424Y253740D01*
G01X78586Y251074D02*
X79214Y251690D01*
G01X79633Y250665D02*
X79424Y250459D01*
G01X78586Y245128D02*
X79005Y245538D01*
G01X79633Y244718D02*
X79424Y244513D01*
G01X80052Y254150D02*
X79633Y253945D01*
G01X80052Y250869D02*
X79633Y250665D01*
G01X80052Y244923D02*
X79633Y244718D01*
G01X79005Y254765D02*
X80052Y255176D01*
G01X79005Y245538D02*
X80052Y245948D01*
G01X22834Y366530D02*
Y340939D01*
G01X24802Y366530D02*
Y340939D01*
G01X26771Y731884D02*
Y338971D01*
G01X12251Y372081D02*
X12452Y371819D01*
G01X14579Y372613D02*
X15464Y372416D01*
G01X15962D02*
X15077Y372613D01*
G01X14579Y376550D02*
X15464Y376353D01*
G01X15962D02*
X15077Y376550D01*
G01X14579Y380487D02*
X15464Y380290D01*
G01X15962D02*
X15077Y380487D01*
G01X14579Y384424D02*
X15464Y384227D01*
G01X15962D02*
X15077Y384424D01*
G01X12050Y371753D02*
X12117Y371556D01*
G01X15962Y371471D02*
X15464D01*
G01X15962Y372416D02*
X15464D01*
G01X12600Y372613D02*
X15077D01*
G01X15962Y375408D02*
X15464D01*
G01X15962Y376353D02*
X15464D01*
G01X12600Y376550D02*
X15077D01*
G01X15962Y379345D02*
X15464D01*
G01X15962Y380290D02*
X15464D01*
G01X12600Y380487D02*
X15077D01*
G01X15962Y383282D02*
X15464D01*
G01X15962Y384227D02*
X15464D01*
G01X12600Y384424D02*
X15077D01*
G01X12452Y371819D02*
X12519Y371491D01*
G01X12117Y371556D02*
Y370309D01*
G01X12519Y371491D02*
Y369916D01*
G01Y373656D02*
Y373262D01*
G01X12600Y384424D02*
Y383085D01*
G01Y376550D02*
Y375211D01*
G01Y380487D02*
Y379148D01*
G01Y372613D02*
Y371274D01*
G01X13423Y384424D02*
Y383085D01*
G01Y376550D02*
Y375211D01*
G01Y380487D02*
Y379148D01*
G01Y372613D02*
Y371274D01*
G01X15464Y384227D02*
Y383282D01*
G01Y376353D02*
Y375408D01*
G01Y380290D02*
Y379345D01*
G01Y372416D02*
Y371471D01*
G01X15962Y384227D02*
Y383282D01*
G01Y380290D02*
Y379345D01*
G01Y376353D02*
Y375408D01*
G01Y372416D02*
Y371471D01*
G01D02*
X15077Y371274D01*
G01X14579D02*
X15464Y371471D01*
G01X15962Y375408D02*
X15077Y375211D01*
G01X14579D02*
X15464Y375408D01*
G01X15962Y379345D02*
X15077Y379148D01*
G01X14579D02*
X15464Y379345D01*
G01X15962Y383282D02*
X15077Y383085D01*
G01X14579D02*
X15464Y383282D01*
G01X14579Y388361D02*
X15464Y388164D01*
G01X15962D02*
X15077Y388361D01*
G01X14579Y392298D02*
X15464Y392101D01*
G01X15962D02*
X15077Y392298D01*
G01X14579Y396235D02*
X15464Y396038D01*
G01X15962D02*
X15077Y396235D01*
G01X15962Y387219D02*
X15464D01*
G01X15962Y388164D02*
X15464D01*
G01X12600Y388361D02*
X15077D01*
G01X15962Y391156D02*
X15464D01*
G01X15962Y392101D02*
X15464D01*
G01X12600Y392298D02*
X15077D01*
G01X15962Y395093D02*
X15464D01*
G01X15962Y396038D02*
X15464D01*
G01X12600Y396235D02*
X15077D01*
G01X12600D02*
Y394896D01*
G01Y392298D02*
Y390959D01*
G01Y388361D02*
Y387022D01*
G01X13423Y396235D02*
Y394896D01*
G01Y392298D02*
Y390959D01*
G01Y388361D02*
Y387022D01*
G01X15464Y396038D02*
Y395093D01*
G01Y392101D02*
Y391156D01*
G01Y388164D02*
Y387219D01*
G01X15962Y396038D02*
Y395093D01*
G01Y392101D02*
Y391156D01*
G01Y388164D02*
Y387219D01*
G01D02*
X15077Y387022D01*
G01X14579D02*
X15464Y387219D01*
G01X15962Y391156D02*
X15077Y390959D01*
G01X14579D02*
X15464Y391156D01*
G01X15962Y395093D02*
X15077Y394896D01*
G01X14579D02*
X15464Y395093D01*
G01X14579Y400172D02*
X15464Y399975D01*
G01X15962D02*
X15077Y400172D01*
G01X14579Y404109D02*
X15464Y403912D01*
G01X15962D02*
X15077Y404109D01*
G01X15962Y399030D02*
X15464D01*
G01X15962Y399975D02*
X15464D01*
G01X12600Y400172D02*
X15077D01*
G01X15962Y402967D02*
X15464D01*
G01X15962Y403912D02*
X15464D01*
G01X12600Y404109D02*
X15077D01*
G01X12600D02*
Y402770D01*
G01Y400172D02*
Y398833D01*
G01X13423Y404109D02*
Y402770D01*
G01Y400172D02*
Y398833D01*
G01X15464Y399975D02*
Y399030D01*
G01Y403912D02*
Y402967D01*
G01X15962Y399975D02*
Y399030D01*
G01Y403912D02*
Y402967D01*
G01Y399030D02*
X15077Y398833D01*
G01X14579D02*
X15464Y399030D01*
G01X15962Y402967D02*
X15077Y402770D01*
G01X14579D02*
X15464Y402967D01*
G01X14579Y408046D02*
X15464Y407849D01*
G01X15962D02*
X15077Y408046D01*
G01X14579Y411983D02*
X15464Y411786D01*
G01X15962D02*
X15077Y411983D01*
G01X15550Y420703D02*
X18700Y419569D01*
G01X14579Y423794D02*
X15464Y423597D01*
G01X15962D02*
X15077Y423794D01*
G01X15962Y406904D02*
X15464D01*
G01X15962Y407849D02*
X15464D01*
G01X12600Y408046D02*
X15077D01*
G01X15962Y410841D02*
X15464D01*
G01X15962Y411786D02*
X15464D01*
G01X12600Y411983D02*
X15077D01*
G01X15962Y422652D02*
X15464D01*
G01X15962Y423597D02*
X15464D01*
G01X12600Y423794D02*
X15077D01*
G01X12600D02*
Y422455D01*
G01Y411983D02*
Y410644D01*
G01Y408046D02*
Y406707D01*
G01X13423Y423794D02*
Y422455D01*
G01Y411983D02*
Y410644D01*
G01Y408046D02*
Y406707D01*
G01X15464Y423597D02*
Y422652D01*
G01Y411786D02*
Y410841D01*
G01Y407849D02*
Y406904D01*
G01X15550Y420703D02*
Y413695D01*
G01X15962Y423597D02*
Y422652D01*
G01Y411786D02*
Y410841D01*
G01Y407849D02*
Y406904D01*
G01X18700Y419569D02*
Y414829D01*
G01X15962Y406904D02*
X15077Y406707D01*
G01X14579D02*
X15464Y406904D01*
G01X15962Y410841D02*
X15077Y410644D01*
G01X14579D02*
X15464Y410841D01*
G01X15962Y422652D02*
X15077Y422455D01*
G01X14579D02*
X15464Y422652D01*
G01X18700Y414829D02*
X15550Y413695D01*
G01X19881Y413583D02*
G03Y421063I0J3740D01*
G01X14579Y427731D02*
X15464Y427534D01*
G01X15962D02*
X15077Y427731D01*
G01X14579Y431668D02*
X15464Y431471D01*
G01X15962D02*
X15077Y431668D01*
G01X14579Y435605D02*
X15464Y435408D01*
G01X15962D02*
X15077Y435605D01*
G01X14579Y439542D02*
X15464Y439345D01*
G01X15962D02*
X15077Y439542D01*
G01X14579Y443479D02*
X15464Y443282D01*
G01X15962D02*
X15077Y443479D01*
G01X15962Y426589D02*
X15464D01*
G01X15962Y427534D02*
X15464D01*
G01X12600Y427731D02*
X15077D01*
G01X15962Y430526D02*
X15464D01*
G01X15962Y431471D02*
X15464D01*
G01X12600Y431668D02*
X15077D01*
G01X15962Y434463D02*
X15464D01*
G01X15962Y435408D02*
X15464D01*
G01X12600Y435605D02*
X15077D01*
G01X15962Y438400D02*
X15464D01*
G01X15962Y439345D02*
X15464D01*
G01X12600Y439542D02*
X15077D01*
G01X15962Y442337D02*
X15464D01*
G01X15962Y443282D02*
X15464D01*
G01X12600Y443479D02*
X15077D01*
G01X12600D02*
Y442140D01*
G01Y439542D02*
Y438203D01*
G01Y435605D02*
Y434266D01*
G01Y427731D02*
Y426392D01*
G01Y431668D02*
Y430329D01*
G01X13423Y443479D02*
Y442140D01*
G01Y439542D02*
Y438203D01*
G01Y435605D02*
Y434266D01*
G01Y427731D02*
Y426392D01*
G01Y431668D02*
Y430329D01*
G01X15464Y443282D02*
Y442337D01*
G01Y439345D02*
Y438400D01*
G01Y435408D02*
Y434463D01*
G01Y427534D02*
Y426589D01*
G01Y431471D02*
Y430526D01*
G01X15962Y443282D02*
Y442337D01*
G01Y439345D02*
Y438400D01*
G01Y435408D02*
Y434463D01*
G01Y431471D02*
Y430526D01*
G01Y427534D02*
Y426589D01*
G01D02*
X15077Y426392D01*
G01X14579D02*
X15464Y426589D01*
G01X15962Y430526D02*
X15077Y430329D01*
G01X14579D02*
X15464Y430526D01*
G01X15962Y434463D02*
X15077Y434266D01*
G01X14579D02*
X15464Y434463D01*
G01X15962Y438400D02*
X15077Y438203D01*
G01X14579D02*
X15464Y438400D01*
G01X15962Y442337D02*
X15077Y442140D01*
G01X14579D02*
X15464Y442337D01*
G01X14579Y447416D02*
X15464Y447219D01*
G01X15962D02*
X15077Y447416D01*
G01X14579Y451353D02*
X15464Y451156D01*
G01X15962D02*
X15077Y451353D01*
G01X14579Y455290D02*
X15464Y455093D01*
G01X15962D02*
X15077Y455290D01*
G01X14579Y459227D02*
X15464Y459030D01*
G01X15962D02*
X15077Y459227D01*
G01X14579Y463164D02*
X15464Y462967D01*
G01X15962D02*
X15077Y463164D01*
G01X15962Y446274D02*
X15464D01*
G01X15962Y447219D02*
X15464D01*
G01X12600Y447416D02*
X15077D01*
G01X15962Y450211D02*
X15464D01*
G01X15962Y451156D02*
X15464D01*
G01X12600Y451353D02*
X15077D01*
G01X15962Y454148D02*
X15464D01*
G01X15962Y455093D02*
X15464D01*
G01X12600Y455290D02*
X15077D01*
G01X15962Y458085D02*
X15464D01*
G01X15962Y459030D02*
X15464D01*
G01X12600Y459227D02*
X15077D01*
G01X15962Y462022D02*
X15464D01*
G01X15962Y462967D02*
X15464D01*
G01X12600Y463164D02*
X15077D01*
G01X12600D02*
Y461825D01*
G01Y459227D02*
Y457888D01*
G01Y451353D02*
Y450014D01*
G01Y455290D02*
Y453951D01*
G01Y447416D02*
Y446077D01*
G01X13423Y463164D02*
Y461825D01*
G01Y459227D02*
Y457888D01*
G01Y451353D02*
Y450014D01*
G01Y455290D02*
Y453951D01*
G01Y447416D02*
Y446077D01*
G01X15464Y462967D02*
Y462022D01*
G01Y459030D02*
Y458085D01*
G01Y455093D02*
Y454148D01*
G01Y451156D02*
Y450211D01*
G01Y447219D02*
Y446274D01*
G01X15962Y462967D02*
Y462022D01*
G01Y459030D02*
Y458085D01*
G01Y455093D02*
Y454148D01*
G01Y451156D02*
Y450211D01*
G01Y447219D02*
Y446274D01*
G01D02*
X15077Y446077D01*
G01X14579D02*
X15464Y446274D01*
G01X15962Y450211D02*
X15077Y450014D01*
G01X14579D02*
X15464Y450211D01*
G01X15962Y454148D02*
X15077Y453951D01*
G01X14579D02*
X15464Y454148D01*
G01X15962Y458085D02*
X15077Y457888D01*
G01X14579D02*
X15464Y458085D01*
G01X15962Y462022D02*
X15077Y461825D01*
G01X14579D02*
X15464Y462022D01*
G01X14579Y467101D02*
X15464Y466904D01*
G01X15962D02*
X15077Y467101D01*
G01X14579Y471038D02*
X15464Y470841D01*
G01X15962D02*
X15077Y471038D01*
G01X14579Y474975D02*
X15464Y474778D01*
G01X15962D02*
X15077Y474975D01*
G01X14579Y478912D02*
X15464Y478715D01*
G01X15962D02*
X15077Y478912D01*
G01X15962Y465959D02*
X15464D01*
G01X15962Y466904D02*
X15464D01*
G01X12600Y467101D02*
X15077D01*
G01X15962Y469896D02*
X15464D01*
G01X15962Y470841D02*
X15464D01*
G01X15077Y471038D02*
X12600D01*
G01Y478912D02*
Y477573D01*
G01Y474975D02*
Y473636D01*
G01Y471038D02*
Y469699D01*
G01Y467101D02*
Y465762D01*
G01X13423Y478912D02*
Y477573D01*
G01Y474975D02*
Y473636D01*
G01Y471038D02*
Y469699D01*
G01Y467101D02*
Y465762D01*
G01X15464Y478715D02*
Y477770D01*
G01Y474778D02*
Y473833D01*
G01Y470841D02*
Y469896D01*
G01Y466904D02*
Y465959D01*
G01X15962Y478715D02*
Y477770D01*
G01Y474778D02*
Y473833D01*
G01Y470841D02*
Y469896D01*
G01Y466904D02*
Y465959D01*
G01Y473833D02*
X15464D01*
G01X15962Y474778D02*
X15464D01*
G01X12600Y474975D02*
X15077D01*
G01X15962Y477770D02*
X15464D01*
G01X15962Y478715D02*
X15464D01*
G01X12600Y478912D02*
X15077D01*
G01X15962Y465959D02*
X15077Y465762D01*
G01X14579D02*
X15464Y465959D01*
G01X15962Y469896D02*
X15077Y469699D01*
G01X14579D02*
X15464Y469896D01*
G01X15962Y473833D02*
X15077Y473636D01*
G01X14579D02*
X15464Y473833D01*
G01X15962Y477770D02*
X15077Y477573D01*
G01X14579D02*
X15464Y477770D01*
G01X80167Y432795D02*
G03Y435945I-2017J1575D01*
G01X76133D02*
G03Y432795I2017J-1575D01*
G01X75780Y436732D02*
G03Y432008I2370J-2362D01*
G01X80520D02*
G03Y436732I-2370J2362D01*
G01X81654Y434370D02*
G03I-3504J0D01*
G01X72638Y422559D02*
G03I-3740J0D01*
G01X75472Y437519D02*
G03Y431220I2678J-3150D01*
G01X80827D02*
G03Y437519I-2677J3149D01*
G01X79528Y447559D02*
X82677Y448740D01*
G01X79528Y452559D02*
X82677Y453740D01*
G01X79528Y457559D02*
X82677Y458740D01*
G01X79528Y467559D02*
X82677Y468740D01*
G01X79528Y472559D02*
X82677Y473740D01*
G01X79528Y477559D02*
X82677Y478740D01*
G01X35300Y437933D02*
X31890Y435964D01*
G01X39764Y442854D02*
X38583Y441673D01*
G01X77559Y462559D02*
X82677Y463740D01*
G01X94488Y425649D02*
Y592696D01*
G01X90551Y429586D02*
Y442854D01*
G01X89567Y462460D02*
Y460885D01*
G01X88110Y447460D02*
Y445885D01*
G01Y452460D02*
Y450885D01*
G01Y457460D02*
Y455885D01*
G01Y467460D02*
Y465885D01*
G01Y472460D02*
Y470885D01*
G01Y477460D02*
Y475885D01*
G01X83189D02*
Y477460D01*
G01Y470885D02*
Y472460D01*
G01Y465885D02*
Y467460D01*
G01Y460885D02*
Y462460D01*
G01Y455885D02*
Y457460D01*
G01Y450885D02*
Y452460D01*
G01Y445885D02*
Y447460D01*
G01X82795D02*
Y445885D01*
G01Y452460D02*
Y450885D01*
G01Y457460D02*
Y455885D01*
G01Y462460D02*
Y460885D01*
G01Y467460D02*
Y465885D01*
G01Y472460D02*
Y470885D01*
G01Y477460D02*
Y475885D01*
G01X82677Y425649D02*
Y412696D01*
G01Y444606D02*
Y442854D01*
G01Y449606D02*
Y448740D01*
G01Y454606D02*
Y453740D01*
G01Y459606D02*
Y458740D01*
G01Y464606D02*
Y463740D01*
G01Y469606D02*
Y468740D01*
G01Y474606D02*
Y473740D01*
G01Y479606D02*
Y478740D01*
G01X82008Y447460D02*
Y445885D01*
G01Y452460D02*
Y450885D01*
G01Y457460D02*
Y455885D01*
G01Y462460D02*
Y460885D01*
G01Y467460D02*
Y465885D01*
G01Y472460D02*
Y470885D01*
G01Y477460D02*
Y475885D01*
G01X80433Y447460D02*
Y445885D01*
G01Y452460D02*
Y450885D01*
G01Y457460D02*
Y455885D01*
G01Y462460D02*
Y460885D01*
G01Y467460D02*
Y465885D01*
G01Y472460D02*
Y470885D01*
G01Y477460D02*
Y475885D01*
G01X78740Y416633D02*
Y429586D01*
G01X78543Y421771D02*
Y423346D01*
G01X77756Y462795D02*
Y465551D01*
G01X74803Y445885D02*
Y445787D01*
G01Y447559D02*
Y447460D01*
G01D02*
Y445885D01*
G01Y450885D02*
Y450787D01*
G01Y452559D02*
Y452460D01*
G01D02*
Y450885D01*
G01Y455885D02*
Y455787D01*
G01Y457559D02*
Y457460D01*
G01D02*
Y455885D01*
G01Y465885D02*
Y465787D01*
G01Y467559D02*
Y467460D01*
G01D02*
Y465885D01*
G01Y470885D02*
Y470787D01*
G01Y472559D02*
Y472460D01*
G01D02*
Y470885D01*
G01Y475885D02*
Y475787D01*
G01Y477559D02*
Y477460D01*
G01D02*
Y475885D01*
G01X73189Y423346D02*
Y421771D01*
G01X38583Y477559D02*
X70866D01*
G01X79528D02*
X74803D01*
G01X70866Y477460D02*
X88110D01*
G01X40344D02*
X70866D01*
G01Y475885D02*
X88110D01*
G01X40344D02*
X70866D01*
G01X74803Y475787D02*
X79528D01*
G01X38583D02*
X70866D01*
G01X72835Y460885D02*
Y460787D01*
G01Y462559D02*
Y462460D01*
G01D02*
Y460885D01*
G01X71850Y423346D02*
Y423543D01*
G01Y421771D02*
Y421574D01*
G01Y423346D02*
Y421771D01*
G01X71654Y423346D02*
Y421771D01*
G01X70866Y460885D02*
Y462460D01*
G01D02*
Y500885D01*
G01Y441082D02*
Y460885D01*
G01X70079Y429586D02*
Y437933D01*
G01Y421771D02*
Y423346D01*
G01X69685Y464035D02*
Y459311D01*
G01X69587Y442854D02*
Y575492D01*
G01X68209D02*
Y442854D01*
G01X67717Y421771D02*
Y423346D01*
G01X66929Y442854D02*
Y575492D01*
G01X66142Y421771D02*
Y423346D01*
G01X65945Y421771D02*
Y423346D01*
G01Y421771D02*
Y421574D01*
G01Y423543D02*
Y423346D01*
G01X64606Y421771D02*
Y423346D01*
G01X59252D02*
Y421771D01*
G01X59055Y429586D02*
Y588759D01*
G01Y416633D02*
Y429586D01*
G01X55118Y412696D02*
Y425649D01*
G01X46553Y447460D02*
Y445885D01*
G01Y452460D02*
Y450885D01*
G01Y457460D02*
Y455885D01*
G01Y462460D02*
Y460885D01*
G01Y467460D02*
Y465885D01*
G01Y472460D02*
Y470885D01*
G01Y477460D02*
Y475885D01*
G01X45447Y447460D02*
Y445885D01*
G01Y452460D02*
Y450885D01*
G01Y457460D02*
Y455885D01*
G01Y462460D02*
Y460885D01*
G01Y467460D02*
Y465885D01*
G01Y472460D02*
Y470885D01*
G01Y477460D02*
Y475885D01*
G01X45201Y447460D02*
Y445885D01*
G01Y452460D02*
Y450885D01*
G01Y457460D02*
Y455885D01*
G01Y462460D02*
Y460885D01*
G01Y467460D02*
Y465885D01*
G01Y472460D02*
Y470885D01*
G01Y477460D02*
Y475885D01*
G01X41535Y447559D02*
Y445787D01*
G01Y452559D02*
Y450787D01*
G01Y457559D02*
Y455787D01*
G01Y462559D02*
Y460787D01*
G01Y467559D02*
Y465787D01*
G01Y472559D02*
Y470787D01*
G01Y477559D02*
Y475787D01*
G01X41026Y475885D02*
Y477460D01*
G01Y470885D02*
Y472460D01*
G01Y465885D02*
Y467460D01*
G01Y460885D02*
Y462460D01*
G01Y455885D02*
Y457460D01*
G01Y450885D02*
Y452460D01*
G01Y445885D02*
Y447460D01*
G01X40344D02*
Y445885D01*
G01Y452460D02*
Y450885D01*
G01Y457460D02*
Y455885D01*
G01Y462460D02*
Y460885D01*
G01Y467460D02*
Y465885D01*
G01Y472460D02*
Y470885D01*
G01Y477460D02*
Y475885D01*
G01X39764Y442854D02*
Y575492D01*
G01X38583Y437933D02*
Y580413D01*
G01X36614Y430767D02*
Y437933D01*
G01X31890Y434232D02*
Y435964D01*
G01X27953Y592696D02*
Y425649D01*
G01X38583Y472559D02*
X70866D01*
G01X79528D02*
X74803D01*
G01X70866Y472460D02*
X88110D01*
G01X40344D02*
X70866D01*
G01Y470885D02*
X88110D01*
G01X40344D02*
X70866D01*
G01X74803Y470787D02*
X79528D01*
G01X38583D02*
X70866D01*
G01X38583Y467559D02*
X70866D01*
G01X79528D02*
X74803D01*
G01X70866Y467460D02*
X88110D01*
G01X40344D02*
X70866D01*
G01Y465885D02*
X88110D01*
G01X40344D02*
X70866D01*
G01X74803Y465787D02*
X79528D01*
G01X38583D02*
X70866D01*
G01Y465551D02*
X77756D01*
G01X70866Y464035D02*
X69685D01*
G01X77756Y462795D02*
X70866D01*
G01X38583Y462559D02*
X69685D01*
G01X77559D02*
X72835D01*
G01X69685Y462460D02*
X89567D01*
G01X40344D02*
X69685D01*
G01Y460885D02*
X89567D01*
G01X40344D02*
X69685D01*
G01X72835Y460787D02*
X77559D01*
G01X38583D02*
X69685D01*
G01Y459311D02*
X70866D01*
G01X38583Y457559D02*
X70866D01*
G01X79528D02*
X74803D01*
G01X70866Y457460D02*
X88110D01*
G01X40344D02*
X70866D01*
G01Y455885D02*
X88110D01*
G01X40344D02*
X70866D01*
G01X74803Y455787D02*
X79528D01*
G01X38583D02*
X70866D01*
G01X38583Y452559D02*
X70866D01*
G01X79528D02*
X74803D01*
G01X70866Y452460D02*
X88110D01*
G01X40344D02*
X70866D01*
G01Y450885D02*
X88110D01*
G01X40344D02*
X70866D01*
G01X74803Y450787D02*
X79528D01*
G01X38583D02*
X70866D01*
G01X38583Y447559D02*
X70866D01*
G01X79528D02*
X74803D01*
G01X70866Y447460D02*
X88110D01*
G01X40344D02*
X70866D01*
G01Y445885D02*
X88110D01*
G01X40344D02*
X70866D01*
G01X74803Y445787D02*
X79528D01*
G01X38583D02*
X70866D01*
G01X69587Y442854D02*
X70866D01*
G01X39764D02*
X68209D01*
G01X90551D02*
X70866D01*
G01Y441082D02*
X90551D01*
G01X40551Y437933D02*
X90551D01*
G01X35300D02*
X38583D01*
G01X75472Y437519D02*
X80827D01*
G01X80520Y436732D02*
X75780D01*
G01X80167Y435945D02*
X76133D01*
G01X70079Y434980D02*
X90551D01*
G01X59055D02*
X70079D01*
G01X80167Y432795D02*
X76133D01*
G01X75780Y432008D02*
X80520D01*
G01X80827Y431220D02*
X75472D01*
G01X70079Y430767D02*
X36614D01*
G01Y429586D02*
X90551D01*
G01X59055Y427618D02*
X78740D01*
G01X82677Y425649D02*
X94488D01*
G01X55118D02*
X27953D01*
G01X78740Y424527D02*
X59055D01*
G01Y423543D02*
X78740D01*
G01X59252Y423346D02*
X78543D01*
G01X59252Y421771D02*
X78543D01*
G01X78740Y421574D02*
X59055D01*
G01Y420590D02*
X78740D01*
G01X59055Y418602D02*
X78740D01*
G01X59055Y416633D02*
X78740D01*
G01X82677Y412696D02*
X55118D01*
G01X82677Y479606D02*
X79528Y480787D01*
G01X82677Y474606D02*
X79528Y475787D01*
G01X82677Y469606D02*
X79528Y470787D01*
G01X82677Y464606D02*
X79528Y465787D01*
G01X82677Y454606D02*
X79528Y455787D01*
G01X82677Y449606D02*
X79528Y450787D01*
G01X82677Y444606D02*
X79528Y445787D01*
G01X82677Y459606D02*
X77559Y460787D01*
G01X38583Y439901D02*
X40551Y437933D01*
G01X31890Y435335D02*
X36610Y430694D01*
G01X36614Y429586D02*
X31890Y434232D01*
G01X14579Y482849D02*
X15464Y482652D01*
G01X15962D02*
X15077Y482849D01*
G01X12600D02*
Y481510D01*
G01X13423Y482849D02*
Y481510D01*
G01X15464Y482652D02*
Y481707D01*
G01X15962Y482652D02*
Y481707D01*
G01D02*
X15464D01*
G01X15962Y482652D02*
X15464D01*
G01X12600Y482849D02*
X15077D01*
G01X15962Y481707D02*
X15077Y481510D01*
G01X14579D02*
X15464Y481707D01*
G01X14579Y486786D02*
X15464Y486589D01*
G01X15962D02*
X15077Y486786D01*
G01X14579Y490723D02*
X15464Y490526D01*
G01X15962D02*
X15077Y490723D01*
G01X14579Y494660D02*
X15464Y494463D01*
G01X15962D02*
X15077Y494660D01*
G01X14579Y498597D02*
X15464Y498400D01*
G01X15962D02*
X15077Y498597D01*
G01X14579Y502534D02*
X15464Y502337D01*
G01X15962D02*
X15077Y502534D01*
G01X12600D02*
Y501195D01*
G01Y506471D02*
Y505132D01*
G01Y498597D02*
Y497258D01*
G01Y494660D02*
Y493321D01*
G01Y490723D02*
Y489384D01*
G01Y486786D02*
Y485447D01*
G01X13423Y502534D02*
Y501195D01*
G01Y506471D02*
Y505132D01*
G01Y498597D02*
Y497258D01*
G01Y494660D02*
Y493321D01*
G01Y490723D02*
Y489384D01*
G01Y486786D02*
Y485447D01*
G01X15464Y502337D02*
Y501392D01*
G01Y506274D02*
Y505329D01*
G01Y498400D02*
Y497455D01*
G01Y494463D02*
Y493518D01*
G01Y490526D02*
Y489581D01*
G01Y486589D02*
Y485644D01*
G01X15962Y506274D02*
Y505329D01*
G01Y502337D02*
Y501392D01*
G01Y498400D02*
Y497455D01*
G01Y494463D02*
Y493518D01*
G01Y490526D02*
Y489581D01*
G01Y486589D02*
Y485644D01*
G01D02*
X15464D01*
G01X15962Y486589D02*
X15464D01*
G01X12600Y486786D02*
X15077D01*
G01X15962Y489581D02*
X15464D01*
G01X15962Y490526D02*
X15464D01*
G01X12600Y490723D02*
X15077D01*
G01X15962Y493518D02*
X15464D01*
G01X15962Y494463D02*
X15464D01*
G01X12600Y494660D02*
X15077D01*
G01X15962Y497455D02*
X15464D01*
G01X15962Y498400D02*
X15464D01*
G01X12600Y498597D02*
X15077D01*
G01X15962Y501392D02*
X15464D01*
G01X15962Y502337D02*
X15464D01*
G01X12600Y502534D02*
X15077D01*
G01X15962Y505329D02*
X15464D01*
G01X15962Y485644D02*
X15077Y485447D01*
G01X14579D02*
X15464Y485644D01*
G01X15962Y489581D02*
X15077Y489384D01*
G01X14579D02*
X15464Y489581D01*
G01X15962Y493518D02*
X15077Y493321D01*
G01X14579D02*
X15464Y493518D01*
G01X15962Y497455D02*
X15077Y497258D01*
G01X14579D02*
X15464Y497455D01*
G01X15962Y501392D02*
X15077Y501195D01*
G01X14579D02*
X15464Y501392D01*
G01X15962Y505329D02*
X15077Y505132D01*
G01X14579D02*
X15464Y505329D01*
G01X14579Y506471D02*
X15464Y506274D01*
G01X15962D02*
X15077Y506471D01*
G01X14579Y510408D02*
X15464Y510211D01*
G01X15962D02*
X15077Y510408D01*
G01X14579Y514345D02*
X15464Y514148D01*
G01X15962D02*
X15077Y514345D01*
G01X14579Y518282D02*
X15464Y518085D01*
G01X15962D02*
X15077Y518282D01*
G01X14579Y522219D02*
X15464Y522022D01*
G01X15962D02*
X15077Y522219D01*
G01X12600Y526156D02*
Y524817D01*
G01Y522219D02*
Y520880D01*
G01Y518282D02*
Y516943D01*
G01Y514345D02*
Y513006D01*
G01Y510408D02*
Y509069D01*
G01X13423Y526156D02*
Y524817D01*
G01Y522219D02*
Y520880D01*
G01Y518282D02*
Y516943D01*
G01Y514345D02*
Y513006D01*
G01Y510408D02*
Y509069D01*
G01X15464Y525959D02*
Y525014D01*
G01Y522022D02*
Y521077D01*
G01Y518085D02*
Y517140D01*
G01Y514148D02*
Y513203D01*
G01Y510211D02*
Y509266D01*
G01X15962Y525959D02*
Y525014D01*
G01Y522022D02*
Y521077D01*
G01Y518085D02*
Y517140D01*
G01Y514148D02*
Y513203D01*
G01Y510211D02*
Y509266D01*
G01Y506274D02*
X15464D01*
G01X12600Y506471D02*
X15077D01*
G01X15962Y509266D02*
X15464D01*
G01X15962Y510211D02*
X15464D01*
G01X12600Y510408D02*
X15077D01*
G01X15962Y513203D02*
X15464D01*
G01X15962Y514148D02*
X15464D01*
G01X12600Y514345D02*
X15077D01*
G01X15962Y517140D02*
X15464D01*
G01X15962Y518085D02*
X15464D01*
G01X12600Y518282D02*
X15077D01*
G01X15962Y521077D02*
X15464D01*
G01X15962Y522022D02*
X15464D01*
G01X12600Y522219D02*
X15077D01*
G01X15962Y525014D02*
X15464D01*
G01X15962Y509266D02*
X15077Y509069D01*
G01X14579D02*
X15464Y509266D01*
G01X15962Y513203D02*
X15077Y513006D01*
G01X14579D02*
X15464Y513203D01*
G01X15962Y517140D02*
X15077Y516943D01*
G01X14579D02*
X15464Y517140D01*
G01X15962Y521077D02*
X15077Y520880D01*
G01X14579D02*
X15464Y521077D01*
G01X15962Y525014D02*
X15077Y524817D01*
G01X14579D02*
X15464Y525014D01*
G01X14579Y526156D02*
X15464Y525959D01*
G01X15962D02*
X15077Y526156D01*
G01X14579Y530093D02*
X15464Y529896D01*
G01X15962D02*
X15077Y530093D01*
G01X14579Y534030D02*
X15464Y533833D01*
G01X15962D02*
X15077Y534030D01*
G01X14579Y537967D02*
X15464Y537770D01*
G01X15962D02*
X15077Y537967D01*
G01X14579Y541904D02*
X15464Y541707D01*
G01X15962D02*
X15077Y541904D01*
G01X14579Y545841D02*
X15464Y545644D01*
G01X15962D02*
X15077Y545841D01*
G01X12600D02*
Y544502D01*
G01Y541904D02*
Y540565D01*
G01Y537967D02*
Y536628D01*
G01Y534030D02*
Y532691D01*
G01Y530093D02*
Y528754D01*
G01X13423Y545841D02*
Y544502D01*
G01Y541904D02*
Y540565D01*
G01Y537967D02*
Y536628D01*
G01Y534030D02*
Y532691D01*
G01Y530093D02*
Y528754D01*
G01X15464Y545644D02*
Y544699D01*
G01Y541707D02*
Y540762D01*
G01Y537770D02*
Y536825D01*
G01Y533833D02*
Y532888D01*
G01Y529896D02*
Y528951D01*
G01X15962Y545644D02*
Y544699D01*
G01Y541707D02*
Y540762D01*
G01Y537770D02*
Y536825D01*
G01Y533833D02*
Y532888D01*
G01Y529896D02*
Y528951D01*
G01Y525959D02*
X15464D01*
G01X12600Y526156D02*
X15077D01*
G01X15962Y528951D02*
X15464D01*
G01X15962Y529896D02*
X15464D01*
G01X12600Y530093D02*
X15077D01*
G01X15962Y532888D02*
X15464D01*
G01X15962Y533833D02*
X15464D01*
G01X12600Y534030D02*
X15077D01*
G01X15962Y536825D02*
X15464D01*
G01X15962Y537770D02*
X15464D01*
G01X12600Y537967D02*
X15077D01*
G01X15962Y540762D02*
X15464D01*
G01X15962Y541707D02*
X15464D01*
G01X12600Y541904D02*
X15077D01*
G01X15962Y544699D02*
X15464D01*
G01X15962Y545644D02*
X15464D01*
G01X15962Y528951D02*
X15077Y528754D01*
G01X14579D02*
X15464Y528951D01*
G01X15962Y532888D02*
X15077Y532691D01*
G01X14579D02*
X15464Y532888D01*
G01X15962Y536825D02*
X15077Y536628D01*
G01X14579D02*
X15464Y536825D01*
G01X15962Y540762D02*
X15077Y540565D01*
G01X14579D02*
X15464Y540762D01*
G01X15962Y544699D02*
X15077Y544502D01*
G01X14579D02*
X15464Y544699D01*
G01X14579Y549778D02*
X15464Y549581D01*
G01X15962D02*
X15077Y549778D01*
G01X14579Y553715D02*
X15464Y553518D01*
G01X15962D02*
X15077Y553715D01*
G01X14579Y557652D02*
X15464Y557455D01*
G01X15962D02*
X15077Y557652D01*
G01X14579Y561589D02*
X15464Y561392D01*
G01X15962D02*
X15077Y561589D01*
G01X12600D02*
Y560250D01*
G01Y557652D02*
Y556313D01*
G01Y549778D02*
Y548439D01*
G01Y553715D02*
Y552376D01*
G01X13423Y561589D02*
Y560250D01*
G01Y557652D02*
Y556313D01*
G01Y549778D02*
Y548439D01*
G01Y553715D02*
Y552376D01*
G01X15464Y561392D02*
Y560447D01*
G01Y557455D02*
Y556510D01*
G01Y553518D02*
Y552573D01*
G01Y549581D02*
Y548636D01*
G01X15962Y561392D02*
Y560447D01*
G01Y557455D02*
Y556510D01*
G01Y553518D02*
Y552573D01*
G01Y549581D02*
Y548636D01*
G01X12600Y545841D02*
X15077D01*
G01X15962Y548636D02*
X15464D01*
G01X15962Y549581D02*
X15464D01*
G01X12600Y549778D02*
X15077D01*
G01X15962Y552573D02*
X15464D01*
G01X15962Y553518D02*
X15464D01*
G01X12600Y553715D02*
X15077D01*
G01X15962Y556510D02*
X15464D01*
G01X15962Y557455D02*
X15464D01*
G01X12600Y557652D02*
X15077D01*
G01X15962Y560447D02*
X15464D01*
G01X15962Y561392D02*
X15464D01*
G01X12600Y561589D02*
X15077D01*
G01X15962Y548636D02*
X15077Y548439D01*
G01X14579D02*
X15464Y548636D01*
G01X15962Y552573D02*
X15077Y552376D01*
G01X14579D02*
X15464Y552573D01*
G01X15962Y556510D02*
X15077Y556313D01*
G01X14579D02*
X15464Y556510D01*
G01X15962Y560447D02*
X15077Y560250D01*
G01X14579D02*
X15464Y560447D01*
G01X73228Y520413D02*
X75591Y521102D01*
G01X73228Y523563D02*
X75591Y524252D01*
G01X73228Y526712D02*
X75591Y527401D01*
G01X73228Y529862D02*
X75591Y530551D01*
G01X73228Y533011D02*
X75591Y533700D01*
G01X73228Y536161D02*
X75591Y536850D01*
G01X85818Y516384D02*
X85918Y516417D01*
G01X85885Y516614D02*
X85784Y516581D01*
G01X79528Y482559D02*
X82677Y483740D01*
G01X79528Y487559D02*
X82677Y488740D01*
G01X79528Y492559D02*
X82677Y493740D01*
G01X73228Y539311D02*
X75591Y540000D01*
G01X78473Y539626D02*
X78372Y539593D01*
G01X79528Y497559D02*
X82677Y498740D01*
G01X79528Y507559D02*
X82677Y508740D01*
G01X79528Y512559D02*
X82677Y513740D01*
G01X79528Y542559D02*
X82677Y543740D01*
G01X79528Y547559D02*
X82677Y548740D01*
G01X79528Y552559D02*
X82677Y553740D01*
G01X79528Y557559D02*
X82677Y558740D01*
G01X79528Y562559D02*
X82677Y563740D01*
G01X79411Y537329D02*
X79244Y537263D01*
G01X78976Y538379D02*
X79143Y538445D01*
G01X78306Y538346D02*
X78473Y538412D01*
G01X78708Y537362D02*
X78574Y537296D01*
G01X79411Y538772D02*
X79277Y538707D01*
G01X78641Y537526D02*
X78540Y537460D01*
G01X78372Y538182D02*
X78473Y538248D01*
G01X79244Y538904D02*
X79344Y538969D01*
G01X85918Y516417D02*
X86052Y516515D01*
G01X79378Y537526D02*
X79244Y537428D01*
G01X79009Y538182D02*
X79143Y538280D01*
G01X85583Y515925D02*
X85818Y516122D01*
G01X85550D02*
X85315Y515925D01*
G01X85952Y516680D02*
X85885Y516614D01*
G01X79512Y537428D02*
X79411Y537329D01*
G01X78808Y537460D02*
X78708Y537362D01*
G01X79545Y538904D02*
X79411Y538772D01*
G01X78205Y538248D02*
X78306Y538346D01*
G01X78172Y539658D02*
X78306Y539790D01*
G01X40551Y519409D02*
X38583Y517441D01*
G01X86052Y516515D02*
X86153Y516646D01*
G01X78741Y537657D02*
X78641Y537526D01*
G01X78875Y538248D02*
X78976Y538379D01*
G01X78272Y538051D02*
X78372Y538182D01*
G01X79344Y538969D02*
X79411Y539068D01*
G01X78372Y539593D02*
X78306Y539495D01*
G01X79612Y537591D02*
X79512Y537428D01*
G01X78104Y538083D02*
X78205Y538248D01*
G01X79445Y537657D02*
X79378Y537526D01*
G01X78842D02*
X78808Y537460D01*
G01X79612Y539035D02*
X79545Y538904D01*
G01X78942Y538051D02*
X79009Y538182D01*
G01X78842D02*
X78875Y538248D01*
G01X78104Y539527D02*
X78172Y539658D01*
G01X85985Y516778D02*
X85952Y516680D01*
G01X78306Y539495D02*
X78272Y539396D01*
G01X78306Y539790D02*
X78440Y539822D01*
G01X79478Y537788D02*
X79445Y537657D01*
G01X79411Y539068D02*
X79445Y539199D01*
G01X78909Y537920D02*
X78937Y538031D01*
G01D02*
X78942Y538051D01*
G01X78775Y537788D02*
X78741Y537657D01*
G01X78267Y538031D02*
X78272Y538051D01*
G01X78239Y537920D02*
X78267Y538031D01*
G01X78071Y539396D02*
X78104Y539527D01*
G01X86153Y516646D02*
X86186Y516811D01*
G01X79646Y537756D02*
X79612Y537591D01*
G01X79646Y539199D02*
X79612Y539035D01*
G01X78071Y537920D02*
X78094Y538031D01*
G01D02*
X78104Y538083D01*
G01X38583Y562559D02*
X70866D01*
G01X79528D02*
X74803D01*
G01X70866Y562460D02*
X88110D01*
G01X40344D02*
X70866D01*
G01Y560885D02*
X88110D01*
G01X40344D02*
X70866D01*
G01X74803Y560787D02*
X79528D01*
G01X38583D02*
X70866D01*
G01X38583Y557559D02*
X70866D01*
G01X79528D02*
X74803D01*
G01X70866Y557460D02*
X88110D01*
G01X40344D02*
X70866D01*
G01Y555885D02*
X88110D01*
G01X40344D02*
X70866D01*
G01X74803Y555787D02*
X79528D01*
G01X38583D02*
X70866D01*
G01X38583Y552559D02*
X70866D01*
G01X79528D02*
X74803D01*
G01X70866Y552460D02*
X88110D01*
G01X40344D02*
X70866D01*
G01Y550885D02*
X88110D01*
G01X40344D02*
X70866D01*
G01X74803Y550787D02*
X79528D01*
G01X38583D02*
X70866D01*
G01Y550551D02*
X77756D01*
G01X77559Y502559D02*
X82677Y503740D01*
G01X89567Y502460D02*
Y500885D01*
G01Y517460D02*
Y515885D01*
G01X88110Y482460D02*
Y480885D01*
G01Y487460D02*
Y485885D01*
G01Y492460D02*
Y490885D01*
G01Y497460D02*
Y495885D01*
G01Y507460D02*
Y505885D01*
G01Y512460D02*
Y510885D01*
G01Y542460D02*
Y540885D01*
G01Y547460D02*
Y545885D01*
G01Y552460D02*
Y550885D01*
G01Y557460D02*
Y555885D01*
G01Y562460D02*
Y560885D01*
G01X86890Y517460D02*
Y517598D01*
G01Y517401D02*
Y517460D01*
G01Y515728D02*
Y515885D01*
G01D02*
Y515925D01*
G01X86186Y516811D02*
Y517401D01*
G01X85985D02*
Y516778D01*
G01X85483D02*
Y517401D01*
G01X85315Y515885D02*
Y515728D01*
G01Y515925D02*
Y515885D01*
G01Y517598D02*
Y517460D01*
G01D02*
Y516811D01*
G01X83189Y560885D02*
Y562460D01*
G01Y555885D02*
Y557460D01*
G01Y550885D02*
Y552460D01*
G01Y545885D02*
Y547460D01*
G01Y540885D02*
Y542460D01*
G01Y515885D02*
Y517460D01*
G01Y510885D02*
Y512460D01*
G01Y505885D02*
Y507460D01*
G01Y500885D02*
Y502460D01*
G01Y495885D02*
Y497460D01*
G01Y490885D02*
Y492460D01*
G01Y485885D02*
Y487460D01*
G01Y480885D02*
Y482460D01*
G01X82795D02*
Y480885D01*
G01Y487460D02*
Y485885D01*
G01Y492460D02*
Y490885D01*
G01Y497460D02*
Y495885D01*
G01Y502460D02*
Y500885D01*
G01Y507460D02*
Y505885D01*
G01Y512460D02*
Y510885D01*
G01Y517460D02*
Y515885D01*
G01Y542460D02*
Y540885D01*
G01Y547460D02*
Y545885D01*
G01Y552460D02*
Y550885D01*
G01Y557460D02*
Y555885D01*
G01Y562460D02*
Y560885D01*
G01X82677Y484606D02*
Y483740D01*
G01Y489606D02*
Y488740D01*
G01Y494606D02*
Y493740D01*
G01Y499606D02*
Y498740D01*
G01Y504606D02*
Y503740D01*
G01Y509606D02*
Y508740D01*
G01Y514606D02*
Y513740D01*
G01Y544606D02*
Y543740D01*
G01Y549606D02*
Y548740D01*
G01Y554606D02*
Y553740D01*
G01Y559606D02*
Y558740D01*
G01X82008Y482460D02*
Y480885D01*
G01Y487460D02*
Y485885D01*
G01Y492460D02*
Y490885D01*
G01Y497460D02*
Y495885D01*
G01Y502460D02*
Y500885D01*
G01Y507460D02*
Y505885D01*
G01Y512460D02*
Y510885D01*
G01Y517460D02*
Y515885D01*
G01Y542460D02*
Y540885D01*
G01Y547460D02*
Y545885D01*
G01Y552460D02*
Y550885D01*
G01Y557460D02*
Y555885D01*
G01Y562460D02*
Y560885D01*
G01X80433Y482460D02*
Y480885D01*
G01Y487460D02*
Y485885D01*
G01Y492460D02*
Y490885D01*
G01Y497460D02*
Y495885D01*
G01Y502460D02*
Y500885D01*
G01Y507460D02*
Y505885D01*
G01Y512460D02*
Y510885D01*
G01Y517460D02*
Y515885D01*
G01Y542460D02*
Y540885D01*
G01Y547460D02*
Y545885D01*
G01Y552460D02*
Y550885D01*
G01Y557460D02*
Y555885D01*
G01Y562460D02*
Y560885D01*
G01X80118Y520315D02*
Y519133D01*
G01Y523464D02*
Y522283D01*
G01Y529763D02*
Y528582D01*
G01Y526614D02*
Y525433D01*
G01Y532913D02*
Y531732D01*
G01Y536063D02*
Y534882D01*
G01Y539212D02*
Y538031D01*
G01X79646Y539461D02*
Y539212D01*
G01Y537952D02*
Y537756D01*
G01Y539212D02*
Y539199D01*
G01X79478Y537920D02*
Y537788D01*
G01X79445Y539212D02*
Y539461D01*
G01Y539199D02*
Y539212D01*
G01X79210Y539724D02*
Y539921D01*
G01X78942Y539396D02*
Y539212D01*
G01D02*
Y539199D01*
G01X78937Y518149D02*
Y517559D01*
G01Y540787D02*
Y540196D01*
G01X78909Y537788D02*
Y537920D01*
G01X78775D02*
Y537788D01*
G01X78741Y539212D02*
Y539396D01*
G01Y539199D02*
Y539212D01*
G01X78440Y539002D02*
Y538806D01*
G01X78272Y539396D02*
Y539212D01*
G01D02*
Y539199D01*
G01X78239Y537788D02*
Y537920D01*
G01X78071Y539232D02*
Y539396D01*
G01Y537788D02*
Y537920D01*
G01X77756Y547795D02*
Y550551D01*
G01Y512795D02*
Y515551D01*
G01Y487795D02*
Y490551D01*
G01X75591Y518346D02*
Y518149D01*
G01Y524645D02*
Y524252D01*
G01Y521496D02*
Y521102D01*
G01Y527795D02*
Y527401D01*
G01Y534094D02*
Y533700D01*
G01Y530945D02*
Y530551D01*
G01Y537244D02*
Y536850D01*
G01Y540196D02*
Y540000D01*
G01X75512Y538031D02*
Y539212D01*
G01Y534882D02*
Y536063D01*
G01Y531732D02*
Y532913D01*
G01Y528582D02*
Y529763D01*
G01Y525433D02*
Y526614D01*
G01Y522283D02*
Y523464D01*
G01Y519133D02*
Y520315D01*
G01X75118D02*
Y519133D01*
G01Y523464D02*
Y522283D01*
G01Y529763D02*
Y528582D01*
G01Y526614D02*
Y525433D01*
G01Y532913D02*
Y531732D01*
G01Y536063D02*
Y534882D01*
G01Y539212D02*
Y538031D01*
G01X74803Y480885D02*
Y480787D01*
G01Y482559D02*
Y482460D01*
G01D02*
Y480885D01*
G01Y485885D02*
Y485787D01*
G01Y487559D02*
Y487460D01*
G01D02*
Y485885D01*
G01Y490885D02*
Y490787D01*
G01Y492559D02*
Y492460D01*
G01D02*
Y490885D01*
G01Y495885D02*
Y495787D01*
G01Y497559D02*
Y497460D01*
G01D02*
Y495885D01*
G01Y505885D02*
Y505787D01*
G01Y507559D02*
Y507460D01*
G01Y510885D02*
Y510787D01*
G01Y507460D02*
Y505885D01*
G01Y512559D02*
Y512460D01*
G01Y515885D02*
Y515787D01*
G01Y512460D02*
Y510885D01*
G01Y517559D02*
Y517460D01*
G01D02*
Y515885D01*
G01Y540885D02*
Y540787D01*
G01Y542559D02*
Y542460D01*
G01D02*
Y540885D01*
G01Y545885D02*
Y545787D01*
G01Y547559D02*
Y547460D01*
G01D02*
Y545885D01*
G01Y550885D02*
Y550787D01*
G01Y552559D02*
Y552460D01*
G01D02*
Y550885D01*
G01Y555885D02*
Y555787D01*
G01Y557559D02*
Y557460D01*
G01D02*
Y555885D01*
G01Y560885D02*
Y560787D01*
G01Y562559D02*
Y562460D01*
G01D02*
Y560885D01*
G01X74331Y520315D02*
Y519133D01*
G01Y523464D02*
Y522283D01*
G01Y526614D02*
Y525433D01*
G01Y529763D02*
Y528582D01*
G01Y532913D02*
Y531732D01*
G01Y539212D02*
Y538031D01*
G01Y536063D02*
Y534882D01*
G01X85315Y516811D02*
X85348Y516646D01*
G01X79612Y539626D02*
X79646Y539461D01*
G01X77756Y547795D02*
X70866D01*
G01X38583Y547559D02*
X70866D01*
G01X79528D02*
X74803D01*
G01X70866Y547460D02*
X88110D01*
G01X40344D02*
X70866D01*
G01Y545885D02*
X88110D01*
G01X40344D02*
X70866D01*
G01X74803Y545787D02*
X79528D01*
G01X38583D02*
X70866D01*
G01X41535Y542559D02*
X70866D01*
G01X79528D02*
X74803D01*
G01X70866Y542460D02*
X88110D01*
G01X40465D02*
X70866D01*
G01X38583Y541378D02*
X70866D01*
G01Y540885D02*
X88110D01*
G01X40465D02*
X70866D01*
G01X74803Y540787D02*
X78937D01*
G01X41535D02*
X70866D01*
G01X78937Y540196D02*
X75591D01*
G01X78440Y539822D02*
X78574D01*
G01X78540Y539626D02*
X78473D01*
G01X38780Y539311D02*
X68110D01*
G01X38780D02*
X38583D01*
G01X73228D02*
X70866D01*
G01X68110Y539212D02*
X80118D01*
G01X42006D02*
X68110D01*
G01X40551Y538937D02*
X59055D01*
G01X79143Y538904D02*
X79244D01*
G01X79277Y538707D02*
X79110D01*
G01X79143Y538445D02*
X79244D01*
G01X78473Y538412D02*
X78574D01*
G01X79143Y538280D02*
X79244D01*
G01X78473Y538248D02*
X78540D01*
G01X68110Y538031D02*
X80118D01*
G01X68110D02*
X42006D01*
G01X38780Y537933D02*
X68110D01*
G01X38583D02*
X38780D01*
G01X73228D02*
X70866D01*
G01X78540Y537460D02*
X78473D01*
G01X79244Y537428D02*
X79143D01*
G01X78574Y537296D02*
X78473D01*
G01X79244Y537263D02*
X79143D01*
G01X38780Y536161D02*
X68110D01*
G01X38780D02*
X38583D01*
G01X73228D02*
X70866D01*
G01X68110Y536063D02*
X80118D01*
G01X42006D02*
X68110D01*
G01Y534882D02*
X80118D01*
G01X68110D02*
X42006D01*
G01X38780Y534783D02*
X68110D01*
G01X38583D02*
X38780D01*
G01X73228D02*
X70866D01*
G01X38780Y533011D02*
X68110D01*
G01X38780D02*
X38583D01*
G01X73228D02*
X70866D01*
G01X68110Y532913D02*
X80118D01*
G01X42006D02*
X68110D01*
G01Y531732D02*
X80118D01*
G01X68110D02*
X42006D01*
G01X38780Y531633D02*
X68110D01*
G01X38583D02*
X38780D01*
G01X73228D02*
X70866D01*
G01X38780Y529862D02*
X68110D01*
G01X38780D02*
X38583D01*
G01X73228D02*
X70866D01*
G01X68110Y529763D02*
X80118D01*
G01X42006D02*
X68110D01*
G01Y528582D02*
X80118D01*
G01X68110D02*
X42006D01*
G01X38780Y528484D02*
X68110D01*
G01X38583D02*
X38780D01*
G01X73228D02*
X70866D01*
G01X38780Y526712D02*
X68110D01*
G01X38780D02*
X38583D01*
G01X73228D02*
X70866D01*
G01X68110Y526614D02*
X80118D01*
G01X42006D02*
X68110D01*
G01Y525433D02*
X80118D01*
G01X68110D02*
X42006D01*
G01X38780Y525334D02*
X68110D01*
G01X38583D02*
X38780D01*
G01X73228D02*
X70866D01*
G01X38780Y523563D02*
X68110D01*
G01X38780D02*
X38583D01*
G01X73228D02*
X70866D01*
G01X68110Y523464D02*
X80118D01*
G01X42006D02*
X68110D01*
G01Y522283D02*
X80118D01*
G01X68110D02*
X42006D01*
G01X38780Y522185D02*
X68110D01*
G01X38583D02*
X38780D01*
G01X73228D02*
X70866D01*
G01X38780Y520413D02*
X38583D01*
G01X68110D02*
X38780D01*
G01X73228D02*
X70866D01*
G01X68110Y520315D02*
X80118D01*
G01X42006D02*
X68110D01*
G01X59055Y519409D02*
X40551D01*
G01X68110Y519133D02*
X80118D01*
G01X68110D02*
X42006D01*
G01X38583Y519035D02*
X38780D01*
G01X68110D02*
X38780D01*
G01X73228D02*
X70866D01*
G01X75591Y518149D02*
X78937D01*
G01X86890Y517598D02*
X85315D01*
G01X70866Y517559D02*
X41535D01*
G01X78937D02*
X74803D01*
G01X70866Y517460D02*
X89567D01*
G01X40465D02*
X70866D01*
G01X85483Y517401D02*
X85985D01*
G01X86186D02*
X86890D01*
G01X38583Y516968D02*
X70866D01*
G01X85784Y516581D02*
X85684D01*
G01Y516384D02*
X85818D01*
G01Y516122D02*
X85550D01*
G01X86890Y515925D02*
X85583D01*
G01X70866Y515885D02*
X89567D01*
G01X40465D02*
X70866D01*
G01X74803Y515787D02*
X79528D01*
G01X41535D02*
X70866D01*
G01X85315Y515728D02*
X86890D01*
G01X70866Y515551D02*
X77756D01*
G01Y512795D02*
X70866D01*
G01X38583Y512559D02*
X70866D01*
G01X79528D02*
X74803D01*
G01X70866Y512460D02*
X88110D01*
G01X40344D02*
X70866D01*
G01Y510885D02*
X88110D01*
G01X40344D02*
X70866D01*
G01X74803Y510787D02*
X79528D01*
G01X38583D02*
X70866D01*
G01X38583Y507559D02*
X70866D01*
G01X79528D02*
X74803D01*
G01X70866Y507460D02*
X88110D01*
G01X40344D02*
X70866D01*
G01Y505885D02*
X88110D01*
G01X40344D02*
X70866D01*
G01X74803Y505787D02*
X79528D01*
G01X38583D02*
X70866D01*
G01Y504035D02*
X69685D01*
G01X38583Y502559D02*
X69685D01*
G01X77559D02*
X72835D01*
G01X69685Y502460D02*
X89567D01*
G01X40344D02*
X69685D01*
G01Y500885D02*
X89567D01*
G01X40344D02*
X69685D01*
G01X72835Y500787D02*
X77559D01*
G01X38583D02*
X69685D01*
G01Y499311D02*
X70866D01*
G01X38583Y497559D02*
X70866D01*
G01X79528D02*
X74803D01*
G01X70866Y497460D02*
X88110D01*
G01X40344D02*
X70866D01*
G01Y495885D02*
X88110D01*
G01X40344D02*
X70866D01*
G01X74803Y495787D02*
X79528D01*
G01X38583D02*
X70866D01*
G01X38583Y492559D02*
X70866D01*
G01X79528D02*
X74803D01*
G01X70866Y492460D02*
X88110D01*
G01X40344D02*
X70866D01*
G01Y490885D02*
X88110D01*
G01X40344D02*
X70866D01*
G01X74803Y490787D02*
X79528D01*
G01X38583D02*
X70866D01*
G01Y490551D02*
X77756D01*
G01Y487795D02*
X70866D01*
G01X38583Y487559D02*
X70866D01*
G01X79528D02*
X74803D01*
G01X70866Y487460D02*
X88110D01*
G01X40344D02*
X70866D01*
G01Y485885D02*
X88110D01*
G01X40344D02*
X70866D01*
G01X74803Y485787D02*
X79528D01*
G01X38583D02*
X70866D01*
G01X38583Y482559D02*
X70866D01*
G01X79528D02*
X74803D01*
G01X70866Y482460D02*
X88110D01*
G01X40344D02*
X70866D01*
G01Y480885D02*
X88110D01*
G01X40344D02*
X70866D01*
G01X74803Y480787D02*
X79528D01*
G01X38583D02*
X70866D01*
G01X72835Y500885D02*
Y500787D01*
G01Y502559D02*
Y502460D01*
G01D02*
Y500885D01*
G01X72756Y520315D02*
Y519133D01*
G01Y523464D02*
Y522283D01*
G01Y529763D02*
Y528582D01*
G01Y526614D02*
Y525433D01*
G01Y532913D02*
Y531732D01*
G01Y539212D02*
Y538031D01*
G01Y536063D02*
Y534882D01*
G01X70866Y539212D02*
Y577263D01*
G01Y536063D02*
Y538031D01*
G01D02*
Y539212D01*
G01Y534882D02*
Y536063D01*
G01Y532913D02*
Y534882D01*
G01Y529763D02*
Y531732D01*
G01D02*
Y532913D01*
G01Y526614D02*
Y528582D01*
G01D02*
Y529763D01*
G01Y525433D02*
Y526614D01*
G01Y523464D02*
Y525433D01*
G01Y520315D02*
Y522283D01*
G01D02*
Y523464D01*
G01Y500885D02*
Y502460D01*
G01D02*
Y519133D01*
G01D02*
Y520315D01*
G01X69685Y504035D02*
Y499311D01*
G01X68110Y541378D02*
Y516968D01*
G01X51039Y520315D02*
Y519133D01*
G01Y523464D02*
Y522283D01*
G01Y526614D02*
Y525433D01*
G01Y529763D02*
Y528582D01*
G01Y532913D02*
Y531732D01*
G01Y539212D02*
Y538031D01*
G01Y536063D02*
Y534882D01*
G01X48800Y520315D02*
Y519133D01*
G01Y523464D02*
Y522283D01*
G01Y526614D02*
Y525433D01*
G01Y529763D02*
Y528582D01*
G01Y532913D02*
Y531732D01*
G01Y539212D02*
Y538031D01*
G01Y536063D02*
Y534882D01*
G01X48302Y538031D02*
Y539212D01*
G01Y534882D02*
Y536063D01*
G01Y531732D02*
Y532913D01*
G01Y525433D02*
Y526614D01*
G01Y528582D02*
Y529763D01*
G01Y522283D02*
Y523464D01*
G01Y519133D02*
Y520315D01*
G01X47559Y537933D02*
Y539311D01*
G01Y519035D02*
Y520413D01*
G01Y523563D02*
Y522185D01*
G01Y529862D02*
Y528484D01*
G01Y526712D02*
Y525334D01*
G01Y533011D02*
Y531633D01*
G01Y536161D02*
Y534783D01*
G01X46553Y482460D02*
Y480885D01*
G01Y487460D02*
Y485885D01*
G01Y492460D02*
Y490885D01*
G01Y497460D02*
Y495885D01*
G01Y502460D02*
Y500885D01*
G01Y507460D02*
Y505885D01*
G01Y512460D02*
Y510885D01*
G01Y517460D02*
Y515885D01*
G01Y542460D02*
Y540885D01*
G01Y547460D02*
Y545885D01*
G01Y552460D02*
Y550885D01*
G01Y557460D02*
Y555885D01*
G01Y562460D02*
Y560885D01*
G01X45447Y482460D02*
Y480885D01*
G01Y487460D02*
Y485885D01*
G01Y492460D02*
Y490885D01*
G01Y497460D02*
Y495885D01*
G01Y502460D02*
Y500885D01*
G01Y507460D02*
Y505885D01*
G01Y512460D02*
Y510885D01*
G01Y517460D02*
Y515885D01*
G01Y542460D02*
Y540885D01*
G01Y547460D02*
Y545885D01*
G01Y552460D02*
Y550885D01*
G01Y557460D02*
Y555885D01*
G01Y562460D02*
Y560885D01*
G01X45201Y540885D02*
Y542460D01*
G01Y515885D02*
Y517460D01*
G01Y482460D02*
Y480885D01*
G01Y487460D02*
Y485885D01*
G01Y492460D02*
Y490885D01*
G01Y497460D02*
Y495885D01*
G01Y502460D02*
Y500885D01*
G01Y507460D02*
Y505885D01*
G01Y512460D02*
Y510885D01*
G01Y547460D02*
Y545885D01*
G01Y552460D02*
Y550885D01*
G01Y557460D02*
Y555885D01*
G01Y562460D02*
Y560885D01*
G01X42744Y520315D02*
Y519133D01*
G01Y523464D02*
Y522283D01*
G01Y526614D02*
Y525433D01*
G01Y529763D02*
Y528582D01*
G01Y532913D02*
Y531732D01*
G01Y539212D02*
Y538031D01*
G01Y536063D02*
Y534882D01*
G01X42006D02*
Y536063D01*
G01Y538031D02*
Y539212D01*
G01Y531732D02*
Y532913D01*
G01Y528582D02*
Y529763D01*
G01Y525433D02*
Y526614D01*
G01Y522283D02*
Y523464D01*
G01Y519133D02*
Y520315D01*
G01X41535Y482559D02*
Y480787D01*
G01Y487559D02*
Y485787D01*
G01Y492559D02*
Y490787D01*
G01Y497559D02*
Y495787D01*
G01Y502559D02*
Y500787D01*
G01Y507559D02*
Y505787D01*
G01Y512559D02*
Y510787D01*
G01Y517559D02*
Y515787D01*
G01Y542559D02*
Y540787D01*
G01Y547559D02*
Y545787D01*
G01Y552559D02*
Y550787D01*
G01Y557559D02*
Y555787D01*
G01Y562559D02*
Y560787D01*
G01X41454Y540885D02*
Y542460D01*
G01Y515885D02*
Y517460D01*
G01X41026Y560885D02*
Y562460D01*
G01Y555885D02*
Y557460D01*
G01Y550885D02*
Y552460D01*
G01Y545885D02*
Y547460D01*
G01Y510885D02*
Y512460D01*
G01Y505885D02*
Y507460D01*
G01Y500885D02*
Y502460D01*
G01Y495885D02*
Y497460D01*
G01Y490885D02*
Y492460D01*
G01Y485885D02*
Y487460D01*
G01Y480885D02*
Y482460D01*
G01X40551Y516968D02*
Y541378D01*
G01X40465Y517460D02*
Y515885D01*
G01Y542460D02*
Y540885D01*
G01X40344Y482460D02*
Y480885D01*
G01Y487460D02*
Y485885D01*
G01Y492460D02*
Y490885D01*
G01Y497460D02*
Y495885D01*
G01Y502460D02*
Y500885D01*
G01Y507460D02*
Y505885D01*
G01Y512460D02*
Y510885D01*
G01Y547460D02*
Y545885D01*
G01Y552460D02*
Y550885D01*
G01Y557460D02*
Y555885D01*
G01Y562460D02*
Y560885D01*
G01X38780Y534783D02*
Y536161D01*
G01Y537933D02*
Y539311D01*
G01Y531633D02*
Y533011D01*
G01Y525334D02*
Y526712D01*
G01Y528484D02*
Y529862D01*
G01Y522185D02*
Y523563D01*
G01Y520413D02*
Y519035D01*
G01X79630Y538031D02*
X79646Y537952D01*
G01X79612Y538117D02*
X79630Y538031D01*
G01X78775Y539035D02*
X78741Y539199D01*
G01X78075Y539212D02*
X78071Y539232D01*
G01X78104Y539068D02*
X78075Y539212D01*
G01X78104Y537624D02*
X78071Y537788D01*
G01X79445Y539461D02*
X79411Y539593D01*
G01X79450Y538031D02*
X79478Y537920D01*
G01X79445Y538051D02*
X79450Y538031D01*
G01X78909Y539527D02*
X78942Y539396D01*
G01Y539199D02*
X78976Y539068D01*
G01X78942Y537657D02*
X78909Y537788D01*
G01X78746Y538031D02*
X78775Y537920D01*
G01X78741Y538051D02*
X78746Y538031D01*
G01X78272Y537657D02*
X78239Y537788D01*
G01X78741Y539396D02*
X78708Y539495D01*
G01X78272Y539199D02*
X78306Y539101D01*
G01X85516Y516680D02*
X85483Y516778D01*
G01X79244Y538445D02*
X79411Y538379D01*
G01X79143Y537263D02*
X78976Y537329D01*
G01X78473Y537296D02*
X78306Y537362D01*
G01X82677Y559606D02*
X79528Y560787D01*
G01X82677Y554606D02*
X79528Y555787D01*
G01X82677Y549606D02*
X79528Y550787D01*
G01X82677Y544606D02*
X79528Y545787D01*
G01X79311Y539691D02*
X79210Y539724D01*
G01X78641Y539593D02*
X78540Y539626D01*
G01X78440Y538806D02*
X78339Y538838D01*
G01X85684Y516581D02*
X85583Y516614D01*
G01Y516417D02*
X85684Y516384D01*
G01X75591Y537244D02*
X73228Y537933D01*
G01X75591Y534094D02*
X73228Y534783D01*
G01X75591Y530945D02*
X73228Y531633D01*
G01X75591Y527795D02*
X73228Y528484D01*
G01X75591Y524645D02*
X73228Y525334D01*
G01X75591Y521496D02*
X73228Y522185D01*
G01X75591Y518346D02*
X73228Y519035D01*
G01X79210Y539921D02*
X79344Y539888D01*
G01X78574Y539822D02*
X78708Y539790D01*
G01X82677Y499606D02*
X77559Y500787D01*
G01X78842Y539658D02*
X78909Y539527D01*
G01X79378Y538182D02*
X79445Y538051D01*
G01X78842Y538904D02*
X78775Y539035D01*
G01X78808Y538248D02*
X78842Y538182D01*
G01X79009Y537526D02*
X78942Y537657D01*
G01X78875Y537460D02*
X78842Y537526D01*
G01X79512Y539790D02*
X79612Y539626D01*
G01X79512Y538280D02*
X79612Y538117D01*
G01X78205Y537460D02*
X78104Y537624D01*
G01X78708Y539495D02*
X78641Y539593D01*
G01X78976Y539068D02*
X79043Y538969D01*
G01X78205Y538937D02*
X78104Y539068D01*
G01X78641Y538182D02*
X78741Y538051D01*
G01X78976Y537329D02*
X78875Y537460D01*
G01X78372Y537526D02*
X78272Y537657D01*
G01X85348Y516646D02*
X85449Y516515D01*
G01X40551Y538937D02*
X38583Y540905D01*
G01X79411Y539593D02*
X79311Y539691D01*
G01X78708Y539790D02*
X78842Y539658D01*
G01X79411Y538379D02*
X79512Y538280D01*
G01X78976Y538772D02*
X78842Y538904D01*
G01X78306Y539101D02*
X78372Y539035D01*
G01X78708Y538346D02*
X78808Y538248D01*
G01X78306Y537362D02*
X78205Y537460D01*
G01X85583Y516614D02*
X85516Y516680D01*
G01X79244Y538280D02*
X79378Y538182D01*
G01X78339Y538838D02*
X78205Y538937D01*
G01X79143Y537428D02*
X79009Y537526D01*
G01X85449Y516515D02*
X85583Y516417D01*
G01X79043Y538969D02*
X79143Y538904D01*
G01X78540Y538248D02*
X78641Y538182D01*
G01X78473Y537460D02*
X78372Y537526D01*
G01X79344Y539888D02*
X79512Y539790D01*
G01X79110Y538707D02*
X78976Y538772D01*
G01X78372Y539035D02*
X78440Y539002D01*
G01X78574Y538412D02*
X78708Y538346D01*
G01X82677Y514606D02*
X79528Y515787D01*
G01X82677Y509606D02*
X79528Y510787D01*
G01X82677Y504606D02*
X79528Y505787D01*
G01X82677Y494606D02*
X79528Y495787D01*
G01X82677Y489606D02*
X79528Y490787D01*
G01X82677Y484606D02*
X79528Y485787D01*
G01X14579Y565526D02*
X15464Y565329D01*
G01X15962D02*
X15077Y565526D01*
G01X12600D02*
Y564187D01*
G01X13423Y565526D02*
Y564187D01*
G01X15464Y565329D02*
Y564384D01*
G01X15962Y565329D02*
Y564384D01*
G01D02*
X15464D01*
G01X15962Y565329D02*
X15464D01*
G01X12600Y565526D02*
X15077D01*
G01X15962Y564384D02*
X15077Y564187D01*
G01X14579D02*
X15464Y564384D01*
G01X14579Y569463D02*
X15464Y569266D01*
G01X15962D02*
X15077Y569463D01*
G01X12600Y585211D02*
Y583872D01*
G01Y577337D02*
Y575998D01*
G01Y581274D02*
Y579935D01*
G01Y573400D02*
Y572061D01*
G01Y569463D02*
Y568124D01*
G01X13423Y585211D02*
Y583872D01*
G01Y577337D02*
Y575998D01*
G01Y581274D02*
Y579935D01*
G01Y573400D02*
Y572061D01*
G01Y569463D02*
Y568124D01*
G01X15464Y585014D02*
Y584069D01*
G01Y581077D02*
Y580132D01*
G01Y573203D02*
Y572258D01*
G01Y577140D02*
Y576195D01*
G01Y569266D02*
Y568321D01*
G01X15962Y585014D02*
Y584069D01*
G01Y581077D02*
Y580132D01*
G01Y573203D02*
Y572258D01*
G01Y577140D02*
Y576195D01*
G01Y569266D02*
Y568321D01*
G01X14579Y573400D02*
X15464Y573203D01*
G01X15962D02*
X15077Y573400D01*
G01X14579Y577337D02*
X15464Y577140D01*
G01X15962D02*
X15077Y577337D01*
G01X14579Y581274D02*
X15464Y581077D01*
G01X15962D02*
X15077Y581274D01*
G01X14579Y585211D02*
X15464Y585014D01*
G01X15962D02*
X15077Y585211D01*
G01X15962Y568321D02*
X15464D01*
G01X15962Y569266D02*
X15464D01*
G01X12600Y569463D02*
X15077D01*
G01X15962Y572258D02*
X15464D01*
G01X15962Y573203D02*
X15464D01*
G01X12600Y573400D02*
X15077D01*
G01X15962Y576195D02*
X15464D01*
G01X15962Y577140D02*
X15464D01*
G01X12600Y577337D02*
X15077D01*
G01X15962Y580132D02*
X15464D01*
G01X15962Y581077D02*
X15464D01*
G01X12600Y581274D02*
X15077D01*
G01X15962Y584069D02*
X15464D01*
G01X15962Y585014D02*
X15464D01*
G01X12600Y585211D02*
X15077D01*
G01X15962Y568321D02*
X15077Y568124D01*
G01X14579D02*
X15464Y568321D01*
G01X15962Y572258D02*
X15077Y572061D01*
G01X14579D02*
X15464Y572258D01*
G01X15962Y576195D02*
X15077Y575998D01*
G01X14579D02*
X15464Y576195D01*
G01X15962Y580132D02*
X15077Y579935D01*
G01X14579D02*
X15464Y580132D01*
G01X15962Y584069D02*
X15077Y583872D01*
G01X14579D02*
X15464Y584069D01*
G01X12600Y600959D02*
Y599620D01*
G01Y604896D02*
Y603557D01*
G01Y597022D02*
Y595683D01*
G01Y593085D02*
Y591746D01*
G01Y589148D02*
Y587809D01*
G01X13423Y600959D02*
Y599620D01*
G01Y604896D02*
Y603557D01*
G01Y597022D02*
Y595683D01*
G01Y593085D02*
Y591746D01*
G01Y589148D02*
Y587809D01*
G01X15464Y604699D02*
Y603754D01*
G01Y600762D02*
Y599817D01*
G01Y596825D02*
Y595880D01*
G01Y592888D02*
Y591943D01*
G01Y588951D02*
Y588006D01*
G01X15962Y604699D02*
Y603754D01*
G01Y600762D02*
Y599817D01*
G01Y596825D02*
Y595880D01*
G01Y592888D02*
Y591943D01*
G01Y588951D02*
Y588006D01*
G01X14579Y589148D02*
X15464Y588951D01*
G01X15962D02*
X15077Y589148D01*
G01X14579Y593085D02*
X15464Y592888D01*
G01X15962D02*
X15077Y593085D01*
G01X14579Y597022D02*
X15464Y596825D01*
G01X15962D02*
X15077Y597022D01*
G01X14579Y600959D02*
X15464Y600762D01*
G01X15962D02*
X15077Y600959D01*
G01X14579Y604896D02*
X15464Y604699D01*
G01X15962D02*
X15077Y604896D01*
G01X15962Y588006D02*
X15464D01*
G01X15962Y588951D02*
X15464D01*
G01X12600Y589148D02*
X15077D01*
G01X15962Y591943D02*
X15464D01*
G01X15962Y592888D02*
X15464D01*
G01X12600Y593085D02*
X15077D01*
G01X15962Y595880D02*
X15464D01*
G01X15962Y596825D02*
X15464D01*
G01X12600Y597022D02*
X15077D01*
G01X15962Y599817D02*
X15464D01*
G01X15962Y600762D02*
X15464D01*
G01X12600Y600959D02*
X15077D01*
G01X15962Y603754D02*
X15464D01*
G01X15962Y604699D02*
X15464D01*
G01X12600Y604896D02*
X15077D01*
G01X15962Y588006D02*
X15077Y587809D01*
G01X14579D02*
X15464Y588006D01*
G01X15962Y591943D02*
X15077Y591746D01*
G01X14579D02*
X15464Y591943D01*
G01X15962Y595880D02*
X15077Y595683D01*
G01X14579D02*
X15464Y595880D01*
G01X15962Y599817D02*
X15077Y599620D01*
G01X14579D02*
X15464Y599817D01*
G01X15962Y603754D02*
X15077Y603557D01*
G01X14579D02*
X15464Y603754D01*
G01X12600Y624581D02*
Y623243D01*
G01Y620644D02*
Y619306D01*
G01Y616707D02*
Y615369D01*
G01Y612770D02*
Y611431D01*
G01Y608833D02*
Y607494D01*
G01X13423Y624581D02*
Y623243D01*
G01Y620644D02*
Y619306D01*
G01Y616707D02*
Y615369D01*
G01Y612770D02*
Y611431D01*
G01Y608833D02*
Y607494D01*
G01X15464Y624384D02*
Y623439D01*
G01Y620447D02*
Y619502D01*
G01Y616510D02*
Y615565D01*
G01Y612573D02*
Y611628D01*
G01Y608636D02*
Y607691D01*
G01X15962Y624384D02*
Y623439D01*
G01Y620447D02*
Y619502D01*
G01Y616510D02*
Y615565D01*
G01Y612573D02*
Y611628D01*
G01Y608636D02*
Y607691D01*
G01X14579Y608833D02*
X15464Y608636D01*
G01X15962D02*
X15077Y608833D01*
G01X14579Y612770D02*
X15464Y612573D01*
G01X15962D02*
X15077Y612770D01*
G01X14579Y616707D02*
X15464Y616510D01*
G01X15962D02*
X15077Y616707D01*
G01X14579Y620644D02*
X15464Y620447D01*
G01X15962D02*
X15077Y620644D01*
G01X14579Y624581D02*
X15464Y624384D01*
G01X15962D02*
X15077Y624581D01*
G01X15962Y607691D02*
X15464D01*
G01X15962Y608636D02*
X15464D01*
G01X12600Y608833D02*
X15077D01*
G01X15962Y611628D02*
X15464D01*
G01X15962Y612573D02*
X15464D01*
G01X12600Y612770D02*
X15077D01*
G01X15962Y615565D02*
X15464D01*
G01X15962Y616510D02*
X15464D01*
G01X12600Y616707D02*
X15077D01*
G01X15962Y619502D02*
X15464D01*
G01X15962Y620447D02*
X15464D01*
G01X12600Y620644D02*
X15077D01*
G01X15962Y623439D02*
X15464D01*
G01X15962Y624384D02*
X15464D01*
G01X12600Y624581D02*
X15077D01*
G01X15962Y607691D02*
X15077Y607494D01*
G01X14579D02*
X15464Y607691D01*
G01X15962Y611628D02*
X15077Y611431D01*
G01X14579D02*
X15464Y611628D01*
G01X15962Y615565D02*
X15077Y615369D01*
G01X14579D02*
X15464Y615565D01*
G01X15962Y619502D02*
X15077Y619306D01*
G01X14579D02*
X15464Y619502D01*
G01X15962Y623439D02*
X15077Y623243D01*
G01X14579D02*
X15464Y623439D01*
G01X12600Y644266D02*
Y642928D01*
G01Y640329D02*
Y638991D01*
G01Y636392D02*
Y635054D01*
G01Y632455D02*
Y631117D01*
G01Y628518D02*
Y627180D01*
G01X13423Y644266D02*
Y642928D01*
G01Y640329D02*
Y638991D01*
G01Y636392D02*
Y635054D01*
G01Y632455D02*
Y631117D01*
G01Y628518D02*
Y627180D01*
G01X15464Y644069D02*
Y643124D01*
G01Y640132D02*
Y639187D01*
G01Y636195D02*
Y635250D01*
G01Y632258D02*
Y631313D01*
G01Y628321D02*
Y627376D01*
G01X15962Y644069D02*
Y643124D01*
G01Y640132D02*
Y639187D01*
G01Y636195D02*
Y635250D01*
G01Y632258D02*
Y631313D01*
G01Y628321D02*
Y627376D01*
G01X14579Y628518D02*
X15464Y628321D01*
G01X15962D02*
X15077Y628518D01*
G01X14579Y632455D02*
X15464Y632258D01*
G01X15962D02*
X15077Y632455D01*
G01X14579Y636392D02*
X15464Y636195D01*
G01X15962D02*
X15077Y636392D01*
G01X14579Y640329D02*
X15464Y640132D01*
G01X15962D02*
X15077Y640329D01*
G01X14579Y644266D02*
X15464Y644069D01*
G01X15962D02*
X15077Y644266D01*
G01X15962Y627376D02*
X15464D01*
G01X15962Y628321D02*
X15464D01*
G01X12600Y628518D02*
X15077D01*
G01X15962Y631313D02*
X15464D01*
G01X15962Y632258D02*
X15464D01*
G01X12600Y632455D02*
X15077D01*
G01X15962Y635250D02*
X15464D01*
G01X15962Y636195D02*
X15464D01*
G01X12600Y636392D02*
X15077D01*
G01X15962Y639187D02*
X15464D01*
G01X15962Y640132D02*
X15464D01*
G01X12600Y640329D02*
X15077D01*
G01X15962Y643124D02*
X15464D01*
G01X15962Y644069D02*
X15464D01*
G01X12600Y644266D02*
X15077D01*
G01X15962Y627376D02*
X15077Y627180D01*
G01X14579D02*
X15464Y627376D01*
G01X15962Y631313D02*
X15077Y631117D01*
G01X14579D02*
X15464Y631313D01*
G01X15962Y635250D02*
X15077Y635054D01*
G01X14579D02*
X15464Y635250D01*
G01X15962Y639187D02*
X15077Y638991D01*
G01X14579D02*
X15464Y639187D01*
G01X15962Y643124D02*
X15077Y642928D01*
G01X14579D02*
X15464Y643124D01*
G01X31889Y583563D02*
Y585492D01*
G01X64172Y615807D02*
Y613839D01*
G01Y611280D02*
Y613248D01*
G01X65664Y612265D02*
Y612393D01*
G01X65747Y616102D02*
Y615512D01*
G01Y614331D02*
Y612756D01*
G01Y611575D02*
Y610984D01*
G01X65758Y611756D02*
Y612377D01*
G01X65851Y612504D02*
Y611756D01*
G01X66731Y610984D02*
Y616102D01*
G01X66928D02*
Y610984D01*
G01X67322Y613248D02*
Y611280D01*
G01Y613839D02*
Y615807D01*
G01X65747Y610984D02*
X72046D01*
G01X67322Y611280D02*
X65747D01*
G01D02*
X64172D01*
G01X65851Y611756D02*
X65758D01*
G01Y612504D02*
X65851D01*
G01X65747Y613248D02*
X67322D01*
G01X64172D02*
X65747D01*
G01Y613839D02*
X67322D01*
G01X64172D02*
X65747D01*
G01X67322Y615807D02*
X65747D01*
G01D02*
X64172D01*
G01X65747Y616102D02*
X72046D01*
G01X65664Y612393D02*
X65758Y612504D01*
G01Y612377D02*
X65664Y612265D01*
G01X65747Y614331D02*
G03Y615512I0J590D01*
G01Y611575D02*
G03Y612756I0J590D01*
G01X70471Y613248D02*
Y611280D01*
G01Y613839D02*
Y615807D01*
G01X70865Y616102D02*
Y610984D01*
G01X71062D02*
Y616102D01*
G01X72046Y610984D02*
Y611575D01*
G01Y612756D02*
Y614331D01*
G01Y615512D02*
Y616102D01*
G01X73621Y615807D02*
Y613839D01*
G01Y611280D02*
Y613248D01*
G01X70471Y611280D02*
X72046D01*
G01D02*
X73621D01*
G01X72046Y613248D02*
X70471D01*
G01X73621D02*
X72046D01*
G01Y613839D02*
X70471D01*
G01X73621D02*
X72046D01*
G01X70471Y615807D02*
X72046D01*
G01D02*
X73621D01*
G01X72046Y615512D02*
G03Y614331I0J-591D01*
G01Y612756D02*
G03Y611575I0J-591D01*
G01X78224Y579843D02*
X78150Y579842D01*
G01X78075Y588109D02*
X78150Y588110D01*
G01X80709Y583976D02*
G03I-2559J0D01*
G01X81496D02*
G03I-3346J0D01*
G01X81654D02*
G03I-3504J0D01*
G01X72638Y595787D02*
G03I-3740J0D01*
G01X78075Y588109D02*
G03X78150Y579842I74J-4133D01*
G01X78224Y579843D02*
G03X78150Y588110I-73J4133D01*
G01X85757Y572342D02*
X85656Y572309D01*
G01X79528Y567559D02*
X82677Y568740D01*
G01X79528Y572559D02*
X82677Y573740D01*
G01X86695Y571489D02*
X86561Y571424D01*
G01X86527Y571620D02*
X86628Y571686D01*
G01X85622Y570964D02*
X85857Y571161D01*
G01X85589D02*
X85354Y570964D01*
G01X86829Y571620D02*
X86695Y571489D01*
G01X85542Y572460D02*
X85589Y572506D01*
G01X85455Y572375D02*
X85542Y572460D01*
G01X36610Y587652D02*
X31890Y583011D01*
G01Y584114D02*
X36614Y588759D01*
G01X40551Y580413D02*
X38583Y578445D01*
G01X86628Y571686D02*
X86695Y571784D01*
G01X85656Y572309D02*
X85589Y572211D01*
G01X86896Y571752D02*
X86829Y571620D01*
G01X85388Y572244D02*
X85455Y572375D01*
G01X85589Y572211D02*
X85556Y572113D01*
G01X85589Y572506D02*
X85723Y572539D01*
G01X86695Y571784D02*
X86728Y571916D01*
G01X85354Y572113D02*
X85388Y572244D01*
G01X86929Y571916D02*
X86896Y571752D01*
G01X55118Y605649D02*
X82677D01*
G01X78740Y601712D02*
X59055D01*
G01X78740Y599744D02*
X59055D01*
G01X78740Y597756D02*
X59055D01*
G01Y596771D02*
X78740D01*
G01X59252Y596574D02*
X78543D01*
G01X59252Y595000D02*
X78543D01*
G01X78740Y594803D02*
X59055D01*
G01Y593819D02*
X78740D01*
G01X27953Y592696D02*
X55118D01*
G01X94488D02*
X82677D01*
G01X78740Y590728D02*
X59055D01*
G01X36614Y588759D02*
X90551D01*
G01X36614Y587578D02*
X70079D01*
G01Y583366D02*
X59055D01*
G01X90551D02*
X70079D01*
G01X35300Y580413D02*
X38583D01*
G01X90551D02*
X40551D01*
G01X90551Y577263D02*
X70866D01*
G01Y575492D02*
X90551D01*
G01X69587D02*
X70866D01*
G01X68209D02*
X39764D01*
G01X38583Y572559D02*
X70866D01*
G01X79528D02*
X74803D01*
G01X85723Y572539D02*
X85857D01*
G01X70866Y572460D02*
X88110D01*
G01X40344D02*
X70866D01*
G01X85824Y572342D02*
X85757D01*
G01X86427Y571620D02*
X86527D01*
G01X86561Y571424D02*
X86393D01*
G01X85857Y571161D02*
X85589D01*
G01X86929Y570964D02*
X85622D01*
G01X70866Y570885D02*
X88110D01*
G01X40344D02*
X70866D01*
G01X74803Y570787D02*
X79528D01*
G01X38583D02*
X70866D01*
G01X85354Y570767D02*
X86929D01*
G01X38583Y567559D02*
X70866D01*
G01X79528D02*
X74803D01*
G01X70866Y567460D02*
X88110D01*
G01X40344D02*
X70866D01*
G01Y565885D02*
X88110D01*
G01X40344D02*
X70866D01*
G01X74803Y565787D02*
X79528D01*
G01X38583D02*
X70866D01*
G01X90551Y575492D02*
Y588759D01*
G01X88110Y567460D02*
Y565885D01*
G01Y572460D02*
Y570885D01*
G01X86929Y570767D02*
Y570885D01*
G01D02*
Y570964D01*
G01Y572178D02*
Y571916D01*
G01X86728D02*
Y572178D01*
G01X86494Y572460D02*
Y572637D01*
G01Y572441D02*
Y572460D01*
G01X86226Y572113D02*
Y571916D01*
G01X86024D02*
Y572113D01*
G01X85723Y571719D02*
Y571522D01*
G01X85556Y572113D02*
Y571916D01*
G01X85354Y571948D02*
Y572113D01*
G01Y570885D02*
Y570767D01*
G01Y570964D02*
Y570885D01*
G01X83189D02*
Y572460D01*
G01Y565885D02*
Y567460D01*
G01X82795D02*
Y565885D01*
G01Y572460D02*
Y570885D01*
G01X82677Y564606D02*
Y563740D01*
G01Y569606D02*
Y568740D01*
G01Y575492D02*
Y573740D01*
G01Y605649D02*
Y592696D01*
G01X82008Y567460D02*
Y565885D01*
G01Y572460D02*
Y570885D01*
G01X80433Y567460D02*
Y565885D01*
G01Y572460D02*
Y570885D01*
G01X78740Y588759D02*
Y601712D01*
G01X78543Y595000D02*
Y596574D01*
G01X74803Y565885D02*
Y565787D01*
G01Y567559D02*
Y567460D01*
G01D02*
Y565885D01*
G01Y570885D02*
Y570787D01*
G01Y572559D02*
Y572460D01*
G01D02*
Y570885D01*
G01X73189Y596574D02*
Y595000D01*
G01X86896Y572342D02*
X86929Y572178D01*
G01X86058Y571752D02*
X86024Y571916D01*
G01X85388Y571784D02*
X85354Y571948D01*
G01X86494Y572637D02*
X86628Y572605D01*
G01X85857Y572539D02*
X85991Y572506D01*
G01X71850Y596574D02*
Y596771D01*
G01Y595000D02*
Y594803D01*
G01Y596574D02*
Y595000D01*
G01X71654Y596574D02*
Y595000D01*
G01X70079D02*
Y596574D01*
G01Y588759D02*
Y580413D01*
G01X67717Y595000D02*
Y596574D01*
G01X66142Y595000D02*
Y596574D01*
G01X65945Y595000D02*
Y596574D01*
G01Y595000D02*
Y594803D01*
G01Y596771D02*
Y596574D01*
G01X64606Y595000D02*
Y596574D01*
G01X59252D02*
Y595000D01*
G01X59055Y588759D02*
Y601712D01*
G01X55118Y592696D02*
Y605649D01*
G01X46553Y567460D02*
Y565885D01*
G01Y572460D02*
Y570885D01*
G01X45447Y567460D02*
Y565885D01*
G01Y572460D02*
Y570885D01*
G01X45201Y567460D02*
Y565885D01*
G01Y572460D02*
Y570885D01*
G01X41535Y567559D02*
Y565787D01*
G01Y572559D02*
Y570787D01*
G01X41026Y570885D02*
Y572460D01*
G01Y565885D02*
Y567460D01*
G01X40344D02*
Y565885D01*
G01Y572460D02*
Y570885D01*
G01X36614Y580413D02*
Y587578D01*
G01X31890Y582382D02*
Y584114D01*
G01X86728Y572178D02*
X86695Y572309D01*
G01X86192Y572244D02*
X86226Y572113D01*
G01Y571916D02*
X86259Y571784D01*
G01X86024Y572113D02*
X85991Y572211D01*
G01X85556Y571916D02*
X85589Y571817D01*
G01X86125Y572375D02*
X86192Y572244D01*
G01X86125Y571620D02*
X86058Y571752D01*
G01X86795Y572506D02*
X86823Y572460D01*
G01D02*
X86896Y572342D01*
G01X85991Y572211D02*
X85924Y572309D01*
G01X86259Y571784D02*
X86326Y571686D01*
G01D02*
X86427Y571620D01*
G01X86628Y572605D02*
X86795Y572506D01*
G01X86393Y571424D02*
X86259Y571489D01*
G01X85656Y571752D02*
X85723Y571719D01*
G01X82677Y569606D02*
X79528Y570787D01*
G01X82677Y564606D02*
X79528Y565787D01*
G01X86594Y572408D02*
X86494Y572441D01*
G01X85924Y572309D02*
X85824Y572342D01*
G01X85723Y571522D02*
X85622Y571555D01*
G01X85489Y571653D02*
X85388Y571784D01*
G01X39764Y575492D02*
X38583Y576673D01*
G01X86695Y572309D02*
X86594Y572408D01*
G01X85991Y572506D02*
X86038Y572460D01*
G01D02*
X86125Y572375D01*
G01X86259Y571489D02*
X86125Y571620D01*
G01X85589Y571817D02*
X85656Y571752D01*
G01X85622Y571555D02*
X85489Y571653D01*
G01X31890Y582382D02*
X35300Y580413D01*
G01X12600Y663951D02*
Y662613D01*
G01Y660014D02*
Y658676D01*
G01Y652140D02*
Y650802D01*
G01Y656077D02*
Y654739D01*
G01Y648203D02*
Y646865D01*
G01X13423Y663951D02*
Y662613D01*
G01Y660014D02*
Y658676D01*
G01Y652140D02*
Y650802D01*
G01Y656077D02*
Y654739D01*
G01Y648203D02*
Y646865D01*
G01X15464Y663754D02*
Y662809D01*
G01Y659817D02*
Y658872D01*
G01Y655880D02*
Y654935D01*
G01Y651943D02*
Y650998D01*
G01Y648006D02*
Y647061D01*
G01X15962Y663754D02*
Y662809D01*
G01Y659817D02*
Y658872D01*
G01Y655880D02*
Y654935D01*
G01Y651943D02*
Y650998D01*
G01Y648006D02*
Y647061D01*
G01X14579Y648203D02*
X15464Y648006D01*
G01X15962D02*
X15077Y648203D01*
G01X14579Y652140D02*
X15464Y651943D01*
G01X15962D02*
X15077Y652140D01*
G01X14579Y656077D02*
X15464Y655880D01*
G01X15962D02*
X15077Y656077D01*
G01X14579Y660014D02*
X15464Y659817D01*
G01X15962D02*
X15077Y660014D01*
G01X14579Y663951D02*
X15464Y663754D01*
G01X15962D02*
X15077Y663951D01*
G01X15962Y647061D02*
X15464D01*
G01X15962Y648006D02*
X15464D01*
G01X12600Y648203D02*
X15077D01*
G01X15962Y650998D02*
X15464D01*
G01X15962Y651943D02*
X15464D01*
G01X12600Y652140D02*
X15077D01*
G01X15962Y654935D02*
X15464D01*
G01X15962Y655880D02*
X15464D01*
G01X12600Y656077D02*
X15077D01*
G01X15962Y658872D02*
X15464D01*
G01X15962Y659817D02*
X15464D01*
G01X12600Y660014D02*
X15077D01*
G01X15962Y662809D02*
X15464D01*
G01X15962Y663754D02*
X15464D01*
G01X12600Y663951D02*
X15077D01*
G01X15962Y647061D02*
X15077Y646865D01*
G01X14579D02*
X15464Y647061D01*
G01X15962Y650998D02*
X15077Y650802D01*
G01X14579D02*
X15464Y650998D01*
G01X15962Y654935D02*
X15077Y654739D01*
G01X14579D02*
X15464Y654935D01*
G01X15962Y658872D02*
X15077Y658676D01*
G01X14579D02*
X15464Y658872D01*
G01X15962Y662809D02*
X15077Y662613D01*
G01X14579D02*
X15464Y662809D01*
G01X12600Y687573D02*
Y686235D01*
G01Y683636D02*
Y682298D01*
G01Y675762D02*
Y674424D01*
G01Y679699D02*
Y678361D01*
G01Y671825D02*
Y670487D01*
G01Y667888D02*
Y666550D01*
G01X13423Y687573D02*
Y686235D01*
G01Y683636D02*
Y682298D01*
G01Y675762D02*
Y674424D01*
G01Y679699D02*
Y678361D01*
G01Y671825D02*
Y670487D01*
G01Y667888D02*
Y666550D01*
G01X15464Y683439D02*
Y682494D01*
G01Y679502D02*
Y678557D01*
G01Y675565D02*
Y674620D01*
G01Y671628D02*
Y670683D01*
G01Y667691D02*
Y666746D01*
G01X15962Y683439D02*
Y682494D01*
G01Y679502D02*
Y678557D01*
G01Y675565D02*
Y674620D01*
G01Y671628D02*
Y670683D01*
G01Y667691D02*
Y666746D01*
G01X14579Y667888D02*
X15464Y667691D01*
G01X15962D02*
X15077Y667888D01*
G01X14579Y671825D02*
X15464Y671628D01*
G01X15962D02*
X15077Y671825D01*
G01X14579Y675762D02*
X15464Y675565D01*
G01X15962D02*
X15077Y675762D01*
G01X14579Y679699D02*
X15464Y679502D01*
G01X15962D02*
X15077Y679699D01*
G01X14579Y683636D02*
X15464Y683439D01*
G01X15962D02*
X15077Y683636D01*
G01X15962Y666746D02*
X15464D01*
G01X15962Y667691D02*
X15464D01*
G01X12600Y667888D02*
X15077D01*
G01X15962Y670683D02*
X15464D01*
G01X15962Y671628D02*
X15464D01*
G01X12600Y671825D02*
X15077D01*
G01X15962Y674620D02*
X15464D01*
G01X15962Y675565D02*
X15464D01*
G01X12600Y675762D02*
X15077D01*
G01X15962Y678557D02*
X15464D01*
G01X15962Y679502D02*
X15464D01*
G01X12600Y679699D02*
X15077D01*
G01X15962Y682494D02*
X15464D01*
G01X15962Y683439D02*
X15464D01*
G01X12600Y683636D02*
X15077D01*
G01X15962Y666746D02*
X15077Y666550D01*
G01X14579D02*
X15464Y666746D01*
G01X15962Y670683D02*
X15077Y670487D01*
G01X14579D02*
X15464Y670683D01*
G01X15962Y674620D02*
X15077Y674424D01*
G01X14579D02*
X15464Y674620D01*
G01X15962Y678557D02*
X15077Y678361D01*
G01X14579D02*
X15464Y678557D01*
G01X15962Y682494D02*
X15077Y682298D01*
G01X14579D02*
X15464Y682494D01*
G01X15962Y686431D02*
X15077Y686235D01*
G01X14579D02*
X15464Y686431D01*
G01X12600Y699384D02*
Y698046D01*
G01Y695447D02*
Y694109D01*
G01Y691510D02*
Y690172D01*
G01X13423Y699384D02*
Y698046D01*
G01Y695447D02*
Y694109D01*
G01Y691510D02*
Y690172D01*
G01X15464Y699187D02*
Y698243D01*
G01Y695250D02*
Y694306D01*
G01Y691313D02*
Y690369D01*
G01Y687376D02*
Y686431D01*
G01X15962Y699187D02*
Y698243D01*
G01Y695250D02*
Y694306D01*
G01Y691313D02*
Y690369D01*
G01Y687376D02*
Y686431D01*
G01X22834Y729916D02*
Y704325D01*
G01X24802D02*
Y729916D01*
G01X14579Y687573D02*
X15464Y687376D01*
G01X15962D02*
X15077Y687573D01*
G01X14579Y691510D02*
X15464Y691313D01*
G01X15962D02*
X15077Y691510D01*
G01X14579Y695447D02*
X15464Y695250D01*
G01X15962D02*
X15077Y695447D01*
G01X14579Y699384D02*
X15464Y699187D01*
G01X15962D02*
X15077Y699384D01*
G01X15962Y686431D02*
X15464D01*
G01X15962Y687376D02*
X15464D01*
G01X12600Y687573D02*
X15077D01*
G01X15962Y690369D02*
X15464D01*
G01X15962Y691313D02*
X15464D01*
G01X12600Y691510D02*
X15077D01*
G01X15962Y694306D02*
X15464D01*
G01X15962Y695250D02*
X15464D01*
G01X12600Y695447D02*
X15077D01*
G01X15962Y698243D02*
X15464D01*
G01X15962Y699187D02*
X15464D01*
G01X12600Y699384D02*
X15077D01*
G01X15962Y690369D02*
X15077Y690172D01*
G01X14579D02*
X15464Y690369D01*
G01X15962Y694306D02*
X15077Y694109D01*
G01X14579D02*
X15464Y694306D01*
G01X15962Y698243D02*
X15077Y698046D01*
G01X14579D02*
X15464Y698243D01*
G01X22851Y775993D02*
Y750402D01*
G01X24802Y775993D02*
Y750402D01*
G01X26771Y889378D02*
Y748433D01*
G01X12829Y780721D02*
Y782059D01*
G01Y784658D02*
Y785996D01*
G01X13613D02*
Y784658D01*
G01Y782059D02*
Y780721D01*
G01X15464Y785800D02*
Y784855D01*
G01Y781863D02*
Y780918D01*
G01X16248D02*
Y781863D01*
G01Y784855D02*
Y785800D01*
G01X14688Y782059D02*
X15464Y781863D01*
G01X16248D02*
X15472Y782059D01*
G01X14688Y785996D02*
X15464Y785800D01*
G01X16248D02*
X15472Y785996D01*
G01Y780721D02*
X12829D01*
G01X16248Y780918D02*
X15464D01*
G01X16248Y781863D02*
X15464D01*
G01X15472Y782059D02*
X12829D01*
G01X15472Y784658D02*
X12829D01*
G01X16248Y784855D02*
X15464D01*
G01X16248Y785800D02*
X15464D01*
G01X15472Y785996D02*
X12829D01*
G01X15472Y780721D02*
X16248Y780918D01*
G01X15464D02*
X14688Y780721D01*
G01X15472Y784658D02*
X16248Y784855D01*
G01X15464D02*
X14688Y784658D01*
G01X12829Y788595D02*
Y789933D01*
G01Y792532D02*
Y793870D01*
G01Y800406D02*
Y801744D01*
G01Y796469D02*
Y797807D01*
G01Y804343D02*
Y805681D01*
G01X13613D02*
Y804343D01*
G01Y797807D02*
Y796469D01*
G01Y801744D02*
Y800406D01*
G01Y793870D02*
Y792532D01*
G01Y789933D02*
Y788595D01*
G01X15464Y805485D02*
Y804540D01*
G01Y797611D02*
Y796666D01*
G01Y801548D02*
Y800603D01*
G01Y793674D02*
Y792729D01*
G01Y789737D02*
Y788792D01*
G01X16248D02*
Y789737D01*
G01Y792729D02*
Y793674D01*
G01Y800603D02*
Y801548D01*
G01Y796666D02*
Y797611D01*
G01Y804540D02*
Y805485D01*
G01X14688Y789933D02*
X15464Y789737D01*
G01X16248D02*
X15472Y789933D01*
G01X14688Y793870D02*
X15464Y793674D01*
G01X16248D02*
X15472Y793870D01*
G01X14688Y797807D02*
X15464Y797611D01*
G01X16248D02*
X15472Y797807D01*
G01X14688Y801744D02*
X15464Y801548D01*
G01X16248D02*
X15472Y801744D01*
G01X14688Y805681D02*
X15464Y805485D01*
G01X16248D02*
X15472Y805681D01*
G01Y788595D02*
X12829D01*
G01X16248Y788792D02*
X15464D01*
G01X16248Y789737D02*
X15464D01*
G01X15472Y789933D02*
X12829D01*
G01X15472Y792532D02*
X12829D01*
G01X16248Y792729D02*
X15464D01*
G01X16248Y793674D02*
X15464D01*
G01X15472Y793870D02*
X12829D01*
G01X15472Y796469D02*
X12829D01*
G01X16248Y796666D02*
X15464D01*
G01X16248Y797611D02*
X15464D01*
G01X15472Y797807D02*
X12829D01*
G01X15472Y800406D02*
X12829D01*
G01X16248Y800603D02*
X15464D01*
G01X16248Y801548D02*
X15464D01*
G01X15472Y801744D02*
X12829D01*
G01X15472Y804343D02*
X12829D01*
G01X16248Y804540D02*
X15464D01*
G01X16248Y805485D02*
X15464D01*
G01X15472Y805681D02*
X12829D01*
G01X15472Y788595D02*
X16248Y788792D01*
G01X15464D02*
X14688Y788595D01*
G01X15472Y792532D02*
X16248Y792729D01*
G01X15464D02*
X14688Y792532D01*
G01X15472Y796469D02*
X16248Y796666D01*
G01X15464D02*
X14688Y796469D01*
G01X15472Y800406D02*
X16248Y800603D01*
G01X15464D02*
X14688Y800406D01*
G01X15472Y804343D02*
X16248Y804540D01*
G01X15464D02*
X14688Y804343D01*
G01X12829Y808280D02*
Y809619D01*
G01X13613D02*
Y808280D01*
G01X15464Y809422D02*
Y808477D01*
G01X16248D02*
Y809422D01*
G01X14688Y809619D02*
X15464Y809422D01*
G01X16248D02*
X15472Y809619D01*
G01Y808280D02*
X12829D01*
G01X16248Y808477D02*
X15464D01*
G01X16248Y809422D02*
X15464D01*
G01X15472Y809619D02*
X12829D01*
G01X15472Y808280D02*
X16248Y808477D01*
G01X15464D02*
X14688Y808280D01*
G01X12829Y812217D02*
Y813556D01*
G01Y816154D02*
Y817493D01*
G01Y820091D02*
Y821430D01*
G01X13613D02*
Y820091D01*
G01Y817493D02*
Y816154D01*
G01Y813556D02*
Y812217D01*
G01X15464Y821233D02*
Y820288D01*
G01Y817296D02*
Y816351D01*
G01Y813359D02*
Y812414D01*
G01X15550Y830294D02*
Y823286D01*
G01X16248Y812414D02*
Y813359D01*
G01Y816351D02*
Y817296D01*
G01Y820288D02*
Y821233D01*
G01X18700Y829160D02*
Y824420D01*
G01X14688Y813556D02*
X15464Y813359D01*
G01X16248D02*
X15472Y813556D01*
G01X14688Y817493D02*
X15464Y817296D01*
G01X16248D02*
X15472Y817493D01*
G01X14688Y821430D02*
X15464Y821233D01*
G01X16248D02*
X15472Y821430D01*
G01Y812217D02*
X12829D01*
G01X16248Y812414D02*
X15464D01*
G01X16248Y813359D02*
X15464D01*
G01X15472Y813556D02*
X12829D01*
G01X15472Y816154D02*
X12829D01*
G01X16248Y816351D02*
X15464D01*
G01X16248Y817296D02*
X15464D01*
G01X15472Y817493D02*
X12829D01*
G01X15472Y820091D02*
X12829D01*
G01X16248Y820288D02*
X15464D01*
G01X16248Y821233D02*
X15464D01*
G01X15472Y821430D02*
X12829D01*
G01X15550Y823286D02*
X18700Y824420D01*
G01X15472Y812217D02*
X16248Y812414D01*
G01X15464D02*
X14688Y812217D01*
G01X15472Y816154D02*
X16248Y816351D01*
G01X15464D02*
X14688Y816154D01*
G01X15472Y820091D02*
X16248Y820288D01*
G01X15464D02*
X14688Y820091D01*
G01X19881Y823031D02*
G03Y830512I0J3741D01*
G01X12829Y831902D02*
Y833241D01*
G01Y835839D02*
Y837178D01*
G01Y839776D02*
Y841115D01*
G01Y843713D02*
Y845052D01*
G01X13613D02*
Y843713D01*
G01Y841115D02*
Y839776D01*
G01Y837178D02*
Y835839D01*
G01Y833241D02*
Y831902D01*
G01X15464Y844855D02*
Y843910D01*
G01Y840918D02*
Y839973D01*
G01Y836981D02*
Y836036D01*
G01Y833044D02*
Y832099D01*
G01X16248D02*
Y833044D01*
G01Y836036D02*
Y836981D01*
G01Y839973D02*
Y840918D01*
G01Y843910D02*
Y844855D01*
G01X15550Y830294D02*
X18700Y829160D01*
G01X14688Y833241D02*
X15464Y833044D01*
G01X16248D02*
X15472Y833241D01*
G01X14688Y837178D02*
X15464Y836981D01*
G01X16248D02*
X15472Y837178D01*
G01X14688Y841115D02*
X15464Y840918D01*
G01X16248D02*
X15472Y841115D01*
G01X14688Y845052D02*
X15464Y844855D01*
G01X16248D02*
X15472Y845052D01*
G01Y831902D02*
X12829D01*
G01X16248Y832099D02*
X15464D01*
G01X16248Y833044D02*
X15464D01*
G01X15472Y833241D02*
X12829D01*
G01X15472Y835839D02*
X12829D01*
G01X16248Y836036D02*
X15464D01*
G01X16248Y836981D02*
X15464D01*
G01X15472Y837178D02*
X12829D01*
G01X15472Y839776D02*
X12829D01*
G01X16248Y839973D02*
X15464D01*
G01X16248Y840918D02*
X15464D01*
G01X15472Y841115D02*
X12829D01*
G01X15472Y843713D02*
X12829D01*
G01X16248Y843910D02*
X15464D01*
G01X16248Y844855D02*
X15464D01*
G01X15472Y845052D02*
X12829D01*
G01X15472Y831902D02*
X16248Y832099D01*
G01X15464D02*
X14688Y831902D01*
G01X15472Y835839D02*
X16248Y836036D01*
G01X15464D02*
X14688Y835839D01*
G01X15472Y839776D02*
X16248Y839973D01*
G01X15464D02*
X14688Y839776D01*
G01X15472Y843713D02*
X16248Y843910D01*
G01X15464D02*
X14688Y843713D01*
G01X12829Y847650D02*
Y848989D01*
G01Y851587D02*
Y852926D01*
G01Y855524D02*
Y856863D01*
G01X13613D02*
Y855524D01*
G01Y852926D02*
Y851587D01*
G01Y848989D02*
Y847650D01*
G01X15464Y856666D02*
Y855721D01*
G01Y848792D02*
Y847847D01*
G01Y852729D02*
Y851784D01*
G01X16248Y847847D02*
Y848792D01*
G01Y851784D02*
Y852729D01*
G01Y855721D02*
Y856666D01*
G01X22851Y887410D02*
Y861819D01*
G01X24802Y887410D02*
Y861819D01*
G01X14688Y848989D02*
X15464Y848792D01*
G01X16248D02*
X15472Y848989D01*
G01X14688Y852926D02*
X15464Y852729D01*
G01X16248D02*
X15472Y852926D01*
G01X14688Y856863D02*
X15464Y856666D01*
G01X16248D02*
X15472Y856863D01*
G01Y847650D02*
X12829D01*
G01X16248Y847847D02*
X15464D01*
G01X16248Y848792D02*
X15464D01*
G01X15472Y848989D02*
X12829D01*
G01X15472Y851587D02*
X12829D01*
G01X16248Y851784D02*
X15464D01*
G01X16248Y852729D02*
X15464D01*
G01X15472Y852926D02*
X12829D01*
G01X15472Y855524D02*
X12829D01*
G01X16248Y855721D02*
X15464D01*
G01X16248Y856666D02*
X15464D01*
G01X15472Y856863D02*
X12829D01*
G01X15472Y847650D02*
X16248Y847847D01*
G01X15464D02*
X14688Y847650D01*
G01X15472Y851587D02*
X16248Y851784D01*
G01X15464D02*
X14688Y851587D01*
G01X15472Y855524D02*
X16248Y855721D01*
G01X15464D02*
X14688Y855524D01*
G01X80167Y838307D02*
G03Y841456I-2017J1575D01*
G01X76133D02*
G03Y838307I2017J-1574D01*
G01X75780Y842244D02*
G03Y837519I2370J-2362D01*
G01X80520D02*
G03Y842244I-2370J2363D01*
G01X81654Y839882D02*
G03I-3504J0D01*
G01X75472Y843031D02*
G03Y836732I2678J-3149D01*
G01X80827D02*
G03Y843031I-2677J3150D01*
G01X72638Y828071D02*
G03I-3740J0D01*
G01X77559Y868070D02*
X82677Y869252D01*
G01X79528Y853070D02*
X82677Y854252D01*
G01X79528Y858070D02*
X82677Y859252D01*
G01X79528Y863070D02*
X82677Y864252D01*
G01X79528Y873070D02*
X82677Y874252D01*
G01X79528Y878070D02*
X82677Y879252D01*
G01X79528Y883070D02*
X82677Y884252D01*
G01X79528Y888070D02*
X82677Y889252D01*
G01X79528Y893070D02*
X82677Y894252D01*
G01X77756Y893307D02*
X70866D01*
G01X38583Y893070D02*
X70866D01*
G01X79528D02*
X74803D01*
G01X70866Y892972D02*
X88110D01*
G01X40344D02*
X70866D01*
G01Y891397D02*
X88110D01*
G01X40344D02*
X70866D01*
G01X74803Y891299D02*
X79528D01*
G01X38583D02*
X70866D01*
G01X38583Y888070D02*
X70866D01*
G01X79528D02*
X74803D01*
G01X70866Y887972D02*
X88110D01*
G01X40344D02*
X70866D01*
G01Y886397D02*
X88110D01*
G01X40344D02*
X70866D01*
G01X74803Y886299D02*
X79528D01*
G01X38583D02*
X70866D01*
G01X38583Y883070D02*
X70866D01*
G01X79528D02*
X74803D01*
G01X70866Y882972D02*
X88110D01*
G01X40344D02*
X70866D01*
G01Y881397D02*
X88110D01*
G01X40344D02*
X70866D01*
G01X74803Y881299D02*
X79528D01*
G01X38583D02*
X70866D01*
G01X38583Y878070D02*
X70866D01*
G01X79528D02*
X74803D01*
G01X70866Y877972D02*
X88110D01*
G01X40344D02*
X70866D01*
G01Y876397D02*
X88110D01*
G01X40344D02*
X70866D01*
G01X74803Y876299D02*
X79528D01*
G01X38583D02*
X70866D01*
G01X38583Y873070D02*
X70866D01*
G01X79528D02*
X74803D01*
G01X70866Y872972D02*
X88110D01*
G01X40344D02*
X70866D01*
G01Y871397D02*
X88110D01*
G01X40344D02*
X70866D01*
G01X74803Y871299D02*
X79528D01*
G01X38583D02*
X70866D01*
G01Y871063D02*
X77756D01*
G01X70866Y869547D02*
X69685D01*
G01X77756Y868307D02*
X70866D01*
G01X38583Y868070D02*
X69685D01*
G01X77559D02*
X72835D01*
G01X69685Y867972D02*
X89567D01*
G01X40344D02*
X69685D01*
G01Y866397D02*
X89567D01*
G01X40344D02*
X69685D01*
G01X72835Y866299D02*
X77559D01*
G01X38583D02*
X69685D01*
G01Y864822D02*
X70866D01*
G01X38583Y863070D02*
X70866D01*
G01X79528D02*
X74803D01*
G01X70866Y862972D02*
X88110D01*
G01X40344D02*
X70866D01*
G01Y861397D02*
X88110D01*
G01X40344D02*
X70866D01*
G01X74803Y861299D02*
X79528D01*
G01X38583D02*
X70866D01*
G01X38583Y858070D02*
X70866D01*
G01X79528D02*
X74803D01*
G01X70866Y857972D02*
X88110D01*
G01X40344D02*
X70866D01*
G01Y856397D02*
X88110D01*
G01X40344D02*
X70866D01*
G01X74803Y856299D02*
X79528D01*
G01X38583D02*
X70866D01*
G01X35300Y843445D02*
X31890Y841476D01*
G01X38583Y853070D02*
X70866D01*
G01X79528D02*
X74803D01*
G01X70866Y852972D02*
X88110D01*
G01X40344D02*
X70866D01*
G01Y851397D02*
X88110D01*
G01X40344D02*
X70866D01*
G01X74803Y851299D02*
X79528D01*
G01X38583D02*
X70866D01*
G01X69587Y848366D02*
X70866D01*
G01X39764D02*
X68209D01*
G01X90551D02*
X70866D01*
G01Y846594D02*
X90551D01*
G01X40551Y843445D02*
X90551D01*
G01X35300D02*
X38583D01*
G01X75472Y843031D02*
X80827D01*
G01X80520Y842244D02*
X75780D01*
G01X80167Y841456D02*
X76133D01*
G01X70079Y840492D02*
X90551D01*
G01X59055D02*
X70079D01*
G01X80167Y838307D02*
X76133D01*
G01X75780Y837519D02*
X80520D01*
G01X80827Y836732D02*
X75472D01*
G01X70079Y836279D02*
X36614D01*
G01Y835098D02*
X90551D01*
G01X59055Y833130D02*
X78740D01*
G01X82677Y831161D02*
X94488D01*
G01X55118D02*
X27953D01*
G01X78740Y830039D02*
X59055D01*
G01Y829055D02*
X78740D01*
G01X59252Y828858D02*
X78543D01*
G01X59252Y827283D02*
X78543D01*
G01X78740Y827086D02*
X59055D01*
G01Y826102D02*
X78740D01*
G01X59055Y824114D02*
X78740D01*
G01X59055Y822145D02*
X78740D01*
G01X82677Y818208D02*
X55118D01*
G01X82677Y890118D02*
X79528Y891299D01*
G01X82677Y885118D02*
X79528Y886299D01*
G01X82677Y880118D02*
X79528Y881299D01*
G01X82677Y875118D02*
X79528Y876299D01*
G01X82677Y870118D02*
X79528Y871299D01*
G01X82677Y860118D02*
X79528Y861299D01*
G01X82677Y855118D02*
X79528Y856299D01*
G01X82677Y850118D02*
X79528Y851299D01*
G01X82677Y865118D02*
X77559Y866299D01*
G01X39764Y848366D02*
X38583Y847185D01*
G01X94488Y831161D02*
Y998208D01*
G01X90551Y835098D02*
Y848366D01*
G01X89567Y867972D02*
Y866397D01*
G01X88110Y852972D02*
Y851397D01*
G01Y857972D02*
Y856397D01*
G01Y862972D02*
Y861397D01*
G01Y872972D02*
Y871397D01*
G01Y877972D02*
Y876397D01*
G01Y882972D02*
Y881397D01*
G01Y887972D02*
Y886397D01*
G01Y892972D02*
Y891397D01*
G01X83189D02*
Y892972D01*
G01Y886397D02*
Y887972D01*
G01Y881397D02*
Y882972D01*
G01Y876397D02*
Y877972D01*
G01Y871397D02*
Y872972D01*
G01Y866397D02*
Y867972D01*
G01Y861397D02*
Y862972D01*
G01Y856397D02*
Y857972D01*
G01Y851397D02*
Y852972D01*
G01X82795D02*
Y851397D01*
G01Y857972D02*
Y856397D01*
G01Y862972D02*
Y861397D01*
G01Y867972D02*
Y866397D01*
G01Y872972D02*
Y871397D01*
G01Y877972D02*
Y876397D01*
G01Y882972D02*
Y881397D01*
G01Y887972D02*
Y886397D01*
G01Y892972D02*
Y891397D01*
G01X82677Y831161D02*
Y818208D01*
G01Y850118D02*
Y848366D01*
G01Y855118D02*
Y854252D01*
G01Y860118D02*
Y859252D01*
G01Y865118D02*
Y864252D01*
G01Y870118D02*
Y869252D01*
G01Y875118D02*
Y874252D01*
G01Y880118D02*
Y879252D01*
G01Y885118D02*
Y884252D01*
G01Y890118D02*
Y889252D01*
G01Y895118D02*
Y894252D01*
G01X82008Y852972D02*
Y851397D01*
G01Y857972D02*
Y856397D01*
G01Y862972D02*
Y861397D01*
G01Y867972D02*
Y866397D01*
G01Y872972D02*
Y871397D01*
G01Y877972D02*
Y876397D01*
G01Y882972D02*
Y881397D01*
G01Y887972D02*
Y886397D01*
G01Y892972D02*
Y891397D01*
G01X80433Y852972D02*
Y851397D01*
G01Y857972D02*
Y856397D01*
G01Y862972D02*
Y861397D01*
G01Y867972D02*
Y866397D01*
G01Y872972D02*
Y871397D01*
G01Y877972D02*
Y876397D01*
G01Y882972D02*
Y881397D01*
G01Y887972D02*
Y886397D01*
G01Y892972D02*
Y891397D01*
G01X78740Y822145D02*
Y835098D01*
G01X78543Y827283D02*
Y828858D01*
G01X77756Y893307D02*
Y896063D01*
G01Y868307D02*
Y871063D01*
G01X74803Y851397D02*
Y851299D01*
G01Y853070D02*
Y852972D01*
G01D02*
Y851397D01*
G01Y856397D02*
Y856299D01*
G01Y857972D02*
Y856397D01*
G01Y858070D02*
Y857972D01*
G01Y861397D02*
Y861299D01*
G01Y863070D02*
Y862972D01*
G01D02*
Y861397D01*
G01Y871397D02*
Y871299D01*
G01Y873070D02*
Y872972D01*
G01Y876397D02*
Y876299D01*
G01Y872972D02*
Y871397D01*
G01Y878070D02*
Y877972D01*
G01Y881397D02*
Y881299D01*
G01Y877972D02*
Y876397D01*
G01Y883070D02*
Y882972D01*
G01D02*
Y881397D01*
G01Y886397D02*
Y886299D01*
G01Y888070D02*
Y887972D01*
G01D02*
Y886397D01*
G01Y891397D02*
Y891299D01*
G01Y893070D02*
Y892972D01*
G01D02*
Y891397D01*
G01X73189Y828858D02*
Y827283D01*
G01X38583Y845413D02*
X40551Y843445D01*
G01X31890Y840847D02*
X36610Y836206D01*
G01X36614Y835098D02*
X31890Y839744D01*
G01X72835Y866397D02*
Y866299D01*
G01Y868070D02*
Y867972D01*
G01D02*
Y866397D01*
G01X71850Y828858D02*
Y829055D01*
G01Y827283D02*
Y827086D01*
G01Y828858D02*
Y827283D01*
G01X71654Y828858D02*
Y827283D01*
G01X70866Y866397D02*
Y867972D01*
G01D02*
Y906397D01*
G01Y846594D02*
Y866397D01*
G01X70079Y835098D02*
Y843445D01*
G01Y827283D02*
Y828858D01*
G01X69685Y869547D02*
Y864822D01*
G01X69587Y848366D02*
Y981004D01*
G01X68209D02*
Y848366D01*
G01X67717Y827283D02*
Y828858D01*
G01X66929Y848366D02*
Y981004D01*
G01X66142Y827283D02*
Y828858D01*
G01X65945Y827283D02*
Y828858D01*
G01Y829055D02*
Y828858D01*
G01Y827283D02*
Y827086D01*
G01X64606Y827283D02*
Y828858D01*
G01X59252D02*
Y827283D01*
G01X59055Y835098D02*
Y994271D01*
G01Y822145D02*
Y835098D01*
G01X55118Y818208D02*
Y831161D01*
G01X46553Y852972D02*
Y851397D01*
G01Y857972D02*
Y856397D01*
G01Y862972D02*
Y861397D01*
G01Y867972D02*
Y866397D01*
G01Y872972D02*
Y871397D01*
G01Y877972D02*
Y876397D01*
G01Y882972D02*
Y881397D01*
G01Y887972D02*
Y886397D01*
G01Y892972D02*
Y891397D01*
G01X45447Y852972D02*
Y851397D01*
G01Y857972D02*
Y856397D01*
G01Y862972D02*
Y861397D01*
G01Y867972D02*
Y866397D01*
G01Y872972D02*
Y871397D01*
G01Y877972D02*
Y876397D01*
G01Y882972D02*
Y881397D01*
G01Y887972D02*
Y886397D01*
G01Y892972D02*
Y891397D01*
G01X45201Y852972D02*
Y851397D01*
G01Y857972D02*
Y856397D01*
G01Y862972D02*
Y861397D01*
G01Y867972D02*
Y866397D01*
G01Y872972D02*
Y871397D01*
G01Y877972D02*
Y876397D01*
G01Y882972D02*
Y881397D01*
G01Y887972D02*
Y886397D01*
G01Y892972D02*
Y891397D01*
G01X41535Y853070D02*
Y851299D01*
G01Y858070D02*
Y856299D01*
G01Y863070D02*
Y861299D01*
G01Y868070D02*
Y866299D01*
G01Y873070D02*
Y871299D01*
G01Y878070D02*
Y876299D01*
G01Y883070D02*
Y881299D01*
G01Y888070D02*
Y886299D01*
G01Y893070D02*
Y891299D01*
G01X41026Y891397D02*
Y892972D01*
G01Y886397D02*
Y887972D01*
G01Y881397D02*
Y882972D01*
G01Y876397D02*
Y877972D01*
G01Y871397D02*
Y872972D01*
G01Y866397D02*
Y867972D01*
G01Y861397D02*
Y862972D01*
G01Y856397D02*
Y857972D01*
G01Y851397D02*
Y852972D01*
G01X40344D02*
Y851397D01*
G01Y857972D02*
Y856397D01*
G01Y862972D02*
Y861397D01*
G01Y867972D02*
Y866397D01*
G01Y872972D02*
Y871397D01*
G01Y877972D02*
Y876397D01*
G01Y882972D02*
Y881397D01*
G01Y887972D02*
Y886397D01*
G01Y892972D02*
Y891397D01*
G01X39764Y848366D02*
Y981004D01*
G01X38583Y843445D02*
Y985925D01*
G01X36614Y836279D02*
Y843445D01*
G01X31890Y839744D02*
Y841476D01*
G01X27953Y998208D02*
Y831161D01*
G01X77559Y908070D02*
X82677Y909252D01*
G01X78306Y945302D02*
X78440Y945334D01*
G01X86427Y977132D02*
X86527D01*
G01X86561Y976935D02*
X86393D01*
G01X85857Y976673D02*
X85589D01*
G01X86929Y976476D02*
X85622D01*
G01X70866Y976397D02*
X88110D01*
G01X40344D02*
X70866D01*
G01X74803Y976299D02*
X79528D01*
G01X38583D02*
X70866D01*
G01X85354Y976279D02*
X86929D01*
G01X38583Y973070D02*
X70866D01*
G01X79528D02*
X74803D01*
G01X70866Y972972D02*
X88110D01*
G01X40344D02*
X70866D01*
G01Y971397D02*
X88110D01*
G01X40344D02*
X70866D01*
G01X74803Y971299D02*
X79528D01*
G01X38583D02*
X70866D01*
G01X38583Y968070D02*
X70866D01*
G01X79528D02*
X74803D01*
G01X70866Y967972D02*
X88110D01*
G01X40344D02*
X70866D01*
G01Y966397D02*
X88110D01*
G01X40344D02*
X70866D01*
G01X74803Y966299D02*
X79528D01*
G01X38583D02*
X70866D01*
G01X38583Y963070D02*
X70866D01*
G01X79528D02*
X74803D01*
G01X70866Y962972D02*
X88110D01*
G01X40344D02*
X70866D01*
G01Y961397D02*
X88110D01*
G01X40344D02*
X70866D01*
G01X74803Y961299D02*
X79528D01*
G01X38583D02*
X70866D01*
G01X38583Y958070D02*
X70866D01*
G01X79528D02*
X74803D01*
G01X70866Y957972D02*
X88110D01*
G01X40344D02*
X70866D01*
G01Y956397D02*
X88110D01*
G01X40344D02*
X70866D01*
G01X74803Y956299D02*
X79528D01*
G01X38583D02*
X70866D01*
G01Y956063D02*
X77756D01*
G01Y953307D02*
X70866D01*
G01X38583Y953070D02*
X70866D01*
G01X79528D02*
X74803D01*
G01X70866Y952972D02*
X88110D01*
G01X40344D02*
X70866D01*
G01Y951397D02*
X88110D01*
G01X40344D02*
X70866D01*
G01X74803Y951299D02*
X79528D01*
G01X38583D02*
X70866D01*
G01X41535Y948070D02*
X70866D01*
G01X79528D02*
X74803D01*
G01X70866Y947972D02*
X88110D01*
G01X40465D02*
X70866D01*
G01X38583Y946889D02*
X70866D01*
G01Y946397D02*
X88110D01*
G01X40465D02*
X70866D01*
G01X74803Y946299D02*
X78937D01*
G01X41535D02*
X70866D01*
G01X78937Y945708D02*
X75591D01*
G01X78440Y945334D02*
X78574D01*
G01X78540Y945137D02*
X78473D01*
G01X38780Y944822D02*
X68110D01*
G01X38780D02*
X38583D01*
G01X73228D02*
X70866D01*
G01X68110Y944724D02*
X80118D01*
G01X42006D02*
X68110D01*
G01X40551Y944448D02*
X59055D01*
G01X79143Y944416D02*
X79244D01*
G01X79277Y944219D02*
X79110D01*
G01X79143Y943956D02*
X79244D01*
G01X78473Y943924D02*
X78574D01*
G01X79143Y943792D02*
X79244D01*
G01X78473Y943759D02*
X78540D01*
G01X68110Y943543D02*
X80118D01*
G01X68110D02*
X42006D01*
G01X38780Y943445D02*
X68110D01*
G01X38583D02*
X38780D01*
G01X73228D02*
X70866D01*
G01X78540Y942972D02*
X78473D01*
G01X79244Y942939D02*
X79143D01*
G01X78574Y942808D02*
X78473D01*
G01X79244Y942775D02*
X79143D01*
G01X38780Y941673D02*
X68110D01*
G01X38780D02*
X38583D01*
G01X73228D02*
X70866D01*
G01X68110Y941574D02*
X80118D01*
G01X42006D02*
X68110D01*
G01Y940393D02*
X80118D01*
G01X68110D02*
X42006D01*
G01X38780Y940295D02*
X68110D01*
G01X38583D02*
X38780D01*
G01X73228D02*
X70866D01*
G01X38780Y938523D02*
X68110D01*
G01X38780D02*
X38583D01*
G01X73228D02*
X70866D01*
G01X68110Y938425D02*
X80118D01*
G01X42006D02*
X68110D01*
G01Y937244D02*
X80118D01*
G01X68110D02*
X42006D01*
G01X38780Y937145D02*
X68110D01*
G01X38583D02*
X38780D01*
G01X73228D02*
X70866D01*
G01X38780Y935374D02*
X68110D01*
G01X38780D02*
X38583D01*
G01X73228D02*
X70866D01*
G01X68110Y935275D02*
X80118D01*
G01X42006D02*
X68110D01*
G01Y934094D02*
X80118D01*
G01X68110D02*
X42006D01*
G01X38780Y933996D02*
X68110D01*
G01X38583D02*
X38780D01*
G01X73228D02*
X70866D01*
G01X38780Y932224D02*
X68110D01*
G01X38780D02*
X38583D01*
G01X73228D02*
X70866D01*
G01X68110Y932126D02*
X80118D01*
G01X42006D02*
X68110D01*
G01Y930945D02*
X80118D01*
G01X68110D02*
X42006D01*
G01X38780Y930846D02*
X68110D01*
G01X38583D02*
X38780D01*
G01X73228D02*
X70866D01*
G01X73228Y925925D02*
X75591Y926614D01*
G01X73228Y929074D02*
X75591Y929763D01*
G01X73228Y932224D02*
X75591Y932913D01*
G01X85818Y921896D02*
X85918Y921929D01*
G01X85885Y922126D02*
X85784Y922093D01*
G01X79528Y898070D02*
X82677Y899252D01*
G01X38780Y929074D02*
X68110D01*
G01X38780D02*
X38583D01*
G01X73228D02*
X70866D01*
G01X68110Y928976D02*
X80118D01*
G01X42006D02*
X68110D01*
G01Y927795D02*
X80118D01*
G01X68110D02*
X42006D01*
G01X38780Y927696D02*
X68110D01*
G01X38583D02*
X38780D01*
G01X73228D02*
X70866D01*
G01X38780Y925925D02*
X38583D01*
G01X68110D02*
X38780D01*
G01X73228D02*
X70866D01*
G01X68110Y925826D02*
X80118D01*
G01X42006D02*
X68110D01*
G01X59055Y924921D02*
X40551D01*
G01X68110Y924645D02*
X80118D01*
G01X68110D02*
X42006D01*
G01X38583Y924547D02*
X38780D01*
G01X68110D02*
X38780D01*
G01X73228D02*
X70866D01*
G01X75591Y923661D02*
X78937D01*
G01X86890Y923110D02*
X85315D01*
G01X70866Y923070D02*
X41535D01*
G01X78937D02*
X74803D01*
G01X70866Y922972D02*
X89567D01*
G01X40465D02*
X70866D01*
G01X85483Y922913D02*
X85985D01*
G01X86186D02*
X86890D01*
G01X38583Y922480D02*
X70866D01*
G01X85784Y922093D02*
X85684D01*
G01Y921896D02*
X85818D01*
G01Y921633D02*
X85550D01*
G01X86890Y921437D02*
X85583D01*
G01X70866Y921397D02*
X89567D01*
G01X40465D02*
X70866D01*
G01X74803Y921299D02*
X79528D01*
G01X41535D02*
X70866D01*
G01X85315Y921240D02*
X86890D01*
G01X70866Y921063D02*
X77756D01*
G01Y918307D02*
X70866D01*
G01X38583Y918070D02*
X70866D01*
G01X79528D02*
X74803D01*
G01X70866Y917972D02*
X88110D01*
G01X40344D02*
X70866D01*
G01Y916397D02*
X88110D01*
G01X40344D02*
X70866D01*
G01X74803Y916299D02*
X79528D01*
G01X38583D02*
X70866D01*
G01X38583Y913070D02*
X70866D01*
G01X79528D02*
X74803D01*
G01X70866Y912972D02*
X88110D01*
G01X40344D02*
X70866D01*
G01Y911397D02*
X88110D01*
G01X40344D02*
X70866D01*
G01X74803Y911299D02*
X79528D01*
G01X38583D02*
X70866D01*
G01Y909547D02*
X69685D01*
G01X38583Y908070D02*
X69685D01*
G01X77559D02*
X72835D01*
G01X69685Y907972D02*
X89567D01*
G01X40344D02*
X69685D01*
G01Y906397D02*
X89567D01*
G01X40344D02*
X69685D01*
G01X72835Y906299D02*
X77559D01*
G01X38583D02*
X69685D01*
G01Y904822D02*
X70866D01*
G01X38583Y903070D02*
X70866D01*
G01X79528D02*
X74803D01*
G01X70866Y902972D02*
X88110D01*
G01X40344D02*
X70866D01*
G01Y901397D02*
X88110D01*
G01X40344D02*
X70866D01*
G01X74803Y901299D02*
X79528D01*
G01X38583D02*
X70866D01*
G01X38583Y898070D02*
X70866D01*
G01X79528D02*
X74803D01*
G01X70866Y897972D02*
X88110D01*
G01X40344D02*
X70866D01*
G01Y896397D02*
X88110D01*
G01X40344D02*
X70866D01*
G01X74803Y896299D02*
X79528D01*
G01X38583D02*
X70866D01*
G01Y896063D02*
X77756D01*
G01X73228Y935374D02*
X75591Y936063D01*
G01X73228Y938523D02*
X75591Y939212D01*
G01X73228Y941673D02*
X75591Y942362D01*
G01X73228Y944822D02*
X75591Y945511D01*
G01X78473Y945137D02*
X78372Y945105D01*
G01X79528Y903070D02*
X82677Y904252D01*
G01X79528Y913070D02*
X82677Y914252D01*
G01X79528Y918070D02*
X82677Y919252D01*
G01X79528Y948070D02*
X82677Y949252D01*
G01X79528Y953070D02*
X82677Y954252D01*
G01X79528Y958070D02*
X82677Y959252D01*
G01X79528Y963070D02*
X82677Y964252D01*
G01X79528Y968070D02*
X82677Y969252D01*
G01X79528Y973070D02*
X82677Y974252D01*
G01X79411Y942841D02*
X79244Y942775D01*
G01X78976Y943891D02*
X79143Y943956D01*
G01X78306Y943858D02*
X78473Y943924D01*
G01X86393Y976935D02*
X86259Y977001D01*
G01X85656Y977263D02*
X85723Y977231D01*
G01X79244Y943956D02*
X79411Y943891D01*
G01X79143Y942775D02*
X78976Y942841D01*
G01X78473Y942808D02*
X78306Y942874D01*
G01X82677Y975118D02*
X79528Y976299D01*
G01X82677Y970118D02*
X79528Y971299D01*
G01X82677Y965118D02*
X79528Y966299D01*
G01X82677Y960118D02*
X79528Y961299D01*
G01X82677Y955118D02*
X79528Y956299D01*
G01X82677Y950118D02*
X79528Y951299D01*
G01X85723Y977034D02*
X85622Y977067D01*
G01X79311Y945203D02*
X79210Y945236D01*
G01X78641Y945105D02*
X78540Y945137D01*
G01X78440Y944317D02*
X78339Y944350D01*
G01X85684Y922093D02*
X85583Y922126D01*
G01Y921929D02*
X85684Y921896D01*
G01X75591Y942756D02*
X73228Y943445D01*
G01X75591Y939606D02*
X73228Y940295D01*
G01X75591Y936456D02*
X73228Y937145D01*
G01X75591Y933307D02*
X73228Y933996D01*
G01X75591Y930157D02*
X73228Y930846D01*
G01X75591Y927008D02*
X73228Y927696D01*
G01X75591Y923858D02*
X73228Y924547D01*
G01X79210Y945433D02*
X79344Y945400D01*
G01X78574Y945334D02*
X78708Y945302D01*
G01X82677Y905118D02*
X77559Y906299D01*
G01X78708Y942874D02*
X78574Y942808D01*
G01X79411Y944284D02*
X79277Y944219D01*
G01X86695Y977001D02*
X86561Y976935D01*
G01X78641Y943038D02*
X78540Y942972D01*
G01X78372Y943694D02*
X78473Y943759D01*
G01X79244Y944416D02*
X79344Y944481D01*
G01X85918Y921929D02*
X86052Y922027D01*
G01X79378Y943038D02*
X79244Y942939D01*
G01X85622Y977067D02*
X85489Y977165D01*
G01X86326Y977198D02*
X86427Y977132D01*
G01X79043Y944481D02*
X79143Y944416D01*
G01X78540Y943759D02*
X78641Y943694D01*
G01X78473Y942972D02*
X78372Y943038D01*
G01X79344Y945400D02*
X79512Y945302D01*
G01X79110Y944219D02*
X78976Y944284D01*
G01X78372Y944547D02*
X78440Y944514D01*
G01X78574Y943924D02*
X78708Y943858D01*
G01X82677Y920118D02*
X79528Y921299D01*
G01X82677Y915118D02*
X79528Y916299D01*
G01X82677Y910118D02*
X79528Y911299D01*
G01X82677Y900118D02*
X79528Y901299D01*
G01X82677Y895118D02*
X79528Y896299D01*
G01X86527Y977132D02*
X86628Y977198D01*
G01X79009Y943694D02*
X79143Y943792D01*
G01X85583Y921437D02*
X85818Y921633D01*
G01X85550D02*
X85315Y921437D01*
G01X85622Y976476D02*
X85857Y976673D01*
G01X85589D02*
X85354Y976476D01*
G01X85952Y922191D02*
X85885Y922126D01*
G01X79512Y942939D02*
X79411Y942841D01*
G01X78808Y942972D02*
X78708Y942874D01*
G01X79545Y944416D02*
X79411Y944284D01*
G01X78205Y943759D02*
X78306Y943858D01*
G01X78172Y945170D02*
X78306Y945302D01*
G01X86829Y977132D02*
X86695Y977001D01*
G01X40551Y924921D02*
X38583Y922952D01*
G01X86259Y977296D02*
X86326Y977198D01*
G01X85489Y977165D02*
X85388Y977296D01*
G01X86259Y977001D02*
X86125Y977132D01*
G01X79411Y945105D02*
X79311Y945203D01*
G01X78708Y945302D02*
X78842Y945170D01*
G01X79411Y943891D02*
X79512Y943792D01*
G01X78976Y944284D02*
X78842Y944416D01*
G01X78306Y944613D02*
X78372Y944547D01*
G01X78708Y943858D02*
X78808Y943759D01*
G01X78306Y942874D02*
X78205Y942972D01*
G01X85583Y922126D02*
X85516Y922191D01*
G01X79244Y943792D02*
X79378Y943694D01*
G01X78339Y944350D02*
X78205Y944448D01*
G01X79143Y942939D02*
X79009Y943038D01*
G01X85449Y922027D02*
X85583Y921929D01*
G01X86052Y922027D02*
X86153Y922158D01*
G01X78741Y943169D02*
X78641Y943038D01*
G01X78875Y943759D02*
X78976Y943891D01*
G01X78272Y943563D02*
X78372Y943694D01*
G01X79344Y944481D02*
X79411Y944580D01*
G01X78372Y945105D02*
X78306Y945006D01*
G01X86628Y977198D02*
X86695Y977296D01*
G01X79612Y943103D02*
X79512Y942939D01*
G01X78104Y943595D02*
X78205Y943759D01*
G01X79445Y943169D02*
X79378Y943038D01*
G01X78842D02*
X78808Y942972D01*
G01X79612Y944547D02*
X79545Y944416D01*
G01X78942Y943563D02*
X79009Y943694D01*
G01X78842D02*
X78875Y943759D01*
G01X78104Y945039D02*
X78172Y945170D01*
G01X85315Y922322D02*
X85348Y922158D01*
G01X79612Y945137D02*
X79646Y944973D01*
G01X79630Y943543D02*
X79646Y943464D01*
G01X79612Y943628D02*
X79630Y943543D01*
G01X78775Y944547D02*
X78741Y944711D01*
G01X78075Y944724D02*
X78071Y944744D01*
G01X78104Y944580D02*
X78075Y944724D01*
G01X78104Y943136D02*
X78071Y943300D01*
G01X79445Y944973D02*
X79411Y945105D01*
G01X79450Y943543D02*
X79478Y943432D01*
G01X79445Y943563D02*
X79450Y943543D01*
G01X78909Y945039D02*
X78942Y944908D01*
G01Y944711D02*
X78976Y944580D01*
G01X78942Y943169D02*
X78909Y943300D01*
G01X78746Y943543D02*
X78775Y943432D01*
G01X78741Y943563D02*
X78746Y943543D01*
G01X78272Y943169D02*
X78239Y943300D01*
G01X78741Y944908D02*
X78708Y945006D01*
G01X78272Y944711D02*
X78306Y944613D01*
G01X85516Y922191D02*
X85483Y922290D01*
G01X86125Y977132D02*
X86058Y977263D01*
G01X78842Y945170D02*
X78909Y945039D01*
G01X79378Y943694D02*
X79445Y943563D01*
G01X78842Y944416D02*
X78775Y944547D01*
G01X78808Y943759D02*
X78842Y943694D01*
G01X79009Y943038D02*
X78942Y943169D01*
G01X78875Y942972D02*
X78842Y943038D01*
G01X79512Y945302D02*
X79612Y945137D01*
G01X79512Y943792D02*
X79612Y943628D01*
G01X78205Y942972D02*
X78104Y943136D01*
G01X78708Y945006D02*
X78641Y945105D01*
G01X78976Y944580D02*
X79043Y944481D01*
G01X78205Y944448D02*
X78104Y944580D01*
G01X78641Y943694D02*
X78741Y943563D01*
G01X78976Y942841D02*
X78875Y942972D01*
G01X78372Y943038D02*
X78272Y943169D01*
G01X85348Y922158D02*
X85449Y922027D01*
G01X40551Y944448D02*
X38583Y946417D01*
G01X86896Y977263D02*
X86829Y977132D01*
G01X85985Y922290D02*
X85952Y922191D01*
G01X78306Y945006D02*
X78272Y944908D01*
G01X79478Y943300D02*
X79445Y943169D01*
G01X79411Y944580D02*
X79445Y944711D01*
G01X78909Y943432D02*
X78937Y943543D01*
G01D02*
X78942Y943563D01*
G01X78775Y943300D02*
X78741Y943169D01*
G01X78239Y943432D02*
X78267Y943543D01*
G01D02*
X78272Y943563D01*
G01X78071Y944908D02*
X78104Y945039D01*
G01X86153Y922158D02*
X86186Y922322D01*
G01X79646Y943267D02*
X79612Y943103D01*
G01X79646Y944711D02*
X79612Y944547D01*
G01X78071Y943432D02*
X78094Y943543D01*
G01D02*
X78104Y943595D01*
G01X89567Y907972D02*
Y906397D01*
G01Y922972D02*
Y921397D01*
G01X88110Y897972D02*
Y896397D01*
G01Y902972D02*
Y901397D01*
G01Y912972D02*
Y911397D01*
G01Y917972D02*
Y916397D01*
G01Y947972D02*
Y946397D01*
G01Y952972D02*
Y951397D01*
G01Y957972D02*
Y956397D01*
G01Y962972D02*
Y961397D01*
G01Y967972D02*
Y966397D01*
G01Y972972D02*
Y971397D01*
G01Y977972D02*
Y976397D01*
G01X86929Y976279D02*
Y976397D01*
G01D02*
Y976476D01*
G01X86890Y921240D02*
Y921397D01*
G01Y922972D02*
Y923110D01*
G01Y921397D02*
Y921437D01*
G01Y922913D02*
Y922972D01*
G01X86186Y922322D02*
Y922913D01*
G01X85985D02*
Y922290D01*
G01X85723Y977231D02*
Y977034D01*
G01X85483Y922290D02*
Y922913D01*
G01X85354Y976397D02*
Y976279D01*
G01Y976476D02*
Y976397D01*
G01X85315Y921397D02*
Y921240D01*
G01Y923110D02*
Y922972D01*
G01Y921437D02*
Y921397D01*
G01Y922972D02*
Y922322D01*
G01X83189Y976397D02*
Y977972D01*
G01Y971397D02*
Y972972D01*
G01Y966397D02*
Y967972D01*
G01Y961397D02*
Y962972D01*
G01Y956397D02*
Y957972D01*
G01Y951397D02*
Y952972D01*
G01Y946397D02*
Y947972D01*
G01Y921397D02*
Y922972D01*
G01Y916397D02*
Y917972D01*
G01Y911397D02*
Y912972D01*
G01Y906397D02*
Y907972D01*
G01Y901397D02*
Y902972D01*
G01Y896397D02*
Y897972D01*
G01X82795D02*
Y896397D01*
G01Y902972D02*
Y901397D01*
G01Y907972D02*
Y906397D01*
G01Y912972D02*
Y911397D01*
G01Y917972D02*
Y916397D01*
G01Y922972D02*
Y921397D01*
G01Y947972D02*
Y946397D01*
G01Y952972D02*
Y951397D01*
G01Y957972D02*
Y956397D01*
G01Y962972D02*
Y961397D01*
G01Y967972D02*
Y966397D01*
G01Y972972D02*
Y971397D01*
G01Y977972D02*
Y976397D01*
G01X82677Y900118D02*
Y899252D01*
G01Y905118D02*
Y904252D01*
G01Y910118D02*
Y909252D01*
G01Y915118D02*
Y914252D01*
G01Y920118D02*
Y919252D01*
G01Y950118D02*
Y949252D01*
G01Y955118D02*
Y954252D01*
G01Y960118D02*
Y959252D01*
G01Y965118D02*
Y964252D01*
G01Y970118D02*
Y969252D01*
G01Y975118D02*
Y974252D01*
G01X82008Y897972D02*
Y896397D01*
G01Y902972D02*
Y901397D01*
G01Y907972D02*
Y906397D01*
G01Y912972D02*
Y911397D01*
G01Y917972D02*
Y916397D01*
G01Y922972D02*
Y921397D01*
G01Y947972D02*
Y946397D01*
G01Y952972D02*
Y951397D01*
G01Y957972D02*
Y956397D01*
G01Y962972D02*
Y961397D01*
G01Y967972D02*
Y966397D01*
G01Y972972D02*
Y971397D01*
G01Y977972D02*
Y976397D01*
G01X80433Y897972D02*
Y896397D01*
G01Y902972D02*
Y901397D01*
G01Y907972D02*
Y906397D01*
G01Y912972D02*
Y911397D01*
G01Y917972D02*
Y916397D01*
G01Y922972D02*
Y921397D01*
G01Y947972D02*
Y946397D01*
G01Y952972D02*
Y951397D01*
G01Y957972D02*
Y956397D01*
G01Y962972D02*
Y961397D01*
G01Y967972D02*
Y966397D01*
G01Y972972D02*
Y971397D01*
G01Y977972D02*
Y976397D01*
G01X80118Y925826D02*
Y924645D01*
G01Y932126D02*
Y930945D01*
G01Y928976D02*
Y927795D01*
G01Y935275D02*
Y934094D01*
G01Y941574D02*
Y940393D01*
G01Y938425D02*
Y937244D01*
G01Y944724D02*
Y943543D01*
G01X79646Y944973D02*
Y944724D01*
G01Y943464D02*
Y943267D01*
G01Y944724D02*
Y944711D01*
G01X79478Y943432D02*
Y943300D01*
G01X79445Y944724D02*
Y944973D01*
G01Y944711D02*
Y944724D01*
G01X79210Y945236D02*
Y945433D01*
G01X78942Y944908D02*
Y944724D01*
G01D02*
Y944711D01*
G01X78937Y923661D02*
Y923070D01*
G01Y946299D02*
Y945708D01*
G01X78909Y943300D02*
Y943432D01*
G01X78775D02*
Y943300D01*
G01X78741Y944724D02*
Y944908D01*
G01Y944711D02*
Y944724D01*
G01X78440Y944514D02*
Y944317D01*
G01X78272Y944908D02*
Y944724D01*
G01D02*
Y944711D01*
G01X78239Y943300D02*
Y943432D01*
G01X78071Y944744D02*
Y944908D01*
G01Y943300D02*
Y943432D01*
G01X77756Y953307D02*
Y956063D01*
G01Y918307D02*
Y921063D01*
G01X75591Y923858D02*
Y923661D01*
G01Y927008D02*
Y926614D01*
G01Y930157D02*
Y929763D01*
G01Y936456D02*
Y936063D01*
G01Y933307D02*
Y932913D01*
G01Y939606D02*
Y939212D01*
G01Y945708D02*
Y945511D01*
G01Y942756D02*
Y942362D01*
G01X75512Y943543D02*
Y944724D01*
G01Y940393D02*
Y941574D01*
G01Y937244D02*
Y938425D01*
G01Y934094D02*
Y935275D01*
G01Y927795D02*
Y928976D01*
G01Y930945D02*
Y932126D01*
G01Y924645D02*
Y925826D01*
G01X75118D02*
Y924645D01*
G01Y932126D02*
Y930945D01*
G01Y928976D02*
Y927795D01*
G01Y935275D02*
Y934094D01*
G01Y941574D02*
Y940393D01*
G01Y938425D02*
Y937244D01*
G01Y944724D02*
Y943543D01*
G01X74803Y896397D02*
Y896299D01*
G01Y898070D02*
Y897972D01*
G01D02*
Y896397D01*
G01Y901397D02*
Y901299D01*
G01Y903070D02*
Y902972D01*
G01D02*
Y901397D01*
G01Y911397D02*
Y911299D01*
G01Y913070D02*
Y912972D01*
G01D02*
Y911397D01*
G01Y916397D02*
Y916299D01*
G01Y918070D02*
Y917972D01*
G01D02*
Y916397D01*
G01Y921397D02*
Y921299D01*
G01Y923070D02*
Y922972D01*
G01D02*
Y921397D01*
G01Y946397D02*
Y946299D01*
G01Y948070D02*
Y947972D01*
G01Y951397D02*
Y951299D01*
G01Y947972D02*
Y946397D01*
G01Y953070D02*
Y952972D01*
G01D02*
Y951397D01*
G01Y956397D02*
Y956299D01*
G01Y958070D02*
Y957972D01*
G01D02*
Y956397D01*
G01Y961397D02*
Y961299D01*
G01Y963070D02*
Y962972D01*
G01D02*
Y961397D01*
G01Y966397D02*
Y966299D01*
G01Y968070D02*
Y967972D01*
G01D02*
Y966397D01*
G01Y971397D02*
Y971299D01*
G01Y973070D02*
Y972972D01*
G01D02*
Y971397D01*
G01Y976397D02*
Y976299D01*
G01Y977972D02*
Y976397D01*
G01X74331Y925826D02*
Y924645D01*
G01Y928976D02*
Y927795D01*
G01Y932126D02*
Y930945D01*
G01Y935275D02*
Y934094D01*
G01Y938425D02*
Y937244D01*
G01Y941574D02*
Y940393D01*
G01Y944724D02*
Y943543D01*
G01X72835Y906397D02*
Y906299D01*
G01Y908070D02*
Y907972D01*
G01D02*
Y906397D01*
G01X72756Y925826D02*
Y924645D01*
G01Y928976D02*
Y927795D01*
G01Y932126D02*
Y930945D01*
G01Y935275D02*
Y934094D01*
G01Y941574D02*
Y940393D01*
G01Y938425D02*
Y937244D01*
G01Y944724D02*
Y943543D01*
G01X70866Y944724D02*
Y982775D01*
G01Y941574D02*
Y943543D01*
G01D02*
Y944724D01*
G01Y938425D02*
Y940393D01*
G01D02*
Y941574D01*
G01Y937244D02*
Y938425D01*
G01Y935275D02*
Y937244D01*
G01Y932126D02*
Y934094D01*
G01D02*
Y935275D01*
G01Y928976D02*
Y930945D01*
G01D02*
Y932126D01*
G01Y927795D02*
Y928976D01*
G01Y906397D02*
Y907972D01*
G01Y925826D02*
Y927795D01*
G01Y907972D02*
Y924645D01*
G01D02*
Y925826D01*
G01X69685Y909547D02*
Y904822D01*
G01X68110Y946889D02*
Y922480D01*
G01X51039Y925826D02*
Y924645D01*
G01Y928976D02*
Y927795D01*
G01Y932126D02*
Y930945D01*
G01Y935275D02*
Y934094D01*
G01Y938425D02*
Y937244D01*
G01Y941574D02*
Y940393D01*
G01Y944724D02*
Y943543D01*
G01X48800Y925826D02*
Y924645D01*
G01Y928976D02*
Y927795D01*
G01Y932126D02*
Y930945D01*
G01Y935275D02*
Y934094D01*
G01Y938425D02*
Y937244D01*
G01Y941574D02*
Y940393D01*
G01Y944724D02*
Y943543D01*
G01X48302D02*
Y944724D01*
G01Y940393D02*
Y941574D01*
G01Y937244D02*
Y938425D01*
G01Y934094D02*
Y935275D01*
G01Y927795D02*
Y928976D01*
G01Y930945D02*
Y932126D01*
G01Y924645D02*
Y925826D01*
G01X47559Y943445D02*
Y944822D01*
G01Y924547D02*
Y925925D01*
G01Y932224D02*
Y930846D01*
G01Y929074D02*
Y927696D01*
G01Y935374D02*
Y933996D01*
G01Y941673D02*
Y940295D01*
G01Y938523D02*
Y937145D01*
G01X46553Y897972D02*
Y896397D01*
G01Y902972D02*
Y901397D01*
G01Y907972D02*
Y906397D01*
G01Y912972D02*
Y911397D01*
G01Y917972D02*
Y916397D01*
G01Y922972D02*
Y921397D01*
G01Y947972D02*
Y946397D01*
G01Y952972D02*
Y951397D01*
G01Y957972D02*
Y956397D01*
G01Y962972D02*
Y961397D01*
G01Y967972D02*
Y966397D01*
G01Y972972D02*
Y971397D01*
G01Y977972D02*
Y976397D01*
G01X45447Y897972D02*
Y896397D01*
G01Y902972D02*
Y901397D01*
G01Y907972D02*
Y906397D01*
G01Y912972D02*
Y911397D01*
G01Y917972D02*
Y916397D01*
G01Y922972D02*
Y921397D01*
G01Y947972D02*
Y946397D01*
G01Y952972D02*
Y951397D01*
G01Y957972D02*
Y956397D01*
G01Y962972D02*
Y961397D01*
G01Y967972D02*
Y966397D01*
G01Y972972D02*
Y971397D01*
G01Y977972D02*
Y976397D01*
G01X45201Y946397D02*
Y947972D01*
G01Y921397D02*
Y922972D01*
G01Y897972D02*
Y896397D01*
G01Y902972D02*
Y901397D01*
G01Y907972D02*
Y906397D01*
G01Y912972D02*
Y911397D01*
G01Y917972D02*
Y916397D01*
G01Y952972D02*
Y951397D01*
G01Y957972D02*
Y956397D01*
G01Y962972D02*
Y961397D01*
G01Y967972D02*
Y966397D01*
G01Y972972D02*
Y971397D01*
G01Y977972D02*
Y976397D01*
G01X42744Y925826D02*
Y924645D01*
G01Y932126D02*
Y930945D01*
G01Y928976D02*
Y927795D01*
G01Y935275D02*
Y934094D01*
G01Y941574D02*
Y940393D01*
G01Y938425D02*
Y937244D01*
G01Y944724D02*
Y943543D01*
G01X42006D02*
Y944724D01*
G01Y940393D02*
Y941574D01*
G01Y937244D02*
Y938425D01*
G01Y934094D02*
Y935275D01*
G01Y930945D02*
Y932126D01*
G01Y927795D02*
Y928976D01*
G01Y924645D02*
Y925826D01*
G01X41535Y898070D02*
Y896299D01*
G01Y903070D02*
Y901299D01*
G01Y908070D02*
Y906299D01*
G01Y913070D02*
Y911299D01*
G01Y918070D02*
Y916299D01*
G01Y923070D02*
Y921299D01*
G01Y948070D02*
Y946299D01*
G01Y953070D02*
Y951299D01*
G01Y958070D02*
Y956299D01*
G01Y963070D02*
Y961299D01*
G01Y968070D02*
Y966299D01*
G01Y973070D02*
Y971299D01*
G01Y978070D02*
Y976299D01*
G01X41454Y946397D02*
Y947972D01*
G01Y921397D02*
Y922972D01*
G01X41026Y976397D02*
Y977972D01*
G01Y971397D02*
Y972972D01*
G01Y966397D02*
Y967972D01*
G01Y961397D02*
Y962972D01*
G01Y956397D02*
Y957972D01*
G01Y951397D02*
Y952972D01*
G01Y916397D02*
Y917972D01*
G01Y911397D02*
Y912972D01*
G01Y906397D02*
Y907972D01*
G01Y901397D02*
Y902972D01*
G01Y896397D02*
Y897972D01*
G01X40551Y922480D02*
Y946889D01*
G01X40465Y922972D02*
Y921397D01*
G01Y947972D02*
Y946397D01*
G01X40344Y897972D02*
Y896397D01*
G01Y902972D02*
Y901397D01*
G01Y907972D02*
Y906397D01*
G01Y912972D02*
Y911397D01*
G01Y917972D02*
Y916397D01*
G01Y952972D02*
Y951397D01*
G01Y957972D02*
Y956397D01*
G01Y962972D02*
Y961397D01*
G01Y967972D02*
Y966397D01*
G01Y972972D02*
Y971397D01*
G01Y977972D02*
Y976397D01*
G01X38780Y943445D02*
Y944822D01*
G01Y937145D02*
Y938523D01*
G01Y940295D02*
Y941673D01*
G01Y933996D02*
Y935374D01*
G01Y927696D02*
Y929074D01*
G01Y930846D02*
Y932224D01*
G01Y925925D02*
Y924547D01*
G01X45275Y1029528D02*
G03I-15748J0D01*
G01X36515D02*
G03I-6988J0D01*
G01X64172Y1021319D02*
Y1019350D01*
G01Y1016791D02*
Y1018760D01*
G01X65664Y1017777D02*
Y1017904D01*
G01X65747Y1021614D02*
Y1021024D01*
G01Y1019843D02*
Y1018268D01*
G01Y1017087D02*
Y1016496D01*
G01X65758Y1017268D02*
Y1017889D01*
G01X65851Y1018016D02*
Y1017268D01*
G01X66731Y1016496D02*
Y1021614D01*
G01X66928D02*
Y1016496D01*
G01X67322Y1018760D02*
Y1016791D01*
G01Y1019350D02*
Y1021319D01*
G01X65664Y1017904D02*
X65758Y1018016D01*
G01Y1017889D02*
X65664Y1017777D01*
G01X65747Y1016496D02*
X72046D01*
G01X67322Y1016791D02*
X65747D01*
G01D02*
X64172D01*
G01X65851Y1017268D02*
X65758D01*
G01Y1018016D02*
X65851D01*
G01X65747Y1018760D02*
X67322D01*
G01X64172D02*
X65747D01*
G01Y1019350D02*
X67322D01*
G01X64172D02*
X65747D01*
G01X67322Y1021319D02*
X65747D01*
G01D02*
X64172D01*
G01X65747Y1021614D02*
X72046D01*
G01X65747Y1019843D02*
G03Y1021024I0J590D01*
G01Y1017087D02*
G03Y1018268I0J590D01*
G01X70471Y1018760D02*
Y1016791D01*
G01Y1019350D02*
Y1021319D01*
G01X70865Y1021614D02*
Y1016496D01*
G01X71062D02*
Y1021614D01*
G01X72046Y1016496D02*
Y1017087D01*
G01Y1021024D02*
Y1021614D01*
G01Y1018268D02*
Y1019843D01*
G01X73621Y1021319D02*
Y1019350D01*
G01Y1016791D02*
Y1018760D01*
G01X70471Y1016791D02*
X72046D01*
G01D02*
X73621D01*
G01X72046Y1018760D02*
X70471D01*
G01X73621D02*
X72046D01*
G01Y1019350D02*
X70471D01*
G01X73621D02*
X72046D01*
G01X70471Y1021319D02*
X72046D01*
G01D02*
X73621D01*
G01X72046Y1021024D02*
G03Y1019843I0J-591D01*
G01Y1018268D02*
G03Y1017087I0J-591D01*
G01X78224Y985354D02*
X78150D01*
G01X78075Y993621D02*
X78150Y993622D01*
G01X72638Y1001299D02*
G03I-3740J0D01*
G01X80709Y989488D02*
G03I-2559J0D01*
G01X81496D02*
G03I-3346J0D01*
G01X81654D02*
G03I-3504J0D01*
G01X78075Y993621D02*
G03X78150Y985354I74J-4133D01*
G01X78224Y985355D02*
G03X78150Y993622I-73J4133D01*
G01X55118Y1011161D02*
X82677D01*
G01X78740Y1007224D02*
X59055D01*
G01X85589Y978018D02*
X85723Y978051D01*
G01X78740Y1005256D02*
X59055D01*
G01X78740Y1003267D02*
X59055D01*
G01Y1002283D02*
X78740D01*
G01X59252Y1002086D02*
X78543D01*
G01X59252Y1000511D02*
X78543D01*
G01X78740Y1000315D02*
X59055D01*
G01Y999330D02*
X78740D01*
G01X27953Y998208D02*
X55118D01*
G01X94488D02*
X82677D01*
G01X78740Y996240D02*
X59055D01*
G01X36614Y994271D02*
X90551D01*
G01X36614Y993090D02*
X70079D01*
G01Y988878D02*
X59055D01*
G01X90551D02*
X70079D01*
G01X35300Y985925D02*
X38583D01*
G01X90551D02*
X40551D01*
G01X90551Y982775D02*
X70866D01*
G01Y981004D02*
X90551D01*
G01X69587D02*
X70866D01*
G01X68209D02*
X39764D01*
G01X38583Y978070D02*
X70866D01*
G01X79528D02*
X74803D01*
G01X85723Y978051D02*
X85857D01*
G01X70866Y977972D02*
X88110D01*
G01X40344D02*
X70866D01*
G01X85824Y977854D02*
X85757D01*
G01X86494Y978149D02*
X86628Y978117D01*
G01X85857Y978051D02*
X85991Y978018D01*
G01X85757Y977854D02*
X85656Y977821D01*
G01X79528Y978070D02*
X82677Y979252D01*
G01X86594Y977920D02*
X86494Y977952D01*
G01X85924Y977821D02*
X85824Y977854D01*
G01X86628Y978117D02*
X86795Y978018D01*
G01X31890Y987893D02*
X35300Y985925D01*
G01X85542Y977972D02*
X85589Y978018D01*
G01X85455Y977887D02*
X85542Y977972D01*
G01X85991Y977723D02*
X85924Y977821D01*
G01X39764Y981004D02*
X38583Y982185D01*
G01X86695Y977821D02*
X86594Y977920D01*
G01X85991Y978018D02*
X86038Y977972D01*
G01D02*
X86125Y977887D01*
G01X85589Y977329D02*
X85656Y977263D01*
G01X36610Y993164D02*
X31890Y988522D01*
G01Y989626D02*
X36614Y994271D01*
G01X40551Y985925D02*
X38583Y983956D01*
G01X85656Y977821D02*
X85589Y977723D01*
G01X86896Y977854D02*
X86929Y977690D01*
G01X86058Y977263D02*
X86024Y977428D01*
G01X85388Y977296D02*
X85354Y977460D01*
G01X86728Y977690D02*
X86695Y977821D01*
G01X86192Y977756D02*
X86226Y977624D01*
G01Y977428D02*
X86259Y977296D01*
G01X86024Y977624D02*
X85991Y977723D01*
G01X85556Y977428D02*
X85589Y977329D01*
G01X86125Y977887D02*
X86192Y977756D01*
G01X86795Y978018D02*
X86823Y977972D01*
G01D02*
X86896Y977854D01*
G01X85388Y977756D02*
X85455Y977887D01*
G01X85589Y977723D02*
X85556Y977624D01*
G01X86695Y977296D02*
X86728Y977428D01*
G01X85354Y977624D02*
X85388Y977756D01*
G01X86929Y977428D02*
X86896Y977263D01*
G01X90551Y981004D02*
Y994271D01*
G01X86929Y977690D02*
Y977428D01*
G01X86728D02*
Y977690D01*
G01X86494Y977972D02*
Y978149D01*
G01Y977952D02*
Y977972D01*
G01X86226Y977624D02*
Y977428D01*
G01X86024D02*
Y977624D01*
G01X85556D02*
Y977428D01*
G01X85354Y977460D02*
Y977624D01*
G01X82677Y981004D02*
Y979252D01*
G01Y1011161D02*
Y998208D01*
G01X78740Y994271D02*
Y1007224D01*
G01X78543Y1000511D02*
Y1002086D01*
G01X74803Y978070D02*
Y977972D01*
G01X73189Y1002086D02*
Y1000511D01*
G01X71850Y1002086D02*
Y1002283D01*
G01Y1000511D02*
Y1000315D01*
G01Y1002086D02*
Y1000511D01*
G01X71654Y1002086D02*
Y1000511D01*
G01X70079D02*
Y1002086D01*
G01Y994271D02*
Y985925D01*
G01X67717Y1000511D02*
Y1002086D01*
G01X66142Y1000511D02*
Y1002086D01*
G01X65945Y1000511D02*
Y1002086D01*
G01Y1000511D02*
Y1000315D01*
G01Y1002283D02*
Y1002086D01*
G01X64606Y1000511D02*
Y1002086D01*
G01X59252D02*
Y1000511D01*
G01X59055Y994271D02*
Y1007224D01*
G01X55118Y998208D02*
Y1011161D01*
G01X36614Y985925D02*
Y993090D01*
G01X31890Y987893D02*
Y989626D01*
G01X22851Y1150796D02*
Y1125205D01*
G01X24802Y1150796D02*
Y1125205D01*
G01X26771Y1264181D02*
Y1123237D01*
G01X12829Y1155524D02*
Y1156863D01*
G01Y1159461D02*
Y1160800D01*
G01Y1163398D02*
Y1164737D01*
G01Y1167335D02*
Y1168674D01*
G01X13613D02*
Y1167335D01*
G01Y1164737D02*
Y1163398D01*
G01Y1160800D02*
Y1159461D01*
G01Y1156863D02*
Y1155524D01*
G01X15464Y1168477D02*
Y1167532D01*
G01Y1164540D02*
Y1163595D01*
G01Y1160603D02*
Y1159658D01*
G01Y1156666D02*
Y1155721D01*
G01X16248D02*
Y1156666D01*
G01Y1159658D02*
Y1160603D01*
G01Y1163595D02*
Y1164540D01*
G01Y1167532D02*
Y1168477D01*
G01X14688Y1156863D02*
X15464Y1156666D01*
G01X16248D02*
X15472Y1156863D01*
G01X14688Y1160800D02*
X15464Y1160603D01*
G01X16248D02*
X15472Y1160800D01*
G01X14688Y1164737D02*
X15464Y1164540D01*
G01X16248D02*
X15472Y1164737D01*
G01X14688Y1168674D02*
X15464Y1168477D01*
G01X16248D02*
X15472Y1168674D01*
G01Y1155524D02*
X12829D01*
G01X16248Y1155721D02*
X15464D01*
G01X16248Y1156666D02*
X15464D01*
G01X15472Y1156863D02*
X12829D01*
G01X15472Y1159461D02*
X12829D01*
G01X16248Y1159658D02*
X15464D01*
G01X16248Y1160603D02*
X15464D01*
G01X15472Y1160800D02*
X12829D01*
G01X15472Y1163398D02*
X12829D01*
G01X16248Y1163595D02*
X15464D01*
G01X16248Y1164540D02*
X15464D01*
G01X15472Y1164737D02*
X12829D01*
G01X15472Y1167335D02*
X12829D01*
G01X16248Y1167532D02*
X15464D01*
G01X16248Y1168477D02*
X15464D01*
G01X15472Y1155524D02*
X16248Y1155721D01*
G01X15464D02*
X14688Y1155524D01*
G01X15472Y1159461D02*
X16248Y1159658D01*
G01X15464D02*
X14688Y1159461D01*
G01X15472Y1163398D02*
X16248Y1163595D01*
G01X15464D02*
X14688Y1163398D01*
G01X15472Y1167335D02*
X16248Y1167532D01*
G01X15464D02*
X14688Y1167335D01*
G01X12829Y1171272D02*
Y1172611D01*
G01Y1175209D02*
Y1176548D01*
G01Y1179146D02*
Y1180485D01*
G01Y1183083D02*
Y1184422D01*
G01Y1187020D02*
Y1188359D01*
G01X13613D02*
Y1187020D01*
G01Y1184422D02*
Y1183083D01*
G01Y1176548D02*
Y1175209D01*
G01Y1180485D02*
Y1179146D01*
G01Y1172611D02*
Y1171272D01*
G01X15464Y1188162D02*
Y1187217D01*
G01Y1184225D02*
Y1183280D01*
G01Y1176351D02*
Y1175406D01*
G01Y1180288D02*
Y1179343D01*
G01Y1172414D02*
Y1171469D01*
G01X16248D02*
Y1172414D01*
G01Y1179343D02*
Y1180288D01*
G01Y1175406D02*
Y1176351D01*
G01Y1183280D02*
Y1184225D01*
G01Y1187217D02*
Y1188162D01*
G01X14688Y1172611D02*
X15464Y1172414D01*
G01X16248D02*
X15472Y1172611D01*
G01X14688Y1176548D02*
X15464Y1176351D01*
G01X16248D02*
X15472Y1176548D01*
G01X14688Y1180485D02*
X15464Y1180288D01*
G01X16248D02*
X15472Y1180485D01*
G01X14688Y1184422D02*
X15464Y1184225D01*
G01X16248D02*
X15472Y1184422D01*
G01X14688Y1188359D02*
X15464Y1188162D01*
G01X16248D02*
X15472Y1188359D01*
G01Y1168674D02*
X12829D01*
G01X15472Y1171272D02*
X12829D01*
G01X16248Y1171469D02*
X15464D01*
G01X16248Y1172414D02*
X15464D01*
G01X15472Y1172611D02*
X12829D01*
G01X15472Y1175209D02*
X12829D01*
G01X16248Y1175406D02*
X15464D01*
G01X16248Y1176351D02*
X15464D01*
G01X15472Y1176548D02*
X12829D01*
G01X15472Y1179146D02*
X12829D01*
G01X16248Y1179343D02*
X15464D01*
G01X16248Y1180288D02*
X15464D01*
G01X15472Y1180485D02*
X12829D01*
G01X15472Y1183083D02*
X12829D01*
G01X16248Y1183280D02*
X15464D01*
G01X16248Y1184225D02*
X15464D01*
G01X15472Y1184422D02*
X12829D01*
G01X15472Y1187020D02*
X12829D01*
G01X16248Y1187217D02*
X15464D01*
G01X16248Y1188162D02*
X15464D01*
G01X15472Y1188359D02*
X12829D01*
G01X15472Y1171272D02*
X16248Y1171469D01*
G01X15464D02*
X14688Y1171272D01*
G01X15472Y1175209D02*
X16248Y1175406D01*
G01X15464D02*
X14688Y1175209D01*
G01X15472Y1179146D02*
X16248Y1179343D01*
G01X15464D02*
X14688Y1179146D01*
G01X15472Y1183083D02*
X16248Y1183280D01*
G01X15464D02*
X14688Y1183083D01*
G01X15472Y1187020D02*
X16248Y1187217D01*
G01X15464D02*
X14688Y1187020D01*
G01X12829Y1190957D02*
Y1192296D01*
G01Y1194894D02*
Y1196233D01*
G01Y1206705D02*
Y1208044D01*
G01X13613D02*
Y1206705D01*
G01Y1196233D02*
Y1194894D01*
G01Y1192296D02*
Y1190957D01*
G01X15464Y1207847D02*
Y1206902D01*
G01Y1196036D02*
Y1195091D01*
G01Y1192099D02*
Y1191154D01*
G01X15550Y1205097D02*
Y1198089D01*
G01X16248Y1191154D02*
Y1192099D01*
G01Y1195091D02*
Y1196036D01*
G01Y1206902D02*
Y1207847D01*
G01X18700Y1203963D02*
Y1199223D01*
G01X15550Y1198089D02*
X18700Y1199223D01*
G01X14688Y1192296D02*
X15464Y1192099D01*
G01X16248D02*
X15472Y1192296D01*
G01X14688Y1196233D02*
X15464Y1196036D01*
G01X16248D02*
X15472Y1196233D01*
G01X14688Y1208044D02*
X15464Y1207847D01*
G01X16248D02*
X15472Y1208044D01*
G01X15550Y1205097D02*
X18700Y1203963D01*
G01X15472Y1190957D02*
X12829D01*
G01X16248Y1191154D02*
X15464D01*
G01X16248Y1192099D02*
X15464D01*
G01X15472Y1192296D02*
X12829D01*
G01X15472Y1194894D02*
X12829D01*
G01X16248Y1195091D02*
X15464D01*
G01X16248Y1196036D02*
X15464D01*
G01X15472Y1196233D02*
X12829D01*
G01X15472Y1206705D02*
X12829D01*
G01X16248Y1206902D02*
X15464D01*
G01X16248Y1207847D02*
X15464D01*
G01X15472Y1208044D02*
X12829D01*
G01X15472Y1190957D02*
X16248Y1191154D01*
G01X15464D02*
X14688Y1190957D01*
G01X15472Y1194894D02*
X16248Y1195091D01*
G01X15464D02*
X14688Y1194894D01*
G01X15472Y1206705D02*
X16248Y1206902D01*
G01X15464D02*
X14688Y1206705D01*
G01X19881Y1197835D02*
G03Y1205315I0J3740D01*
G01X12829Y1210642D02*
Y1211981D01*
G01Y1214579D02*
Y1215918D01*
G01Y1218516D02*
Y1219855D01*
G01Y1222453D02*
Y1223792D01*
G01X13613D02*
Y1222453D01*
G01Y1219855D02*
Y1218516D01*
G01Y1215918D02*
Y1214579D01*
G01Y1211981D02*
Y1210642D01*
G01X15464Y1223595D02*
Y1222650D01*
G01Y1219658D02*
Y1218713D01*
G01Y1215721D02*
Y1214776D01*
G01Y1211784D02*
Y1210839D01*
G01X16248D02*
Y1211784D01*
G01Y1214776D02*
Y1215721D01*
G01Y1218713D02*
Y1219658D01*
G01Y1222650D02*
Y1223595D01*
G01X14688Y1211981D02*
X15464Y1211784D01*
G01X16248D02*
X15472Y1211981D01*
G01X14688Y1215918D02*
X15464Y1215721D01*
G01X16248D02*
X15472Y1215918D01*
G01X14688Y1219855D02*
X15464Y1219658D01*
G01X16248D02*
X15472Y1219855D01*
G01X14688Y1223792D02*
X15464Y1223595D01*
G01X16248D02*
X15472Y1223792D01*
G01Y1210642D02*
X12829D01*
G01X16248Y1210839D02*
X15464D01*
G01X16248Y1211784D02*
X15464D01*
G01X15472Y1211981D02*
X12829D01*
G01X15472Y1214579D02*
X12829D01*
G01X16248Y1214776D02*
X15464D01*
G01X16248Y1215721D02*
X15464D01*
G01X15472Y1215918D02*
X12829D01*
G01X15472Y1218516D02*
X12829D01*
G01X16248Y1218713D02*
X15464D01*
G01X16248Y1219658D02*
X15464D01*
G01X15472Y1219855D02*
X12829D01*
G01X15472Y1222453D02*
X12829D01*
G01X16248Y1222650D02*
X15464D01*
G01X16248Y1223595D02*
X15464D01*
G01X15472Y1223792D02*
X12829D01*
G01X15472Y1210642D02*
X16248Y1210839D01*
G01X15464D02*
X14688Y1210642D01*
G01X15472Y1214579D02*
X16248Y1214776D01*
G01X15464D02*
X14688Y1214579D01*
G01X15472Y1218516D02*
X16248Y1218713D01*
G01X15464D02*
X14688Y1218516D01*
G01X15472Y1222453D02*
X16248Y1222650D01*
G01X15464D02*
X14688Y1222453D01*
G01X82677Y1223720D02*
X55118D01*
G01X82677Y1236673D02*
Y1223720D01*
G01X55118D02*
Y1236673D01*
G01X12829Y1226390D02*
Y1227729D01*
G01X13613D02*
Y1226390D01*
G01X15464Y1227532D02*
Y1226587D01*
G01X16248D02*
Y1227532D01*
G01X14688Y1227729D02*
X15464Y1227532D01*
G01X16248D02*
X15472Y1227729D01*
G01Y1226390D02*
X12829D01*
G01X16248Y1226587D02*
X15464D01*
G01X16248Y1227532D02*
X15464D01*
G01X15472Y1227729D02*
X12829D01*
G01X15472Y1226390D02*
X16248Y1226587D01*
G01X15464D02*
X14688Y1226390D01*
G01X12829Y1230327D02*
Y1231666D01*
G01X13613D02*
Y1230327D01*
G01X15464Y1231469D02*
Y1230524D01*
G01X16248D02*
Y1231469D01*
G01X22851Y1262213D02*
Y1236622D01*
G01X24802Y1262213D02*
Y1236622D01*
G01X14688Y1231666D02*
X15464Y1231469D01*
G01X16248D02*
X15472Y1231666D01*
G01Y1230327D02*
X12829D01*
G01X16248Y1230524D02*
X15464D01*
G01X16248Y1231469D02*
X15464D01*
G01X15472Y1231666D02*
X12829D01*
G01X15472Y1230327D02*
X16248Y1230524D01*
G01X15464D02*
X14688Y1230327D01*
G01X80167Y1243819D02*
G03Y1246968I-2017J1574D01*
G01X76133D02*
G03Y1243819I2017J-1575D01*
G01X75780Y1247756D02*
G03Y1243031I2370J-2363D01*
G01X80520D02*
G03Y1247756I-2370J2362D01*
G01X81654Y1245393D02*
G03I-3504J0D01*
G01X75472Y1248543D02*
G03Y1242244I2678J-3150D01*
G01X80827D02*
G03Y1248543I-2677J3149D01*
G01X72638Y1233582D02*
G03I-3740J0D01*
G01X77559Y1273582D02*
X82677Y1274763D01*
G01X70866Y1306909D02*
X88110D01*
G01X40344D02*
X70866D01*
G01X74803Y1306811D02*
X79528D01*
G01X38583D02*
X70866D01*
G01X38583Y1303582D02*
X70866D01*
G01X79528D02*
X74803D01*
G01X70866Y1303484D02*
X88110D01*
G01X40344D02*
X70866D01*
G01Y1301909D02*
X88110D01*
G01X40344D02*
X70866D01*
G01X74803Y1301811D02*
X79528D01*
G01X38583D02*
X70866D01*
G01Y1301574D02*
X77756D01*
G01Y1298819D02*
X70866D01*
G01X38583Y1298582D02*
X70866D01*
G01X79528D02*
X74803D01*
G01X70866Y1298484D02*
X88110D01*
G01X40344D02*
X70866D01*
G01Y1296909D02*
X88110D01*
G01X40344D02*
X70866D01*
G01X74803Y1296811D02*
X79528D01*
G01X38583D02*
X70866D01*
G01X38583Y1293582D02*
X70866D01*
G01X79528D02*
X74803D01*
G01X70866Y1293484D02*
X88110D01*
G01X40344D02*
X70866D01*
G01Y1291909D02*
X88110D01*
G01X40344D02*
X70866D01*
G01X74803Y1291811D02*
X79528D01*
G01X38583D02*
X70866D01*
G01X38583Y1288582D02*
X70866D01*
G01X79528D02*
X74803D01*
G01X70866Y1288484D02*
X88110D01*
G01X40344D02*
X70866D01*
G01Y1286909D02*
X88110D01*
G01X40344D02*
X70866D01*
G01X74803Y1286811D02*
X79528D01*
G01X38583D02*
X70866D01*
G01X38583Y1283582D02*
X70866D01*
G01X79528D02*
X74803D01*
G01X70866Y1283484D02*
X88110D01*
G01X40344D02*
X70866D01*
G01Y1281909D02*
X88110D01*
G01X40344D02*
X70866D01*
G01X74803Y1281811D02*
X79528D01*
G01X38583D02*
X70866D01*
G01X38583Y1278582D02*
X70866D01*
G01X79528D02*
X74803D01*
G01X70866Y1278484D02*
X88110D01*
G01X40344D02*
X70866D01*
G01Y1276909D02*
X88110D01*
G01X40344D02*
X70866D01*
G01X74803Y1276811D02*
X79528D01*
G01X38583D02*
X70866D01*
G01Y1276574D02*
X77756D01*
G01X70866Y1275059D02*
X69685D01*
G01X77756Y1273819D02*
X70866D01*
G01X38583Y1273582D02*
X69685D01*
G01X77559D02*
X72835D01*
G01X69685Y1273484D02*
X89567D01*
G01X40344D02*
X69685D01*
G01Y1271909D02*
X89567D01*
G01X40344D02*
X69685D01*
G01X72835Y1271811D02*
X77559D01*
G01X38583D02*
X69685D01*
G01Y1270334D02*
X70866D01*
G01X38583Y1268582D02*
X70866D01*
G01X79528D02*
X74803D01*
G01X70866Y1268484D02*
X88110D01*
G01X40344D02*
X70866D01*
G01Y1266909D02*
X88110D01*
G01X40344D02*
X70866D01*
G01X74803Y1266811D02*
X79528D01*
G01X38583D02*
X70866D01*
G01X38583Y1263582D02*
X70866D01*
G01X79528D02*
X74803D01*
G01X70866Y1263484D02*
X88110D01*
G01X40344D02*
X70866D01*
G01Y1261909D02*
X88110D01*
G01X40344D02*
X70866D01*
G01X74803Y1261811D02*
X79528D01*
G01X38583D02*
X70866D01*
G01X38583Y1258582D02*
X70866D01*
G01X79528D02*
X74803D01*
G01X70866Y1258484D02*
X88110D01*
G01X40344D02*
X70866D01*
G01Y1256909D02*
X88110D01*
G01X40344D02*
X70866D01*
G01X74803Y1256811D02*
X79528D01*
G01X38583D02*
X70866D01*
G01X69587Y1253878D02*
X70866D01*
G01X39764D02*
X68209D01*
G01X90551D02*
X70866D01*
G01Y1252106D02*
X90551D01*
G01X40551Y1248956D02*
X90551D01*
G01X35300D02*
X38583D01*
G01X75472Y1248543D02*
X80827D01*
G01X80520Y1247756D02*
X75780D01*
G01X80167Y1246968D02*
X76133D01*
G01X70079Y1246004D02*
X90551D01*
G01X59055D02*
X70079D01*
G01X80167Y1243819D02*
X76133D01*
G01X75780Y1243031D02*
X80520D01*
G01X80827Y1242244D02*
X75472D01*
G01X70079Y1241791D02*
X36614D01*
G01Y1240610D02*
X90551D01*
G01X59055Y1238641D02*
X78740D01*
G01X82677Y1236673D02*
X94488D01*
G01X55118D02*
X27953D01*
G01X78740Y1235551D02*
X59055D01*
G01X82677Y1270630D02*
X77559Y1271811D01*
G01X59055Y1234567D02*
X78740D01*
G01X59252Y1234370D02*
X78543D01*
G01X59252Y1232795D02*
X78543D01*
G01X78740Y1232598D02*
X59055D01*
G01Y1231614D02*
X78740D01*
G01X59055Y1229626D02*
X78740D01*
G01X59055Y1227657D02*
X78740D01*
G01X82677Y1305630D02*
X79528Y1306811D01*
G01X82677Y1300630D02*
X79528Y1301811D01*
G01X82677Y1295630D02*
X79528Y1296811D01*
G01X82677Y1290630D02*
X79528Y1291811D01*
G01X82677Y1285630D02*
X79528Y1286811D01*
G01X82677Y1280630D02*
X79528Y1281811D01*
G01X82677Y1275630D02*
X79528Y1276811D01*
G01X82677Y1265630D02*
X79528Y1266811D01*
G01X82677Y1260630D02*
X79528Y1261811D01*
G01X82677Y1255630D02*
X79528Y1256811D01*
G01X38583Y1250925D02*
X40551Y1248956D01*
G01X31890Y1246359D02*
X36610Y1241717D01*
G01X36614Y1240610D02*
X31890Y1245256D01*
G01X79528Y1258582D02*
X82677Y1259763D01*
G01X79528Y1263582D02*
X82677Y1264763D01*
G01X79528Y1268582D02*
X82677Y1269763D01*
G01X79528Y1278582D02*
X82677Y1279763D01*
G01X79528Y1283582D02*
X82677Y1284763D01*
G01X79528Y1288582D02*
X82677Y1289763D01*
G01X79528Y1293582D02*
X82677Y1294763D01*
G01X79528Y1298582D02*
X82677Y1299763D01*
G01X79528Y1303582D02*
X82677Y1304763D01*
G01X94488Y1236673D02*
Y1403720D01*
G01X90551Y1240610D02*
Y1253878D01*
G01X89567Y1273484D02*
Y1271909D01*
G01X88110Y1258484D02*
Y1256909D01*
G01Y1263484D02*
Y1261909D01*
G01Y1268484D02*
Y1266909D01*
G01Y1278484D02*
Y1276909D01*
G01Y1283484D02*
Y1281909D01*
G01Y1288484D02*
Y1286909D01*
G01Y1293484D02*
Y1291909D01*
G01Y1298484D02*
Y1296909D01*
G01Y1303484D02*
Y1301909D01*
G01Y1308484D02*
Y1306909D01*
G01X83189D02*
Y1308484D01*
G01Y1301909D02*
Y1303484D01*
G01Y1296909D02*
Y1298484D01*
G01Y1291909D02*
Y1293484D01*
G01Y1286909D02*
Y1288484D01*
G01Y1281909D02*
Y1283484D01*
G01Y1276909D02*
Y1278484D01*
G01Y1271909D02*
Y1273484D01*
G01Y1266909D02*
Y1268484D01*
G01Y1261909D02*
Y1263484D01*
G01Y1256909D02*
Y1258484D01*
G01X82795D02*
Y1256909D01*
G01Y1263484D02*
Y1261909D01*
G01Y1268484D02*
Y1266909D01*
G01Y1273484D02*
Y1271909D01*
G01Y1278484D02*
Y1276909D01*
G01Y1283484D02*
Y1281909D01*
G01Y1288484D02*
Y1286909D01*
G01Y1293484D02*
Y1291909D01*
G01Y1298484D02*
Y1296909D01*
G01Y1303484D02*
Y1301909D01*
G01Y1308484D02*
Y1306909D01*
G01X82677Y1255630D02*
Y1253878D01*
G01Y1260630D02*
Y1259763D01*
G01Y1265630D02*
Y1264763D01*
G01Y1270630D02*
Y1269763D01*
G01Y1275630D02*
Y1274763D01*
G01Y1280630D02*
Y1279763D01*
G01Y1285630D02*
Y1284763D01*
G01Y1290630D02*
Y1289763D01*
G01Y1295630D02*
Y1294763D01*
G01Y1300630D02*
Y1299763D01*
G01Y1305630D02*
Y1304763D01*
G01X82008Y1258484D02*
Y1256909D01*
G01Y1263484D02*
Y1261909D01*
G01Y1268484D02*
Y1266909D01*
G01Y1273484D02*
Y1271909D01*
G01Y1278484D02*
Y1276909D01*
G01Y1283484D02*
Y1281909D01*
G01Y1288484D02*
Y1286909D01*
G01Y1293484D02*
Y1291909D01*
G01Y1298484D02*
Y1296909D01*
G01Y1303484D02*
Y1301909D01*
G01Y1308484D02*
Y1306909D01*
G01X80433Y1258484D02*
Y1256909D01*
G01Y1263484D02*
Y1261909D01*
G01Y1268484D02*
Y1266909D01*
G01Y1273484D02*
Y1271909D01*
G01Y1278484D02*
Y1276909D01*
G01Y1283484D02*
Y1281909D01*
G01Y1288484D02*
Y1286909D01*
G01Y1293484D02*
Y1291909D01*
G01Y1298484D02*
Y1296909D01*
G01Y1303484D02*
Y1301909D01*
G01Y1308484D02*
Y1306909D01*
G01X78740Y1227657D02*
Y1240610D01*
G01X78543Y1232795D02*
Y1234370D01*
G01X77756Y1298819D02*
Y1301574D01*
G01Y1273819D02*
Y1276574D01*
G01X74803Y1256909D02*
Y1256811D01*
G01Y1258582D02*
Y1258484D01*
G01D02*
Y1256909D01*
G01Y1261909D02*
Y1261811D01*
G01Y1263582D02*
Y1263484D01*
G01D02*
Y1261909D01*
G01Y1266909D02*
Y1266811D01*
G01Y1268582D02*
Y1268484D01*
G01D02*
Y1266909D01*
G01Y1276909D02*
Y1276811D01*
G01Y1278582D02*
Y1278484D01*
G01D02*
Y1276909D01*
G01Y1281909D02*
Y1281811D01*
G01Y1283582D02*
Y1283484D01*
G01D02*
Y1281909D01*
G01Y1286909D02*
Y1286811D01*
G01Y1288582D02*
Y1288484D01*
G01D02*
Y1286909D01*
G01Y1291909D02*
Y1291811D01*
G01Y1293582D02*
Y1293484D01*
G01Y1296909D02*
Y1296811D01*
G01Y1293484D02*
Y1291909D01*
G01Y1298582D02*
Y1298484D01*
G01Y1301909D02*
Y1301811D01*
G01Y1298484D02*
Y1296909D01*
G01Y1303582D02*
Y1303484D01*
G01Y1306909D02*
Y1306811D01*
G01Y1303484D02*
Y1301909D01*
G01Y1308484D02*
Y1306909D01*
G01X73189Y1234370D02*
Y1232795D01*
G01X35300Y1248956D02*
X31890Y1246988D01*
G01X39764Y1253878D02*
X38583Y1252696D01*
G01X72835Y1271909D02*
Y1271811D01*
G01Y1273582D02*
Y1273484D01*
G01D02*
Y1271909D01*
G01X71850Y1234370D02*
Y1234567D01*
G01Y1232795D02*
Y1232598D01*
G01Y1234370D02*
Y1232795D01*
G01X71654Y1234370D02*
Y1232795D01*
G01X70866Y1271909D02*
Y1273484D01*
G01D02*
Y1311909D01*
G01Y1252106D02*
Y1271909D01*
G01X70079Y1240610D02*
Y1248956D01*
G01Y1232795D02*
Y1234370D01*
G01X69685Y1275059D02*
Y1270334D01*
G01X69587Y1253878D02*
Y1386515D01*
G01X68209D02*
Y1253878D01*
G01X67717Y1232795D02*
Y1234370D01*
G01X66929Y1253878D02*
Y1386515D01*
G01X66142Y1232795D02*
Y1234370D01*
G01X65945Y1232795D02*
Y1234370D01*
G01Y1234567D02*
Y1234370D01*
G01Y1232795D02*
Y1232598D01*
G01X64606Y1232795D02*
Y1234370D01*
G01X59252D02*
Y1232795D01*
G01X59055Y1240610D02*
Y1399783D01*
G01Y1227657D02*
Y1240610D01*
G01X46553Y1258484D02*
Y1256909D01*
G01Y1263484D02*
Y1261909D01*
G01Y1268484D02*
Y1266909D01*
G01Y1273484D02*
Y1271909D01*
G01Y1278484D02*
Y1276909D01*
G01Y1283484D02*
Y1281909D01*
G01Y1288484D02*
Y1286909D01*
G01Y1293484D02*
Y1291909D01*
G01Y1298484D02*
Y1296909D01*
G01Y1303484D02*
Y1301909D01*
G01Y1308484D02*
Y1306909D01*
G01X45447Y1258484D02*
Y1256909D01*
G01Y1263484D02*
Y1261909D01*
G01Y1268484D02*
Y1266909D01*
G01Y1273484D02*
Y1271909D01*
G01Y1278484D02*
Y1276909D01*
G01Y1283484D02*
Y1281909D01*
G01Y1288484D02*
Y1286909D01*
G01Y1293484D02*
Y1291909D01*
G01Y1298484D02*
Y1296909D01*
G01Y1303484D02*
Y1301909D01*
G01Y1308484D02*
Y1306909D01*
G01X45201Y1258484D02*
Y1256909D01*
G01Y1263484D02*
Y1261909D01*
G01Y1268484D02*
Y1266909D01*
G01Y1273484D02*
Y1271909D01*
G01Y1278484D02*
Y1276909D01*
G01Y1283484D02*
Y1281909D01*
G01Y1288484D02*
Y1286909D01*
G01Y1293484D02*
Y1291909D01*
G01Y1298484D02*
Y1296909D01*
G01Y1303484D02*
Y1301909D01*
G01Y1308484D02*
Y1306909D01*
G01X41535Y1258582D02*
Y1256811D01*
G01Y1263582D02*
Y1261811D01*
G01Y1268582D02*
Y1266811D01*
G01Y1273582D02*
Y1271811D01*
G01Y1278582D02*
Y1276811D01*
G01Y1283582D02*
Y1281811D01*
G01Y1288582D02*
Y1286811D01*
G01Y1293582D02*
Y1291811D01*
G01Y1298582D02*
Y1296811D01*
G01Y1303582D02*
Y1301811D01*
G01Y1308582D02*
Y1306811D01*
G01X41026Y1306909D02*
Y1308484D01*
G01Y1301909D02*
Y1303484D01*
G01Y1296909D02*
Y1298484D01*
G01Y1291909D02*
Y1293484D01*
G01Y1286909D02*
Y1288484D01*
G01Y1281909D02*
Y1283484D01*
G01Y1276909D02*
Y1278484D01*
G01Y1271909D02*
Y1273484D01*
G01Y1266909D02*
Y1268484D01*
G01Y1261909D02*
Y1263484D01*
G01Y1256909D02*
Y1258484D01*
G01X40344D02*
Y1256909D01*
G01Y1263484D02*
Y1261909D01*
G01Y1268484D02*
Y1266909D01*
G01Y1273484D02*
Y1271909D01*
G01Y1278484D02*
Y1276909D01*
G01Y1283484D02*
Y1281909D01*
G01Y1288484D02*
Y1286909D01*
G01Y1293484D02*
Y1291909D01*
G01Y1298484D02*
Y1296909D01*
G01Y1303484D02*
Y1301909D01*
G01Y1308484D02*
Y1306909D01*
G01X39764Y1253878D02*
Y1386515D01*
G01X38583Y1248956D02*
Y1391437D01*
G01X36614Y1241791D02*
Y1248956D01*
G01X31890Y1245256D02*
Y1246988D01*
G01X27953Y1403720D02*
Y1236673D01*
G01X22834Y1350782D02*
Y1325191D01*
G01X24802Y1350782D02*
Y1325191D01*
G01X26771Y1716136D02*
Y1323223D01*
G01X12117Y1355808D02*
Y1354561D01*
G01X12519Y1355743D02*
Y1354168D01*
G01Y1357908D02*
Y1357514D01*
G01X12600Y1368676D02*
Y1367337D01*
G01Y1364739D02*
Y1363400D01*
G01Y1360802D02*
Y1359463D01*
G01Y1356865D02*
Y1355526D01*
G01X13423Y1368676D02*
Y1367337D01*
G01Y1364739D02*
Y1363400D01*
G01Y1360802D02*
Y1359463D01*
G01Y1356865D02*
Y1355526D01*
G01X15464Y1368479D02*
Y1367534D01*
G01Y1364542D02*
Y1363597D01*
G01Y1360605D02*
Y1359660D01*
G01Y1356668D02*
Y1355723D01*
G01X15962Y1368479D02*
Y1367534D01*
G01Y1364542D02*
Y1363597D01*
G01Y1360605D02*
Y1359660D01*
G01Y1356668D02*
Y1355723D01*
G01X12452Y1356070D02*
X12519Y1355743D01*
G01X12050Y1356005D02*
X12117Y1355808D01*
G01X12251Y1356333D02*
X12452Y1356070D01*
G01X14579Y1356865D02*
X15464Y1356668D01*
G01X15962D02*
X15077Y1356865D01*
G01X14579Y1360802D02*
X15464Y1360605D01*
G01X15962D02*
X15077Y1360802D01*
G01X14579Y1364739D02*
X15464Y1364542D01*
G01X15962D02*
X15077Y1364739D01*
G01X14579Y1368676D02*
X15464Y1368479D01*
G01X15962D02*
X15077Y1368676D01*
G01X15962Y1355723D02*
X15464D01*
G01X15962Y1356668D02*
X15464D01*
G01X12600Y1356865D02*
X15077D01*
G01X15962Y1359660D02*
X15464D01*
G01X15962Y1360605D02*
X15464D01*
G01X12600Y1360802D02*
X15077D01*
G01X15962Y1363597D02*
X15464D01*
G01X15962Y1364542D02*
X15464D01*
G01X12600Y1364739D02*
X15077D01*
G01X15962Y1367534D02*
X15464D01*
G01X15962Y1368479D02*
X15464D01*
G01X12600Y1368676D02*
X15077D01*
G01X15962Y1355723D02*
X15077Y1355526D01*
G01X14579D02*
X15464Y1355723D01*
G01X15962Y1359660D02*
X15077Y1359463D01*
G01X14579D02*
X15464Y1359660D01*
G01X15962Y1363597D02*
X15077Y1363400D01*
G01X14579D02*
X15464Y1363597D01*
G01X15962Y1367534D02*
X15077Y1367337D01*
G01X14579D02*
X15464Y1367534D01*
G01X12600Y1388361D02*
Y1387022D01*
G01Y1384424D02*
Y1383085D01*
G01Y1380487D02*
Y1379148D01*
G01Y1376550D02*
Y1375211D01*
G01Y1372613D02*
Y1371274D01*
G01X13423Y1388361D02*
Y1387022D01*
G01Y1384424D02*
Y1383085D01*
G01Y1380487D02*
Y1379148D01*
G01Y1376550D02*
Y1375211D01*
G01Y1372613D02*
Y1371274D01*
G01X15464Y1388164D02*
Y1387219D01*
G01Y1384227D02*
Y1383282D01*
G01Y1380290D02*
Y1379345D01*
G01Y1376353D02*
Y1375408D01*
G01Y1372416D02*
Y1371471D01*
G01X15962Y1388164D02*
Y1387219D01*
G01Y1384227D02*
Y1383282D01*
G01Y1380290D02*
Y1379345D01*
G01Y1376353D02*
Y1375408D01*
G01Y1372416D02*
Y1371471D01*
G01X14579Y1372613D02*
X15464Y1372416D01*
G01X15962D02*
X15077Y1372613D01*
G01X14579Y1376550D02*
X15464Y1376353D01*
G01X15962D02*
X15077Y1376550D01*
G01X14579Y1380487D02*
X15464Y1380290D01*
G01X15962D02*
X15077Y1380487D01*
G01X14579Y1384424D02*
X15464Y1384227D01*
G01X15962D02*
X15077Y1384424D01*
G01X14579Y1388361D02*
X15464Y1388164D01*
G01X15962D02*
X15077Y1388361D01*
G01X15962Y1371471D02*
X15464D01*
G01X15962Y1372416D02*
X15464D01*
G01X12600Y1372613D02*
X15077D01*
G01X15962Y1375408D02*
X15464D01*
G01X15962Y1376353D02*
X15464D01*
G01X12600Y1376550D02*
X15077D01*
G01X15962Y1379345D02*
X15464D01*
G01X15962Y1380290D02*
X15464D01*
G01X12600Y1380487D02*
X15077D01*
G01X15962Y1383282D02*
X15464D01*
G01X15962Y1384227D02*
X15464D01*
G01X12600Y1384424D02*
X15077D01*
G01X15962Y1387219D02*
X15464D01*
G01X15962Y1388164D02*
X15464D01*
G01X12600Y1388361D02*
X15077D01*
G01X15962Y1371471D02*
X15077Y1371274D01*
G01X14579D02*
X15464Y1371471D01*
G01X15962Y1375408D02*
X15077Y1375211D01*
G01X14579D02*
X15464Y1375408D01*
G01X15962Y1379345D02*
X15077Y1379148D01*
G01X14579D02*
X15464Y1379345D01*
G01X15962Y1383282D02*
X15077Y1383085D01*
G01X14579D02*
X15464Y1383282D01*
G01X15962Y1387219D02*
X15077Y1387022D01*
G01X14579D02*
X15464Y1387219D01*
G01X12600Y1392298D02*
Y1390959D01*
G01X13423Y1392298D02*
Y1390959D01*
G01X15962Y1391156D02*
X15077Y1390959D01*
G01X14579D02*
X15464Y1391156D01*
G01X78224Y1390866D02*
X78150D01*
G01X78075Y1399133D02*
G03X78150Y1390866I74J-4133D01*
G01X78224Y1390867D02*
G03X78150Y1399133I-74J4133D01*
G01X85589Y1383530D02*
X85723Y1383563D01*
G01X90551Y1388287D02*
X70866D01*
G01X77559Y1313582D02*
X82677Y1314763D01*
G01X78306Y1350813D02*
X78440Y1350846D01*
G01X70866Y1386515D02*
X90551D01*
G01X69587D02*
X70866D01*
G01X68209D02*
X39764D01*
G01X38583Y1383582D02*
X70866D01*
G01X79528D02*
X74803D01*
G01X85723Y1383563D02*
X85857D01*
G01X70866Y1383484D02*
X88110D01*
G01X40344D02*
X70866D01*
G01X85824Y1383366D02*
X85757D01*
G01X86427Y1382644D02*
X86527D01*
G01X86561Y1382447D02*
X86393D01*
G01X85857Y1382185D02*
X85589D01*
G01X86929Y1381988D02*
X85622D01*
G01X70866Y1381909D02*
X88110D01*
G01X40344D02*
X70866D01*
G01X74803Y1381811D02*
X79528D01*
G01X38583D02*
X70866D01*
G01X85354Y1381791D02*
X86929D01*
G01X38583Y1378582D02*
X70866D01*
G01X79528D02*
X74803D01*
G01X70866Y1378484D02*
X88110D01*
G01X40344D02*
X70866D01*
G01Y1376909D02*
X88110D01*
G01X40344D02*
X70866D01*
G01X74803Y1376811D02*
X79528D01*
G01X38583D02*
X70866D01*
G01X38583Y1373582D02*
X70866D01*
G01X79528D02*
X74803D01*
G01X70866Y1373484D02*
X88110D01*
G01X40344D02*
X70866D01*
G01Y1371909D02*
X88110D01*
G01X40344D02*
X70866D01*
G01X74803Y1371811D02*
X79528D01*
G01X38583D02*
X70866D01*
G01X38583Y1368582D02*
X70866D01*
G01X79528D02*
X74803D01*
G01X70866Y1368484D02*
X88110D01*
G01X40344D02*
X70866D01*
G01Y1366909D02*
X88110D01*
G01X40344D02*
X70866D01*
G01X74803Y1366811D02*
X79528D01*
G01X38583D02*
X70866D01*
G01X38583Y1363582D02*
X70866D01*
G01X79528D02*
X74803D01*
G01X70866Y1363484D02*
X88110D01*
G01X40344D02*
X70866D01*
G01Y1361909D02*
X88110D01*
G01X40344D02*
X70866D01*
G01X74803Y1361811D02*
X79528D01*
G01X38583D02*
X70866D01*
G01Y1361574D02*
X77756D01*
G01Y1358819D02*
X70866D01*
G01X38583Y1358582D02*
X70866D01*
G01X79528D02*
X74803D01*
G01X70866Y1358484D02*
X88110D01*
G01X40344D02*
X70866D01*
G01Y1356909D02*
X88110D01*
G01X40344D02*
X70866D01*
G01X74803Y1356811D02*
X79528D01*
G01X38583D02*
X70866D01*
G01X41535Y1353582D02*
X70866D01*
G01X79528D02*
X74803D01*
G01X70866Y1353484D02*
X88110D01*
G01X40465D02*
X70866D01*
G01X38583Y1352401D02*
X70866D01*
G01Y1351909D02*
X88110D01*
G01X40465D02*
X70866D01*
G01X74803Y1351811D02*
X78937D01*
G01X41535D02*
X70866D01*
G01X78937Y1351220D02*
X75591D01*
G01X78440Y1350846D02*
X78574D01*
G01X78540Y1350649D02*
X78473D01*
G01X38780Y1350334D02*
X68110D01*
G01X38780D02*
X38583D01*
G01X73228D02*
X70866D01*
G01X68110Y1350236D02*
X80118D01*
G01X42006D02*
X68110D01*
G01X40551Y1349960D02*
X59055D01*
G01X79143Y1349928D02*
X79244D01*
G01X79277Y1349731D02*
X79110D01*
G01X79143Y1349468D02*
X79244D01*
G01X78473Y1349435D02*
X78574D01*
G01X79143Y1349304D02*
X79244D01*
G01X78473Y1349271D02*
X78540D01*
G01X68110Y1349055D02*
X80118D01*
G01X68110D02*
X42006D01*
G01X38780Y1348956D02*
X68110D01*
G01X38583D02*
X38780D01*
G01X73228D02*
X70866D01*
G01X78540Y1348484D02*
X78473D01*
G01X79244Y1348451D02*
X79143D01*
G01X78574Y1348320D02*
X78473D01*
G01X79244Y1348287D02*
X79143D01*
G01X38780Y1347185D02*
X68110D01*
G01X38780D02*
X38583D01*
G01X73228D02*
X70866D01*
G01X68110Y1347086D02*
X80118D01*
G01X42006D02*
X68110D01*
G01Y1345905D02*
X80118D01*
G01X68110D02*
X42006D01*
G01X38780Y1345807D02*
X68110D01*
G01X38583D02*
X38780D01*
G01X73228D02*
X70866D01*
G01X38780Y1344035D02*
X68110D01*
G01X38780D02*
X38583D01*
G01X73228D02*
X70866D01*
G01X68110Y1343937D02*
X80118D01*
G01X42006D02*
X68110D01*
G01Y1342756D02*
X80118D01*
G01X68110D02*
X42006D01*
G01X38780Y1342657D02*
X68110D01*
G01X38583D02*
X38780D01*
G01X73228D02*
X70866D01*
G01X38780Y1340885D02*
X68110D01*
G01X38780D02*
X38583D01*
G01X73228D02*
X70866D01*
G01X68110Y1340787D02*
X80118D01*
G01X42006D02*
X68110D01*
G01Y1339606D02*
X80118D01*
G01X68110D02*
X42006D01*
G01X38780Y1339508D02*
X68110D01*
G01X38583D02*
X38780D01*
G01X73228D02*
X70866D01*
G01X38780Y1337736D02*
X68110D01*
G01X38780D02*
X38583D01*
G01X73228D02*
X70866D01*
G01X68110Y1337637D02*
X80118D01*
G01X42006D02*
X68110D01*
G01Y1336456D02*
X80118D01*
G01X68110D02*
X42006D01*
G01X38780Y1336358D02*
X68110D01*
G01X38583D02*
X38780D01*
G01X73228D02*
X70866D01*
G01X38780Y1334586D02*
X68110D01*
G01X38780D02*
X38583D01*
G01X73228D02*
X70866D01*
G01X68110Y1334488D02*
X80118D01*
G01X42006D02*
X68110D01*
G01Y1333307D02*
X80118D01*
G01X68110D02*
X42006D01*
G01X38780Y1333208D02*
X68110D01*
G01X38583D02*
X38780D01*
G01X73228D02*
X70866D01*
G01X38780Y1331437D02*
X38583D01*
G01X68110D02*
X38780D01*
G01X73228D02*
X70866D01*
G01X68110Y1331338D02*
X80118D01*
G01X42006D02*
X68110D01*
G01X59055Y1330433D02*
X40551D01*
G01X68110Y1330157D02*
X80118D01*
G01X68110D02*
X42006D01*
G01X38583Y1330059D02*
X38780D01*
G01X68110D02*
X38780D01*
G01X73228D02*
X70866D01*
G01X75591Y1329173D02*
X78937D01*
G01X86890Y1328622D02*
X85315D01*
G01X70866Y1328582D02*
X41535D01*
G01X78937D02*
X74803D01*
G01X70866Y1328484D02*
X89567D01*
G01X40465D02*
X70866D01*
G01X85483Y1328425D02*
X85985D01*
G01X86186D02*
X86890D01*
G01X38583Y1327992D02*
X70866D01*
G01X85784Y1327605D02*
X85684D01*
G01Y1327408D02*
X85818D01*
G01Y1327145D02*
X85550D01*
G01X86890Y1326948D02*
X85583D01*
G01X70866Y1326909D02*
X89567D01*
G01X40465D02*
X70866D01*
G01X74803Y1326811D02*
X79528D01*
G01X41535D02*
X70866D01*
G01X85315Y1326752D02*
X86890D01*
G01X70866Y1326574D02*
X77756D01*
G01Y1323819D02*
X70866D01*
G01X38583Y1323582D02*
X70866D01*
G01X79528D02*
X74803D01*
G01X70866Y1323484D02*
X88110D01*
G01X40344D02*
X70866D01*
G01Y1321909D02*
X88110D01*
G01X40344D02*
X70866D01*
G01X74803Y1321811D02*
X79528D01*
G01X38583D02*
X70866D01*
G01X38583Y1318582D02*
X70866D01*
G01X79528D02*
X74803D01*
G01X70866Y1318484D02*
X88110D01*
G01X40344D02*
X70866D01*
G01Y1316909D02*
X88110D01*
G01X40344D02*
X70866D01*
G01X74803Y1316811D02*
X79528D01*
G01X38583D02*
X70866D01*
G01Y1315059D02*
X69685D01*
G01X38583Y1313582D02*
X69685D01*
G01X77559D02*
X72835D01*
G01X69685Y1313484D02*
X89567D01*
G01X40344D02*
X69685D01*
G01Y1311909D02*
X89567D01*
G01X40344D02*
X69685D01*
G01X72835Y1311811D02*
X77559D01*
G01X38583D02*
X69685D01*
G01X86494Y1383661D02*
X86628Y1383628D01*
G01X85857Y1383563D02*
X85991Y1383530D01*
G01X79210Y1350945D02*
X79344Y1350912D01*
G01X78574Y1350846D02*
X78708Y1350813D01*
G01X69685Y1310334D02*
X70866D01*
G01X38583Y1308582D02*
X70866D01*
G01X79528D02*
X74803D01*
G01X70866Y1308484D02*
X88110D01*
G01X40344D02*
X70866D01*
G01X79244Y1349468D02*
X79411Y1349402D01*
G01X79143Y1348287D02*
X78976Y1348353D01*
G01X78473Y1348320D02*
X78306Y1348385D01*
G01X82677Y1380630D02*
X79528Y1381811D01*
G01X82677Y1375630D02*
X79528Y1376811D01*
G01X82677Y1370630D02*
X79528Y1371811D01*
G01X82677Y1365630D02*
X79528Y1366811D01*
G01X82677Y1360630D02*
X79528Y1361811D01*
G01X82677Y1355630D02*
X79528Y1356811D01*
G01X86594Y1383432D02*
X86494Y1383464D01*
G01X85924Y1383333D02*
X85824Y1383366D01*
G01X85723Y1382546D02*
X85622Y1382578D01*
G01X79311Y1350715D02*
X79210Y1350748D01*
G01X78641Y1350617D02*
X78540Y1350649D01*
G01X78440Y1349829D02*
X78339Y1349862D01*
G01X85684Y1327605D02*
X85583Y1327637D01*
G01Y1327441D02*
X85684Y1327408D01*
G01X75591Y1348267D02*
X73228Y1348956D01*
G01X75591Y1345118D02*
X73228Y1345807D01*
G01X75591Y1341968D02*
X73228Y1342657D01*
G01X75591Y1338819D02*
X73228Y1339508D01*
G01X75591Y1335669D02*
X73228Y1336358D01*
G01X75591Y1332519D02*
X73228Y1333208D01*
G01X75591Y1329370D02*
X73228Y1330059D01*
G01X82677Y1310630D02*
X77559Y1311811D01*
G01X86326Y1382709D02*
X86427Y1382644D01*
G01X86628Y1383628D02*
X86795Y1383530D01*
G01X86393Y1382447D02*
X86259Y1382513D01*
G01X85656Y1382775D02*
X85723Y1382743D01*
G01X79110Y1349731D02*
X78976Y1349796D01*
G01X78372Y1350059D02*
X78440Y1350026D01*
G01X78574Y1349435D02*
X78708Y1349370D01*
G01X82677Y1325630D02*
X79528Y1326811D01*
G01X82677Y1320630D02*
X79528Y1321811D01*
G01X82677Y1315630D02*
X79528Y1316811D01*
G01X85622Y1382578D02*
X85489Y1382677D01*
G01X79244Y1349304D02*
X79378Y1349206D01*
G01X78339Y1349862D02*
X78205Y1349960D01*
G01X79143Y1348451D02*
X79009Y1348550D01*
G01X79043Y1349993D02*
X79143Y1349928D01*
G01X78540Y1349271D02*
X78641Y1349206D01*
G01X78473Y1348484D02*
X78372Y1348550D01*
G01X79344Y1350912D02*
X79512Y1350813D01*
G01X39764Y1386515D02*
X38583Y1387696D01*
G01X86695Y1383333D02*
X86594Y1383432D01*
G01X85991Y1383530D02*
X86038Y1383484D01*
G01D02*
X86125Y1383398D01*
G01X86259Y1382513D02*
X86125Y1382644D01*
G01X85589Y1382841D02*
X85656Y1382775D01*
G01X79411Y1350617D02*
X79311Y1350715D01*
G01X78708Y1350813D02*
X78842Y1350682D01*
G01X79411Y1349402D02*
X79512Y1349304D01*
G01X78976Y1349796D02*
X78842Y1349928D01*
G01X78306Y1350124D02*
X78372Y1350059D01*
G01X78708Y1349370D02*
X78808Y1349271D01*
G01X78306Y1348385D02*
X78205Y1348484D01*
G01X85449Y1327539D02*
X85583Y1327441D01*
G01X85991Y1383235D02*
X85924Y1383333D01*
G01X86259Y1382808D02*
X86326Y1382709D01*
G01X85489Y1382677D02*
X85388Y1382808D01*
G01X78205Y1349960D02*
X78104Y1350091D01*
G01X78641Y1349206D02*
X78741Y1349074D01*
G01X78976Y1348353D02*
X78875Y1348484D01*
G01X78372Y1348550D02*
X78272Y1348681D01*
G01X40551Y1349960D02*
X38583Y1351929D01*
G01X85583Y1327637D02*
X85516Y1327703D01*
G01X86125Y1383398D02*
X86192Y1383267D01*
G01X86125Y1382644D02*
X86058Y1382775D01*
G01X86795Y1383530D02*
X86823Y1383484D01*
G01D02*
X86896Y1383366D01*
G01X79512Y1350813D02*
X79612Y1350649D01*
G01X79512Y1349304D02*
X79612Y1349140D01*
G01X78205Y1348484D02*
X78104Y1348648D01*
G01X78708Y1350518D02*
X78641Y1350617D01*
G01X78976Y1350091D02*
X79043Y1349993D01*
G01X85348Y1327670D02*
X85449Y1327539D01*
G01X86024Y1383136D02*
X85991Y1383235D01*
G01X85556Y1382939D02*
X85589Y1382841D01*
G01X78842Y1350682D02*
X78909Y1350551D01*
G01X79378Y1349206D02*
X79445Y1349074D01*
G01X78842Y1349928D02*
X78775Y1350059D01*
G01X78808Y1349271D02*
X78842Y1349206D01*
G01X79009Y1348550D02*
X78942Y1348681D01*
G01X78875Y1348484D02*
X78842Y1348550D01*
G01X86896Y1383366D02*
X86929Y1383202D01*
G01X86058Y1382775D02*
X86024Y1382939D01*
G01X85388Y1382808D02*
X85354Y1382972D01*
G01X85315Y1327834D02*
X85348Y1327670D01*
G01X79612Y1350649D02*
X79646Y1350485D01*
G01X79630Y1349055D02*
X79646Y1348976D01*
G01X79612Y1349140D02*
X79630Y1349055D01*
G01X78775Y1350059D02*
X78741Y1350223D01*
G01X78075Y1350236D02*
X78071Y1350256D01*
G01X78104Y1350091D02*
X78075Y1350236D01*
G01X78104Y1348648D02*
X78071Y1348812D01*
G01X86728Y1383202D02*
X86695Y1383333D01*
G01X86192Y1383267D02*
X86226Y1383136D01*
G01Y1382939D02*
X86259Y1382808D01*
G01X79445Y1350485D02*
X79411Y1350617D01*
G01X79450Y1349055D02*
X79478Y1348943D01*
G01X79445Y1349074D02*
X79450Y1349055D01*
G01X78909Y1350551D02*
X78942Y1350420D01*
G01Y1350223D02*
X78976Y1350091D01*
G01X78942Y1348681D02*
X78909Y1348812D01*
G01X78746Y1349055D02*
X78775Y1348943D01*
G01X78741Y1349074D02*
X78746Y1349055D01*
G01X78272Y1348681D02*
X78239Y1348812D01*
G01X78741Y1350420D02*
X78708Y1350518D01*
G01X78272Y1350223D02*
X78306Y1350124D01*
G01X85516Y1327703D02*
X85483Y1327802D01*
G01X90551Y1386515D02*
Y1399783D01*
G01X89567Y1313484D02*
Y1311909D01*
G01Y1328484D02*
Y1326909D01*
G01X88110Y1318484D02*
Y1316909D01*
G01Y1323484D02*
Y1321909D01*
G01Y1353484D02*
Y1351909D01*
G01Y1358484D02*
Y1356909D01*
G01Y1363484D02*
Y1361909D01*
G01Y1368484D02*
Y1366909D01*
G01Y1373484D02*
Y1371909D01*
G01Y1378484D02*
Y1376909D01*
G01Y1383484D02*
Y1381909D01*
G01X86929Y1381791D02*
Y1381909D01*
G01D02*
Y1381988D01*
G01Y1383202D02*
Y1382939D01*
G01X86890Y1326752D02*
Y1326909D01*
G01Y1328484D02*
Y1328622D01*
G01Y1326909D02*
Y1326948D01*
G01Y1328425D02*
Y1328484D01*
G01X86728Y1382939D02*
Y1383202D01*
G01X86494Y1383484D02*
Y1383661D01*
G01Y1383464D02*
Y1383484D01*
G01X86226Y1383136D02*
Y1382939D01*
G01X86186Y1327834D02*
Y1328425D01*
G01X86024Y1382939D02*
Y1383136D01*
G01X85985Y1328425D02*
Y1327802D01*
G01X85723Y1382743D02*
Y1382546D01*
G01X85556Y1383136D02*
Y1382939D01*
G01X85483Y1327802D02*
Y1328425D01*
G01X85354Y1382972D02*
Y1383136D01*
G01Y1381909D02*
Y1381791D01*
G01Y1381988D02*
Y1381909D01*
G01X85315Y1326909D02*
Y1326752D01*
G01Y1328622D02*
Y1328484D01*
G01Y1326948D02*
Y1326909D01*
G01Y1328484D02*
Y1327834D01*
G01X83189Y1381909D02*
Y1383484D01*
G01Y1376909D02*
Y1378484D01*
G01Y1371909D02*
Y1373484D01*
G01Y1366909D02*
Y1368484D01*
G01Y1361909D02*
Y1363484D01*
G01Y1356909D02*
Y1358484D01*
G01Y1351909D02*
Y1353484D01*
G01Y1326909D02*
Y1328484D01*
G01Y1321909D02*
Y1323484D01*
G01Y1316909D02*
Y1318484D01*
G01Y1311909D02*
Y1313484D01*
G01X82795D02*
Y1311909D01*
G01Y1318484D02*
Y1316909D01*
G01Y1323484D02*
Y1321909D01*
G01Y1328484D02*
Y1326909D01*
G01Y1353484D02*
Y1351909D01*
G01Y1358484D02*
Y1356909D01*
G01Y1363484D02*
Y1361909D01*
G01Y1368484D02*
Y1366909D01*
G01Y1373484D02*
Y1371909D01*
G01Y1378484D02*
Y1376909D01*
G01Y1383484D02*
Y1381909D01*
G01X82677Y1310630D02*
Y1309763D01*
G01Y1315630D02*
Y1314763D01*
G01Y1320630D02*
Y1319763D01*
G01Y1325630D02*
Y1324763D01*
G01Y1355630D02*
Y1354763D01*
G01Y1360630D02*
Y1359763D01*
G01Y1365630D02*
Y1364763D01*
G01Y1370630D02*
Y1369763D01*
G01Y1375630D02*
Y1374763D01*
G01Y1380630D02*
Y1379763D01*
G01Y1386515D02*
Y1384763D01*
G01X82008Y1313484D02*
Y1311909D01*
G01Y1318484D02*
Y1316909D01*
G01Y1323484D02*
Y1321909D01*
G01Y1328484D02*
Y1326909D01*
G01Y1353484D02*
Y1351909D01*
G01Y1358484D02*
Y1356909D01*
G01Y1363484D02*
Y1361909D01*
G01Y1368484D02*
Y1366909D01*
G01Y1373484D02*
Y1371909D01*
G01Y1378484D02*
Y1376909D01*
G01Y1383484D02*
Y1381909D01*
G01X80433Y1313484D02*
Y1311909D01*
G01Y1318484D02*
Y1316909D01*
G01Y1323484D02*
Y1321909D01*
G01Y1328484D02*
Y1326909D01*
G01Y1353484D02*
Y1351909D01*
G01Y1358484D02*
Y1356909D01*
G01Y1363484D02*
Y1361909D01*
G01Y1368484D02*
Y1366909D01*
G01Y1373484D02*
Y1371909D01*
G01Y1378484D02*
Y1376909D01*
G01Y1383484D02*
Y1381909D01*
G01X80118Y1331338D02*
Y1330157D01*
G01Y1334488D02*
Y1333307D01*
G01Y1337637D02*
Y1336456D01*
G01Y1343937D02*
Y1342756D01*
G01Y1340787D02*
Y1339606D01*
G01Y1347086D02*
Y1345905D01*
G01Y1350236D02*
Y1349055D01*
G01X79646Y1348976D02*
Y1348779D01*
G01Y1350485D02*
Y1350236D01*
G01D02*
Y1350223D01*
G01X79478Y1348943D02*
Y1348812D01*
G01X79445Y1350236D02*
Y1350485D01*
G01Y1350223D02*
Y1350236D01*
G01X79210Y1350748D02*
Y1350945D01*
G01X78942Y1350420D02*
Y1350236D01*
G01D02*
Y1350223D01*
G01X78937Y1329173D02*
Y1328582D01*
G01Y1351811D02*
Y1351220D01*
G01X78909Y1348812D02*
Y1348943D01*
G01X78775D02*
Y1348812D01*
G01X78741Y1350236D02*
Y1350420D01*
G01Y1350223D02*
Y1350236D01*
G01X78440Y1350026D02*
Y1349829D01*
G01X78272Y1350420D02*
Y1350236D01*
G01D02*
Y1350223D01*
G01X78239Y1348812D02*
Y1348943D01*
G01X78071Y1350256D02*
Y1350420D01*
G01Y1348812D02*
Y1348943D01*
G01X77756Y1358819D02*
Y1361574D01*
G01Y1323819D02*
Y1326574D01*
G01X75591Y1329370D02*
Y1329173D01*
G01Y1332519D02*
Y1332126D01*
G01Y1338819D02*
Y1338425D01*
G01Y1335669D02*
Y1335275D01*
G01Y1341968D02*
Y1341574D01*
G01Y1348267D02*
Y1347874D01*
G01Y1345118D02*
Y1344724D01*
G01Y1351220D02*
Y1351023D01*
G01X75512Y1349055D02*
Y1350236D01*
G01Y1345905D02*
Y1347086D01*
G01Y1339606D02*
Y1340787D01*
G01Y1342756D02*
Y1343937D01*
G01Y1336456D02*
Y1337637D01*
G01Y1330157D02*
Y1331338D01*
G01Y1333307D02*
Y1334488D01*
G01X75118D02*
Y1333307D01*
G01Y1331338D02*
Y1330157D01*
G01Y1337637D02*
Y1336456D01*
G01Y1343937D02*
Y1342756D01*
G01Y1340787D02*
Y1339606D01*
G01Y1347086D02*
Y1345905D01*
G01Y1350236D02*
Y1349055D01*
G01X74803Y1308582D02*
Y1308484D01*
G01Y1316909D02*
Y1316811D01*
G01Y1318582D02*
Y1318484D01*
G01D02*
Y1316909D01*
G01Y1321909D02*
Y1321811D01*
G01Y1323582D02*
Y1323484D01*
G01D02*
Y1321909D01*
G01Y1326909D02*
Y1326811D01*
G01Y1328582D02*
Y1328484D01*
G01D02*
Y1326909D01*
G01Y1351909D02*
Y1351811D01*
G01Y1353582D02*
Y1353484D01*
G01D02*
Y1351909D01*
G01Y1356909D02*
Y1356811D01*
G01Y1358582D02*
Y1358484D01*
G01D02*
Y1356909D01*
G01Y1361909D02*
Y1361811D01*
G01Y1363484D02*
Y1361909D01*
G01Y1363582D02*
Y1363484D01*
G01Y1366909D02*
Y1366811D01*
G01Y1368582D02*
Y1368484D01*
G01Y1371909D02*
Y1371811D01*
G01Y1368484D02*
Y1366909D01*
G01Y1373582D02*
Y1373484D01*
G01Y1376909D02*
Y1376811D01*
G01Y1373484D02*
Y1371909D01*
G01Y1378582D02*
Y1378484D01*
G01Y1381909D02*
Y1381811D01*
G01Y1378484D02*
Y1376909D01*
G01Y1383582D02*
Y1383484D01*
G01D02*
Y1381909D01*
G01X74331Y1331338D02*
Y1330157D01*
G01Y1334488D02*
Y1333307D01*
G01Y1337637D02*
Y1336456D01*
G01Y1340787D02*
Y1339606D01*
G01Y1343937D02*
Y1342756D01*
G01Y1347086D02*
Y1345905D01*
G01Y1350236D02*
Y1349055D01*
G01X73228Y1331437D02*
X75591Y1332126D01*
G01X73228Y1334586D02*
X75591Y1335275D01*
G01X73228Y1337736D02*
X75591Y1338425D01*
G01X73228Y1340885D02*
X75591Y1341574D01*
G01X73228Y1344035D02*
X75591Y1344724D01*
G01X73228Y1347185D02*
X75591Y1347874D01*
G01X73228Y1350334D02*
X75591Y1351023D01*
G01X85818Y1327408D02*
X85918Y1327441D01*
G01X85885Y1327637D02*
X85784Y1327605D01*
G01X78473Y1350649D02*
X78372Y1350617D01*
G01X85757Y1383366D02*
X85656Y1383333D01*
G01X79528Y1308582D02*
X82677Y1309763D01*
G01X79528Y1318582D02*
X82677Y1319763D01*
G01X79528Y1323582D02*
X82677Y1324763D01*
G01X79528Y1353582D02*
X82677Y1354763D01*
G01X79528Y1358582D02*
X82677Y1359763D01*
G01X79528Y1363582D02*
X82677Y1364763D01*
G01X79528Y1368582D02*
X82677Y1369763D01*
G01X79528Y1373582D02*
X82677Y1374763D01*
G01X79528Y1378582D02*
X82677Y1379763D01*
G01X79528Y1383582D02*
X82677Y1384763D01*
G01X79411Y1348353D02*
X79244Y1348287D01*
G01X78976Y1349402D02*
X79143Y1349468D01*
G01X78306Y1349370D02*
X78473Y1349435D01*
G01X78708Y1348385D02*
X78574Y1348320D01*
G01X79411Y1349796D02*
X79277Y1349731D01*
G01X85985Y1327802D02*
X85952Y1327703D01*
G01X79478Y1348812D02*
X79445Y1348681D01*
G01X79411Y1350091D02*
X79445Y1350223D01*
G01X78909Y1348943D02*
X78937Y1349055D01*
G01D02*
X78942Y1349074D01*
G01X78775Y1348812D02*
X78741Y1348681D01*
G01X78239Y1348943D02*
X78267Y1349055D01*
G01D02*
X78272Y1349074D01*
G01X86695Y1382808D02*
X86728Y1382939D01*
G01X78071Y1350420D02*
X78104Y1350551D01*
G01X85354Y1383136D02*
X85388Y1383267D01*
G01X86153Y1327670D02*
X86186Y1327834D01*
G01X86929Y1382939D02*
X86896Y1382775D01*
G01X79646Y1348779D02*
X79612Y1348615D01*
G01X79646Y1350223D02*
X79612Y1350059D01*
G01X78071Y1348943D02*
X78094Y1349055D01*
G01D02*
X78104Y1349107D01*
G01X72835Y1311909D02*
Y1311811D01*
G01Y1313582D02*
Y1313484D01*
G01D02*
Y1311909D01*
G01X72756Y1331338D02*
Y1330157D01*
G01Y1334488D02*
Y1333307D01*
G01Y1337637D02*
Y1336456D01*
G01Y1340787D02*
Y1339606D01*
G01Y1343937D02*
Y1342756D01*
G01Y1347086D02*
Y1345905D01*
G01Y1350236D02*
Y1349055D01*
G01X70866Y1350236D02*
Y1388287D01*
G01Y1349055D02*
Y1350236D01*
G01Y1347086D02*
Y1349055D01*
G01Y1343937D02*
Y1345905D01*
G01D02*
Y1347086D01*
G01Y1340787D02*
Y1342756D01*
G01D02*
Y1343937D01*
G01Y1339606D02*
Y1340787D01*
G01Y1337637D02*
Y1339606D01*
G01Y1334488D02*
Y1336456D01*
G01D02*
Y1337637D01*
G01Y1331338D02*
Y1333307D01*
G01D02*
Y1334488D01*
G01Y1330157D02*
Y1331338D01*
G01Y1311909D02*
Y1313484D01*
G01D02*
Y1330157D01*
G01X69685Y1315059D02*
Y1310334D01*
G01X68110Y1352401D02*
Y1327992D01*
G01X51039Y1331338D02*
Y1330157D01*
G01Y1334488D02*
Y1333307D01*
G01Y1337637D02*
Y1336456D01*
G01Y1340787D02*
Y1339606D01*
G01Y1343937D02*
Y1342756D01*
G01Y1347086D02*
Y1345905D01*
G01Y1350236D02*
Y1349055D01*
G01X48800Y1331338D02*
Y1330157D01*
G01Y1334488D02*
Y1333307D01*
G01Y1337637D02*
Y1336456D01*
G01Y1340787D02*
Y1339606D01*
G01Y1343937D02*
Y1342756D01*
G01Y1347086D02*
Y1345905D01*
G01Y1350236D02*
Y1349055D01*
G01X48302D02*
Y1350236D01*
G01Y1345905D02*
Y1347086D01*
G01Y1342756D02*
Y1343937D01*
G01Y1339606D02*
Y1340787D01*
G01Y1336456D02*
Y1337637D01*
G01Y1330157D02*
Y1331338D01*
G01Y1333307D02*
Y1334488D01*
G01X47559Y1348956D02*
Y1350334D01*
G01Y1330059D02*
Y1331437D01*
G01Y1334586D02*
Y1333208D01*
G01Y1337736D02*
Y1336358D01*
G01Y1344035D02*
Y1342657D01*
G01Y1340885D02*
Y1339508D01*
G01Y1347185D02*
Y1345807D01*
G01X46553Y1313484D02*
Y1311909D01*
G01Y1318484D02*
Y1316909D01*
G01Y1323484D02*
Y1321909D01*
G01Y1328484D02*
Y1326909D01*
G01Y1353484D02*
Y1351909D01*
G01Y1358484D02*
Y1356909D01*
G01Y1363484D02*
Y1361909D01*
G01Y1368484D02*
Y1366909D01*
G01Y1373484D02*
Y1371909D01*
G01Y1378484D02*
Y1376909D01*
G01Y1383484D02*
Y1381909D01*
G01X45447Y1313484D02*
Y1311909D01*
G01Y1318484D02*
Y1316909D01*
G01Y1323484D02*
Y1321909D01*
G01Y1328484D02*
Y1326909D01*
G01Y1353484D02*
Y1351909D01*
G01Y1358484D02*
Y1356909D01*
G01Y1363484D02*
Y1361909D01*
G01Y1368484D02*
Y1366909D01*
G01Y1373484D02*
Y1371909D01*
G01Y1378484D02*
Y1376909D01*
G01Y1383484D02*
Y1381909D01*
G01X45201Y1351909D02*
Y1353484D01*
G01Y1326909D02*
Y1328484D01*
G01Y1313484D02*
Y1311909D01*
G01Y1318484D02*
Y1316909D01*
G01Y1323484D02*
Y1321909D01*
G01Y1358484D02*
Y1356909D01*
G01Y1363484D02*
Y1361909D01*
G01Y1368484D02*
Y1366909D01*
G01Y1373484D02*
Y1371909D01*
G01Y1378484D02*
Y1376909D01*
G01Y1383484D02*
Y1381909D01*
G01X42744Y1331338D02*
Y1330157D01*
G01Y1334488D02*
Y1333307D01*
G01Y1337637D02*
Y1336456D01*
G01Y1343937D02*
Y1342756D01*
G01Y1340787D02*
Y1339606D01*
G01Y1347086D02*
Y1345905D01*
G01Y1350236D02*
Y1349055D01*
G01X42006D02*
Y1350236D01*
G01Y1345905D02*
Y1347086D01*
G01Y1342756D02*
Y1343937D01*
G01Y1339606D02*
Y1340787D01*
G01Y1336456D02*
Y1337637D01*
G01Y1330157D02*
Y1331338D01*
G01Y1333307D02*
Y1334488D01*
G01X41535Y1313582D02*
Y1311811D01*
G01Y1318582D02*
Y1316811D01*
G01Y1323582D02*
Y1321811D01*
G01Y1328582D02*
Y1326811D01*
G01Y1353582D02*
Y1351811D01*
G01Y1358582D02*
Y1356811D01*
G01Y1363582D02*
Y1361811D01*
G01Y1368582D02*
Y1366811D01*
G01Y1373582D02*
Y1371811D01*
G01Y1378582D02*
Y1376811D01*
G01Y1383582D02*
Y1381811D01*
G01X41454Y1351909D02*
Y1353484D01*
G01Y1326909D02*
Y1328484D01*
G01X41026Y1381909D02*
Y1383484D01*
G01Y1376909D02*
Y1378484D01*
G01Y1371909D02*
Y1373484D01*
G01Y1366909D02*
Y1368484D01*
G01Y1361909D02*
Y1363484D01*
G01Y1356909D02*
Y1358484D01*
G01Y1321909D02*
Y1323484D01*
G01Y1316909D02*
Y1318484D01*
G01Y1311909D02*
Y1313484D01*
G01X40551Y1327992D02*
Y1352401D01*
G01X40465Y1328484D02*
Y1326909D01*
G01Y1353484D02*
Y1351909D01*
G01X40344Y1313484D02*
Y1311909D01*
G01Y1318484D02*
Y1316909D01*
G01Y1323484D02*
Y1321909D01*
G01Y1358484D02*
Y1356909D01*
G01Y1363484D02*
Y1361909D01*
G01Y1368484D02*
Y1366909D01*
G01Y1373484D02*
Y1371909D01*
G01Y1378484D02*
Y1376909D01*
G01Y1383484D02*
Y1381909D01*
G01X38780Y1348956D02*
Y1350334D01*
G01Y1345807D02*
Y1347185D01*
G01Y1339508D02*
Y1340885D01*
G01Y1342657D02*
Y1344035D01*
G01Y1336358D02*
Y1337736D01*
G01Y1333208D02*
Y1334586D01*
G01Y1331437D02*
Y1330059D01*
G01X86695Y1382513D02*
X86561Y1382447D01*
G01X78641Y1348550D02*
X78540Y1348484D01*
G01X78372Y1349206D02*
X78473Y1349271D01*
G01X79244Y1349928D02*
X79344Y1349993D01*
G01X86527Y1382644D02*
X86628Y1382709D01*
G01X85918Y1327441D02*
X86052Y1327539D01*
G01X79378Y1348550D02*
X79244Y1348451D01*
G01X79009Y1349206D02*
X79143Y1349304D01*
G01X85583Y1326948D02*
X85818Y1327145D01*
G01X85550D02*
X85315Y1326948D01*
G01X85622Y1381988D02*
X85857Y1382185D01*
G01X85589D02*
X85354Y1381988D01*
G01X85952Y1327703D02*
X85885Y1327637D01*
G01X79512Y1348451D02*
X79411Y1348353D01*
G01X78808Y1348484D02*
X78708Y1348385D01*
G01X79545Y1349928D02*
X79411Y1349796D01*
G01X78205Y1349271D02*
X78306Y1349370D01*
G01X78172Y1350682D02*
X78306Y1350813D01*
G01X86829Y1382644D02*
X86695Y1382513D01*
G01X85542Y1383484D02*
X85589Y1383530D01*
G01X85455Y1383398D02*
X85542Y1383484D01*
G01X40551Y1330433D02*
X38583Y1328464D01*
G01X86052Y1327539D02*
X86153Y1327670D01*
G01X78741Y1348681D02*
X78641Y1348550D01*
G01X78875Y1349271D02*
X78976Y1349402D01*
G01X78272Y1349074D02*
X78372Y1349206D01*
G01X79344Y1349993D02*
X79411Y1350091D01*
G01X78372Y1350617D02*
X78306Y1350518D01*
G01X86628Y1382709D02*
X86695Y1382808D01*
G01X85656Y1383333D02*
X85589Y1383235D01*
G01X79612Y1348615D02*
X79512Y1348451D01*
G01X78104Y1349107D02*
X78205Y1349271D01*
G01X79445Y1348681D02*
X79378Y1348550D01*
G01X78842D02*
X78808Y1348484D01*
G01X79612Y1350059D02*
X79545Y1349928D01*
G01X78942Y1349074D02*
X79009Y1349206D01*
G01X78842D02*
X78875Y1349271D01*
G01X78104Y1350551D02*
X78172Y1350682D01*
G01X86896Y1382775D02*
X86829Y1382644D01*
G01X85388Y1383267D02*
X85455Y1383398D01*
G01X78306Y1350518D02*
X78272Y1350420D01*
G01X85589Y1383235D02*
X85556Y1383136D01*
G01X40551Y1391437D02*
X38583Y1389468D01*
G01X18700Y1399081D02*
X15550Y1397947D01*
G01X12600Y1408046D02*
Y1406707D01*
G01Y1396235D02*
Y1394896D01*
G01X13423Y1408046D02*
Y1406707D01*
G01Y1396235D02*
Y1394896D01*
G01X15464Y1407849D02*
Y1406904D01*
G01Y1396038D02*
Y1395093D01*
G01Y1392101D02*
Y1391156D01*
G01X15550Y1404955D02*
Y1397947D01*
G01X15962Y1407849D02*
Y1406904D01*
G01Y1396038D02*
Y1395093D01*
G01Y1392101D02*
Y1391156D01*
G01X18700Y1403821D02*
Y1399081D01*
G01X15550Y1404955D02*
X18700Y1403821D01*
G01X14579Y1392298D02*
X15464Y1392101D01*
G01X15962D02*
X15077Y1392298D01*
G01X14579Y1396235D02*
X15464Y1396038D01*
G01X15962D02*
X15077Y1396235D01*
G01X14579Y1408046D02*
X15464Y1407849D01*
G01X15962D02*
X15077Y1408046D01*
G01X15962Y1391156D02*
X15464D01*
G01X15962Y1392101D02*
X15464D01*
G01X12600Y1392298D02*
X15077D01*
G01X15962Y1395093D02*
X15464D01*
G01X15962Y1396038D02*
X15464D01*
G01X12600Y1396235D02*
X15077D01*
G01X15962Y1406904D02*
X15464D01*
G01X15962Y1407849D02*
X15464D01*
G01X12600Y1408046D02*
X15077D01*
G01X15962Y1395093D02*
X15077Y1394896D01*
G01X14579D02*
X15464Y1395093D01*
G01X15962Y1406904D02*
X15077Y1406707D01*
G01X14579D02*
X15464Y1406904D01*
G01X19881Y1397835D02*
G03Y1405315I0J3740D01*
G01X12600Y1427731D02*
Y1426392D01*
G01Y1419857D02*
Y1418518D01*
G01Y1423794D02*
Y1422455D01*
G01Y1415920D02*
Y1414581D01*
G01Y1411983D02*
Y1410644D01*
G01X13423Y1427731D02*
Y1426392D01*
G01Y1419857D02*
Y1418518D01*
G01Y1423794D02*
Y1422455D01*
G01Y1415920D02*
Y1414581D01*
G01Y1411983D02*
Y1410644D01*
G01X15464Y1427534D02*
Y1426589D01*
G01Y1423597D02*
Y1422652D01*
G01Y1419660D02*
Y1418715D01*
G01Y1415723D02*
Y1414778D01*
G01Y1411786D02*
Y1410841D01*
G01X15962Y1427534D02*
Y1426589D01*
G01Y1423597D02*
Y1422652D01*
G01Y1419660D02*
Y1418715D01*
G01Y1415723D02*
Y1414778D01*
G01Y1411786D02*
Y1410841D01*
G01X14579Y1411983D02*
X15464Y1411786D01*
G01X15962D02*
X15077Y1411983D01*
G01X14579Y1415920D02*
X15464Y1415723D01*
G01X15962D02*
X15077Y1415920D01*
G01X14579Y1419857D02*
X15464Y1419660D01*
G01X15962D02*
X15077Y1419857D01*
G01X14579Y1423794D02*
X15464Y1423597D01*
G01X15962D02*
X15077Y1423794D01*
G01X14579Y1427731D02*
X15464Y1427534D01*
G01X15962D02*
X15077Y1427731D01*
G01X15962Y1410841D02*
X15464D01*
G01X15962Y1411786D02*
X15464D01*
G01X12600Y1411983D02*
X15077D01*
G01X15962Y1414778D02*
X15464D01*
G01X15962Y1415723D02*
X15464D01*
G01X12600Y1415920D02*
X15077D01*
G01X15962Y1418715D02*
X15464D01*
G01X15962Y1419660D02*
X15464D01*
G01X12600Y1419857D02*
X15077D01*
G01X15962Y1422652D02*
X15464D01*
G01X15962Y1423597D02*
X15464D01*
G01X12600Y1423794D02*
X15077D01*
G01X15962Y1426589D02*
X15464D01*
G01X15962Y1427534D02*
X15464D01*
G01X12600Y1427731D02*
X15077D01*
G01X15962Y1410841D02*
X15077Y1410644D01*
G01X14579D02*
X15464Y1410841D01*
G01X15962Y1414778D02*
X15077Y1414581D01*
G01X14579D02*
X15464Y1414778D01*
G01X15962Y1418715D02*
X15077Y1418518D01*
G01X14579D02*
X15464Y1418715D01*
G01X15962Y1422652D02*
X15077Y1422455D01*
G01X14579D02*
X15464Y1422652D01*
G01X15962Y1426589D02*
X15077Y1426392D01*
G01X14579D02*
X15464Y1426589D01*
G01X12600Y1443479D02*
Y1442140D01*
G01Y1447416D02*
Y1446077D01*
G01Y1439542D02*
Y1438203D01*
G01Y1435605D02*
Y1434266D01*
G01Y1431668D02*
Y1430329D01*
G01X13423Y1443479D02*
Y1442140D01*
G01Y1447416D02*
Y1446077D01*
G01Y1439542D02*
Y1438203D01*
G01Y1435605D02*
Y1434266D01*
G01Y1431668D02*
Y1430329D01*
G01X15464Y1443282D02*
Y1442337D01*
G01Y1447219D02*
Y1446274D01*
G01Y1439345D02*
Y1438400D01*
G01Y1435408D02*
Y1434463D01*
G01Y1431471D02*
Y1430526D01*
G01X15962Y1447219D02*
Y1446274D01*
G01Y1443282D02*
Y1442337D01*
G01Y1439345D02*
Y1438400D01*
G01Y1435408D02*
Y1434463D01*
G01Y1431471D02*
Y1430526D01*
G01X14579Y1431668D02*
X15464Y1431471D01*
G01X15962D02*
X15077Y1431668D01*
G01X14579Y1435605D02*
X15464Y1435408D01*
G01X15962D02*
X15077Y1435605D01*
G01X14579Y1439542D02*
X15464Y1439345D01*
G01X15962D02*
X15077Y1439542D01*
G01X14579Y1443479D02*
X15464Y1443282D01*
G01X15962D02*
X15077Y1443479D01*
G01X14579Y1447416D02*
X15464Y1447219D01*
G01X15962D02*
X15077Y1447416D01*
G01X15962Y1430526D02*
X15464D01*
G01X15962Y1431471D02*
X15464D01*
G01X12600Y1431668D02*
X15077D01*
G01X15962Y1434463D02*
X15464D01*
G01X15962Y1435408D02*
X15464D01*
G01X12600Y1435605D02*
X15077D01*
G01X15962Y1438400D02*
X15464D01*
G01X15962Y1439345D02*
X15464D01*
G01X12600Y1439542D02*
X15077D01*
G01X15962Y1442337D02*
X15464D01*
G01X15962Y1443282D02*
X15464D01*
G01X12600Y1443479D02*
X15077D01*
G01X15962Y1446274D02*
X15464D01*
G01X15962Y1447219D02*
X15464D01*
G01X12600Y1447416D02*
X15077D01*
G01X15962Y1430526D02*
X15077Y1430329D01*
G01X14579D02*
X15464Y1430526D01*
G01X15962Y1434463D02*
X15077Y1434266D01*
G01X14579D02*
X15464Y1434463D01*
G01X15962Y1438400D02*
X15077Y1438203D01*
G01X14579D02*
X15464Y1438400D01*
G01X15962Y1442337D02*
X15077Y1442140D01*
G01X14579D02*
X15464Y1442337D01*
G01X15962Y1446274D02*
X15077Y1446077D01*
G01X14579D02*
X15464Y1446274D01*
G01X12600Y1467101D02*
Y1465762D01*
G01Y1471038D02*
Y1469699D01*
G01Y1463164D02*
Y1461825D01*
G01Y1459227D02*
Y1457888D01*
G01Y1455290D02*
Y1453951D01*
G01Y1451353D02*
Y1450014D01*
G01X13423Y1467101D02*
Y1465762D01*
G01Y1471038D02*
Y1469699D01*
G01Y1463164D02*
Y1461825D01*
G01Y1459227D02*
Y1457888D01*
G01Y1455290D02*
Y1453951D01*
G01Y1451353D02*
Y1450014D01*
G01X15464Y1466904D02*
Y1465959D01*
G01Y1470841D02*
Y1469896D01*
G01Y1462967D02*
Y1462022D01*
G01Y1459030D02*
Y1458085D01*
G01Y1455093D02*
Y1454148D01*
G01Y1451156D02*
Y1450211D01*
G01X15962Y1470841D02*
Y1469896D01*
G01Y1466904D02*
Y1465959D01*
G01Y1462967D02*
Y1462022D01*
G01Y1459030D02*
Y1458085D01*
G01Y1455093D02*
Y1454148D01*
G01Y1451156D02*
Y1450211D01*
G01X14579Y1451353D02*
X15464Y1451156D01*
G01X15962D02*
X15077Y1451353D01*
G01X14579Y1455290D02*
X15464Y1455093D01*
G01X15962D02*
X15077Y1455290D01*
G01X14579Y1459227D02*
X15464Y1459030D01*
G01X15962D02*
X15077Y1459227D01*
G01X14579Y1463164D02*
X15464Y1462967D01*
G01X15962D02*
X15077Y1463164D01*
G01X14579Y1467101D02*
X15464Y1466904D01*
G01X15962D02*
X15077Y1467101D01*
G01X15962Y1450211D02*
X15464D01*
G01X15962Y1451156D02*
X15464D01*
G01X12600Y1451353D02*
X15077D01*
G01X15962Y1454148D02*
X15464D01*
G01X15962Y1455093D02*
X15464D01*
G01X12600Y1455290D02*
X15077D01*
G01X15962Y1458085D02*
X15464D01*
G01X15962Y1459030D02*
X15464D01*
G01X12600Y1459227D02*
X15077D01*
G01X15962Y1462022D02*
X15464D01*
G01X15962Y1462967D02*
X15464D01*
G01X12600Y1463164D02*
X15077D01*
G01X15962Y1465959D02*
X15464D01*
G01X15962Y1466904D02*
X15464D01*
G01X12600Y1467101D02*
X15077D01*
G01X15962Y1469896D02*
X15464D01*
G01X15962Y1450211D02*
X15077Y1450014D01*
G01X14579D02*
X15464Y1450211D01*
G01X15962Y1454148D02*
X15077Y1453951D01*
G01X14579D02*
X15464Y1454148D01*
G01X15962Y1458085D02*
X15077Y1457888D01*
G01X14579D02*
X15464Y1458085D01*
G01X15962Y1462022D02*
X15077Y1461825D01*
G01X14579D02*
X15464Y1462022D01*
G01X15962Y1465959D02*
X15077Y1465762D01*
G01X14579D02*
X15464Y1465959D01*
G01X15962Y1469896D02*
X15077Y1469699D01*
G01X14579D02*
X15464Y1469896D01*
G01X12600Y1474975D02*
Y1473636D01*
G01X13423Y1474975D02*
Y1473636D01*
G01X15464Y1474778D02*
Y1473833D01*
G01X15962Y1474778D02*
Y1473833D01*
G01X14579Y1471038D02*
X15464Y1470841D01*
G01X15962D02*
X15077Y1471038D01*
G01X15962Y1470841D02*
X15464D01*
G01X12600Y1471038D02*
X15077D01*
G01X15962Y1473833D02*
X15464D01*
G01X15962D02*
X15077Y1473636D01*
G01X14579D02*
X15464Y1473833D01*
G01X65664Y1423416D02*
X65758Y1423528D01*
G01Y1423400D02*
X65664Y1423289D01*
G01X64172Y1426831D02*
Y1424862D01*
G01Y1422303D02*
Y1424272D01*
G01X65664Y1423289D02*
Y1423416D01*
G01X65747Y1427126D02*
Y1426535D01*
G01Y1425354D02*
Y1423780D01*
G01Y1422598D02*
Y1422008D01*
G01X65758Y1422780D02*
Y1423400D01*
G01X65851Y1423528D02*
Y1422780D01*
G01X66731Y1422008D02*
Y1427126D01*
G01X66928D02*
Y1422008D01*
G01X67322Y1424272D02*
Y1422303D01*
G01Y1424862D02*
Y1426831D01*
G01X65747Y1422008D02*
X72046D01*
G01X67322Y1422303D02*
X65747D01*
G01D02*
X64172D01*
G01X65851Y1422780D02*
X65758D01*
G01Y1423528D02*
X65851D01*
G01X65747Y1424272D02*
X67322D01*
G01X64172D02*
X65747D01*
G01Y1424862D02*
X67322D01*
G01X64172D02*
X65747D01*
G01X67322Y1426831D02*
X65747D01*
G01D02*
X64172D01*
G01X65747Y1427126D02*
X72046D01*
G01X65747Y1425354D02*
G03Y1426535I0J590D01*
G01Y1422598D02*
G03Y1423780I0J591D01*
G01X70471Y1424272D02*
Y1422303D01*
G01Y1424862D02*
Y1426831D01*
G01X70865Y1427126D02*
Y1422008D01*
G01X71062D02*
Y1427126D01*
G01X72046Y1422008D02*
Y1422598D01*
G01Y1426535D02*
Y1427126D01*
G01Y1423780D02*
Y1425354D01*
G01X73621Y1426831D02*
Y1424862D01*
G01Y1422303D02*
Y1424272D01*
G01X70471Y1422303D02*
X72046D01*
G01D02*
X73621D01*
G01X72046Y1424272D02*
X70471D01*
G01X73621D02*
X72046D01*
G01Y1424862D02*
X70471D01*
G01X73621D02*
X72046D01*
G01X70471Y1426831D02*
X72046D01*
G01D02*
X73621D01*
G01X72046Y1426535D02*
G03Y1425354I0J-591D01*
G01Y1423780D02*
G03Y1422598I0J-591D01*
G01X78075Y1399133D02*
X78150D01*
G01X80709Y1395000D02*
G03I-2559J0D01*
G01X81496D02*
G03I-3346J0D01*
G01X81654D02*
G03I-3504J0D01*
G01X72638Y1406811D02*
G03I-3740J0D01*
G01X55118Y1416673D02*
X82677D01*
G01X78740Y1412736D02*
X59055D01*
G01X78740Y1410767D02*
X59055D01*
G01X78740Y1408779D02*
X59055D01*
G01Y1407795D02*
X78740D01*
G01X59252Y1407598D02*
X78543D01*
G01X59252Y1406023D02*
X78543D01*
G01X78740Y1405826D02*
X59055D01*
G01Y1404842D02*
X78740D01*
G01X27953Y1403720D02*
X55118D01*
G01X94488D02*
X82677D01*
G01X78740Y1401752D02*
X59055D01*
G01X36614Y1399783D02*
X90551D01*
G01X36614Y1398602D02*
X70079D01*
G01Y1394389D02*
X59055D01*
G01X90551D02*
X70079D01*
G01X35300Y1391437D02*
X38583D01*
G01X90551D02*
X40551D01*
G01X31890Y1393405D02*
X35300Y1391437D01*
G01X82677Y1416673D02*
Y1403720D01*
G01X78740Y1399783D02*
Y1412736D01*
G01X78543Y1406023D02*
Y1407598D01*
G01X73189D02*
Y1406023D01*
G01X71850Y1407598D02*
Y1407795D01*
G01Y1406023D02*
Y1405826D01*
G01Y1407598D02*
Y1406023D01*
G01X71654Y1407598D02*
Y1406023D01*
G01X70079D02*
Y1407598D01*
G01Y1399783D02*
Y1391437D01*
G01X67717Y1406023D02*
Y1407598D01*
G01X66142Y1406023D02*
Y1407598D01*
G01X65945Y1406023D02*
Y1407598D01*
G01Y1406023D02*
Y1405826D01*
G01Y1407795D02*
Y1407598D01*
G01X64606Y1406023D02*
Y1407598D01*
G01X59252D02*
Y1406023D01*
G01X59055Y1399783D02*
Y1412736D01*
G01X55118Y1403720D02*
Y1416673D01*
G01X36614Y1391437D02*
Y1398602D01*
G01X31890Y1393405D02*
Y1395137D01*
G01X36610Y1398676D02*
X31890Y1394034D01*
G01Y1395137D02*
X36614Y1399783D01*
G01X12600Y1490723D02*
Y1489384D01*
G01Y1486786D02*
Y1485447D01*
G01Y1482849D02*
Y1481510D01*
G01Y1478912D02*
Y1477573D01*
G01X13423Y1490723D02*
Y1489384D01*
G01Y1486786D02*
Y1485447D01*
G01Y1482849D02*
Y1481510D01*
G01Y1478912D02*
Y1477573D01*
G01X15464Y1490526D02*
Y1489581D01*
G01Y1486589D02*
Y1485644D01*
G01Y1482652D02*
Y1481707D01*
G01Y1478715D02*
Y1477770D01*
G01X15962Y1490526D02*
Y1489581D01*
G01Y1486589D02*
Y1485644D01*
G01Y1482652D02*
Y1481707D01*
G01Y1478715D02*
Y1477770D01*
G01X14579Y1474975D02*
X15464Y1474778D01*
G01X15962D02*
X15077Y1474975D01*
G01X14579Y1478912D02*
X15464Y1478715D01*
G01X15962D02*
X15077Y1478912D01*
G01X14579Y1482849D02*
X15464Y1482652D01*
G01X15962D02*
X15077Y1482849D01*
G01X14579Y1486786D02*
X15464Y1486589D01*
G01X15962D02*
X15077Y1486786D01*
G01X15962Y1474778D02*
X15464D01*
G01X12600Y1474975D02*
X15077D01*
G01X15962Y1477770D02*
X15464D01*
G01X15962Y1478715D02*
X15464D01*
G01X12600Y1478912D02*
X15077D01*
G01X15962Y1481707D02*
X15464D01*
G01X15962Y1482652D02*
X15464D01*
G01X12600Y1482849D02*
X15077D01*
G01X15962Y1485644D02*
X15464D01*
G01X15962Y1486589D02*
X15464D01*
G01X12600Y1486786D02*
X15077D01*
G01X15962Y1489581D02*
X15464D01*
G01X15962Y1477770D02*
X15077Y1477573D01*
G01X14579D02*
X15464Y1477770D01*
G01X15962Y1481707D02*
X15077Y1481510D01*
G01X14579D02*
X15464Y1481707D01*
G01X15962Y1485644D02*
X15077Y1485447D01*
G01X14579D02*
X15464Y1485644D01*
G01X15962Y1489581D02*
X15077Y1489384D01*
G01X14579D02*
X15464Y1489581D01*
G01X12600Y1510408D02*
Y1509069D01*
G01Y1506471D02*
Y1505132D01*
G01Y1502534D02*
Y1501195D01*
G01Y1494660D02*
Y1493321D01*
G01Y1498597D02*
Y1497258D01*
G01X13423Y1510408D02*
Y1509069D01*
G01Y1506471D02*
Y1505132D01*
G01Y1502534D02*
Y1501195D01*
G01Y1494660D02*
Y1493321D01*
G01Y1498597D02*
Y1497258D01*
G01X15464Y1510211D02*
Y1509266D01*
G01Y1506274D02*
Y1505329D01*
G01Y1502337D02*
Y1501392D01*
G01Y1498400D02*
Y1497455D01*
G01Y1494463D02*
Y1493518D01*
G01X15962Y1510211D02*
Y1509266D01*
G01Y1506274D02*
Y1505329D01*
G01Y1502337D02*
Y1501392D01*
G01Y1498400D02*
Y1497455D01*
G01Y1494463D02*
Y1493518D01*
G01X14579Y1490723D02*
X15464Y1490526D01*
G01X15962D02*
X15077Y1490723D01*
G01X14579Y1494660D02*
X15464Y1494463D01*
G01X15962D02*
X15077Y1494660D01*
G01X14579Y1498597D02*
X15464Y1498400D01*
G01X15962D02*
X15077Y1498597D01*
G01X14579Y1502534D02*
X15464Y1502337D01*
G01X15962D02*
X15077Y1502534D01*
G01X14579Y1506471D02*
X15464Y1506274D01*
G01X15962D02*
X15077Y1506471D01*
G01X15962Y1490526D02*
X15464D01*
G01X12600Y1490723D02*
X15077D01*
G01X15962Y1493518D02*
X15464D01*
G01X15962Y1494463D02*
X15464D01*
G01X12600Y1494660D02*
X15077D01*
G01X15962Y1497455D02*
X15464D01*
G01X15962Y1498400D02*
X15464D01*
G01X12600Y1498597D02*
X15077D01*
G01X15962Y1501392D02*
X15464D01*
G01X15962Y1502337D02*
X15464D01*
G01X12600Y1502534D02*
X15077D01*
G01X15962Y1505329D02*
X15464D01*
G01X15962Y1506274D02*
X15464D01*
G01X12600Y1506471D02*
X15077D01*
G01X15962Y1509266D02*
X15464D01*
G01X15962Y1493518D02*
X15077Y1493321D01*
G01X14579D02*
X15464Y1493518D01*
G01X15962Y1497455D02*
X15077Y1497258D01*
G01X14579D02*
X15464Y1497455D01*
G01X15962Y1501392D02*
X15077Y1501195D01*
G01X14579D02*
X15464Y1501392D01*
G01X15962Y1505329D02*
X15077Y1505132D01*
G01X14579D02*
X15464Y1505329D01*
G01X15962Y1509266D02*
X15077Y1509069D01*
G01X14579D02*
X15464Y1509266D01*
G01X12600Y1530093D02*
Y1528754D01*
G01Y1526156D02*
Y1524817D01*
G01Y1518282D02*
Y1516943D01*
G01Y1522219D02*
Y1520880D01*
G01Y1514345D02*
Y1513006D01*
G01X13423Y1530093D02*
Y1528754D01*
G01Y1526156D02*
Y1524817D01*
G01Y1518282D02*
Y1516943D01*
G01Y1522219D02*
Y1520880D01*
G01Y1514345D02*
Y1513006D01*
G01X15464Y1529896D02*
Y1528951D01*
G01Y1525959D02*
Y1525014D01*
G01Y1522022D02*
Y1521077D01*
G01Y1518085D02*
Y1517140D01*
G01Y1514148D02*
Y1513203D01*
G01X15962Y1529896D02*
Y1528951D01*
G01Y1525959D02*
Y1525014D01*
G01Y1522022D02*
Y1521077D01*
G01Y1518085D02*
Y1517140D01*
G01Y1514148D02*
Y1513203D01*
G01X14579Y1510408D02*
X15464Y1510211D01*
G01X15962D02*
X15077Y1510408D01*
G01X14579Y1514345D02*
X15464Y1514148D01*
G01X15962D02*
X15077Y1514345D01*
G01X14579Y1518282D02*
X15464Y1518085D01*
G01X15962D02*
X15077Y1518282D01*
G01X14579Y1522219D02*
X15464Y1522022D01*
G01X15962D02*
X15077Y1522219D01*
G01X14579Y1526156D02*
X15464Y1525959D01*
G01X15962D02*
X15077Y1526156D01*
G01X14579Y1530093D02*
X15464Y1529896D01*
G01X15962D02*
X15077Y1530093D01*
G01X15962Y1510211D02*
X15464D01*
G01X12600Y1510408D02*
X15077D01*
G01X15962Y1513203D02*
X15464D01*
G01X15962Y1514148D02*
X15464D01*
G01X12600Y1514345D02*
X15077D01*
G01X15962Y1517140D02*
X15464D01*
G01X15962Y1518085D02*
X15464D01*
G01X12600Y1518282D02*
X15077D01*
G01X15962Y1521077D02*
X15464D01*
G01X15962Y1522022D02*
X15464D01*
G01X12600Y1522219D02*
X15077D01*
G01X15962Y1525014D02*
X15464D01*
G01X15962Y1525959D02*
X15464D01*
G01X12600Y1526156D02*
X15077D01*
G01X15962Y1528951D02*
X15464D01*
G01X15962Y1529896D02*
X15464D01*
G01X12600Y1530093D02*
X15077D01*
G01X15962Y1513203D02*
X15077Y1513006D01*
G01X14579D02*
X15464Y1513203D01*
G01X15962Y1517140D02*
X15077Y1516943D01*
G01X14579D02*
X15464Y1517140D01*
G01X15962Y1521077D02*
X15077Y1520880D01*
G01X14579D02*
X15464Y1521077D01*
G01X15962Y1525014D02*
X15077Y1524817D01*
G01X14579D02*
X15464Y1525014D01*
G01X15962Y1528951D02*
X15077Y1528754D01*
G01X14579D02*
X15464Y1528951D01*
G01X12600Y1549778D02*
Y1548439D01*
G01Y1541904D02*
Y1540565D01*
G01Y1545841D02*
Y1544502D01*
G01Y1537967D02*
Y1536628D01*
G01Y1534030D02*
Y1532691D01*
G01X13423Y1549778D02*
Y1548439D01*
G01Y1541904D02*
Y1540565D01*
G01Y1545841D02*
Y1544502D01*
G01Y1537967D02*
Y1536628D01*
G01Y1534030D02*
Y1532691D01*
G01X15464Y1549581D02*
Y1548636D01*
G01Y1541707D02*
Y1540762D01*
G01Y1545644D02*
Y1544699D01*
G01Y1537770D02*
Y1536825D01*
G01Y1533833D02*
Y1532888D01*
G01X15962Y1549581D02*
Y1548636D01*
G01Y1545644D02*
Y1544699D01*
G01Y1541707D02*
Y1540762D01*
G01Y1537770D02*
Y1536825D01*
G01Y1533833D02*
Y1532888D01*
G01X14579Y1534030D02*
X15464Y1533833D01*
G01X15962D02*
X15077Y1534030D01*
G01X14579Y1537967D02*
X15464Y1537770D01*
G01X15962D02*
X15077Y1537967D01*
G01X14579Y1541904D02*
X15464Y1541707D01*
G01X15962D02*
X15077Y1541904D01*
G01X14579Y1545841D02*
X15464Y1545644D01*
G01X15962D02*
X15077Y1545841D01*
G01X14579Y1549778D02*
X15464Y1549581D01*
G01X15962D02*
X15077Y1549778D01*
G01X15962Y1532888D02*
X15464D01*
G01X15962Y1533833D02*
X15464D01*
G01X12600Y1534030D02*
X15077D01*
G01X15962Y1536825D02*
X15464D01*
G01X15962Y1537770D02*
X15464D01*
G01X12600Y1537967D02*
X15077D01*
G01X15962Y1540762D02*
X15464D01*
G01X15962Y1541707D02*
X15464D01*
G01X12600Y1541904D02*
X15077D01*
G01X15962Y1544699D02*
X15464D01*
G01X15962Y1545644D02*
X15464D01*
G01X12600Y1545841D02*
X15077D01*
G01X15962Y1548636D02*
X15464D01*
G01X15962Y1549581D02*
X15464D01*
G01X12600Y1549778D02*
X15077D01*
G01X15962Y1532888D02*
X15077Y1532691D01*
G01X14579D02*
X15464Y1532888D01*
G01X15962Y1536825D02*
X15077Y1536628D01*
G01X14579D02*
X15464Y1536825D01*
G01X15962Y1540762D02*
X15077Y1540565D01*
G01X14579D02*
X15464Y1540762D01*
G01X15962Y1544699D02*
X15077Y1544502D01*
G01X14579D02*
X15464Y1544699D01*
G01X15962Y1548636D02*
X15077Y1548439D01*
G01X14579D02*
X15464Y1548636D01*
G01X12600Y1557652D02*
Y1556313D01*
G01Y1553715D02*
Y1552376D01*
G01X13423Y1557652D02*
Y1556313D01*
G01Y1553715D02*
Y1552376D01*
G01X15464Y1557455D02*
Y1556510D01*
G01Y1553518D02*
Y1552573D01*
G01X15962Y1557455D02*
Y1556510D01*
G01Y1553518D02*
Y1552573D01*
G01X14579Y1553715D02*
X15464Y1553518D01*
G01X15962D02*
X15077Y1553715D01*
G01X15962Y1552573D02*
X15464D01*
G01X15962Y1553518D02*
X15464D01*
G01X12600Y1553715D02*
X15077D01*
G01X15962Y1556510D02*
X15464D01*
G01X15962Y1552573D02*
X15077Y1552376D01*
G01X14579D02*
X15464Y1552573D01*
G01X15962Y1556510D02*
X15077Y1556313D01*
G01X14579D02*
X15464Y1556510D01*
G01X12600Y1565526D02*
Y1564187D01*
G01Y1569463D02*
Y1568124D01*
G01Y1561589D02*
Y1560250D01*
G01X13423Y1565526D02*
Y1564187D01*
G01Y1569463D02*
Y1568124D01*
G01Y1561589D02*
Y1560250D01*
G01X15464Y1569266D02*
Y1568321D01*
G01Y1565329D02*
Y1564384D01*
G01Y1561392D02*
Y1560447D01*
G01X15962Y1569266D02*
Y1568321D01*
G01Y1565329D02*
Y1564384D01*
G01Y1561392D02*
Y1560447D01*
G01X14579Y1557652D02*
X15464Y1557455D01*
G01X15962D02*
X15077Y1557652D01*
G01X14579Y1561589D02*
X15464Y1561392D01*
G01X15962D02*
X15077Y1561589D01*
G01X14579Y1565526D02*
X15464Y1565329D01*
G01X15962D02*
X15077Y1565526D01*
G01X14579Y1569463D02*
X15464Y1569266D01*
G01X15962D02*
X15077Y1569463D01*
G01X15962Y1557455D02*
X15464D01*
G01X12600Y1557652D02*
X15077D01*
G01X15962Y1560447D02*
X15464D01*
G01X15962Y1561392D02*
X15464D01*
G01X12600Y1561589D02*
X15077D01*
G01X15962Y1564384D02*
X15464D01*
G01X15962Y1565329D02*
X15464D01*
G01X12600Y1565526D02*
X15077D01*
G01X15962Y1568321D02*
X15464D01*
G01X15962Y1569266D02*
X15464D01*
G01X12600Y1569463D02*
X15077D01*
G01X15962Y1560447D02*
X15077Y1560250D01*
G01X14579D02*
X15464Y1560447D01*
G01X15962Y1564384D02*
X15077Y1564187D01*
G01X14579D02*
X15464Y1564384D01*
G01X15962Y1568321D02*
X15077Y1568124D01*
G01X14579D02*
X15464Y1568321D01*
G01X12600Y1589148D02*
Y1587809D01*
G01Y1585211D02*
Y1583872D01*
G01Y1581274D02*
Y1579935D01*
G01Y1577337D02*
Y1575998D01*
G01Y1573400D02*
Y1572061D01*
G01X13423Y1589148D02*
Y1587809D01*
G01Y1585211D02*
Y1583872D01*
G01Y1581274D02*
Y1579935D01*
G01Y1577337D02*
Y1575998D01*
G01Y1573400D02*
Y1572061D01*
G01X15464Y1588951D02*
Y1588006D01*
G01Y1585014D02*
Y1584069D01*
G01Y1581077D02*
Y1580132D01*
G01Y1577140D02*
Y1576195D01*
G01Y1573203D02*
Y1572258D01*
G01X15962Y1588951D02*
Y1588006D01*
G01Y1585014D02*
Y1584069D01*
G01Y1581077D02*
Y1580132D01*
G01Y1577140D02*
Y1576195D01*
G01Y1573203D02*
Y1572258D01*
G01X14579Y1573400D02*
X15464Y1573203D01*
G01X15962D02*
X15077Y1573400D01*
G01X14579Y1577337D02*
X15464Y1577140D01*
G01X15962D02*
X15077Y1577337D01*
G01X14579Y1581274D02*
X15464Y1581077D01*
G01X15962D02*
X15077Y1581274D01*
G01X14579Y1585211D02*
X15464Y1585014D01*
G01X15962D02*
X15077Y1585211D01*
G01X14579Y1589148D02*
X15464Y1588951D01*
G01X15962D02*
X15077Y1589148D01*
G01X15962Y1572258D02*
X15464D01*
G01X15962Y1573203D02*
X15464D01*
G01X12600Y1573400D02*
X15077D01*
G01X15962Y1576195D02*
X15464D01*
G01X15962Y1577140D02*
X15464D01*
G01X12600Y1577337D02*
X15077D01*
G01X15962Y1580132D02*
X15464D01*
G01X15962Y1581077D02*
X15464D01*
G01X12600Y1581274D02*
X15077D01*
G01X15962Y1584069D02*
X15464D01*
G01X15962Y1585014D02*
X15464D01*
G01X12600Y1585211D02*
X15077D01*
G01X15962Y1588006D02*
X15464D01*
G01X15962Y1588951D02*
X15464D01*
G01X12600Y1589148D02*
X15077D01*
G01X15962Y1572258D02*
X15077Y1572061D01*
G01X14579D02*
X15464Y1572258D01*
G01X15962Y1576195D02*
X15077Y1575998D01*
G01X14579D02*
X15464Y1576195D01*
G01X15962Y1580132D02*
X15077Y1579935D01*
G01X14579D02*
X15464Y1580132D01*
G01X15962Y1584069D02*
X15077Y1583872D01*
G01X14579D02*
X15464Y1584069D01*
G01X15962Y1588006D02*
X15077Y1587809D01*
G01X14579D02*
X15464Y1588006D01*
G01X12600Y1608833D02*
Y1607494D01*
G01Y1604896D02*
Y1603557D01*
G01Y1600959D02*
Y1599620D01*
G01Y1593085D02*
Y1591746D01*
G01Y1597022D02*
Y1595683D01*
G01X13423Y1608833D02*
Y1607494D01*
G01Y1604896D02*
Y1603557D01*
G01Y1600959D02*
Y1599620D01*
G01Y1593085D02*
Y1591746D01*
G01Y1597022D02*
Y1595683D01*
G01X15464Y1608636D02*
Y1607691D01*
G01Y1604699D02*
Y1603754D01*
G01Y1600762D02*
Y1599817D01*
G01Y1596825D02*
Y1595880D01*
G01Y1592888D02*
Y1591943D01*
G01X15962Y1608636D02*
Y1607691D01*
G01Y1604699D02*
Y1603754D01*
G01Y1600762D02*
Y1599817D01*
G01Y1596825D02*
Y1595880D01*
G01Y1592888D02*
Y1591943D01*
G01X14579Y1593085D02*
X15464Y1592888D01*
G01X15962D02*
X15077Y1593085D01*
G01X14579Y1597022D02*
X15464Y1596825D01*
G01X15962D02*
X15077Y1597022D01*
G01X14579Y1600959D02*
X15464Y1600762D01*
G01X15962D02*
X15077Y1600959D01*
G01X14579Y1604896D02*
X15464Y1604699D01*
G01X15962D02*
X15077Y1604896D01*
G01X14579Y1608833D02*
X15464Y1608636D01*
G01X15962D02*
X15077Y1608833D01*
G01X15962Y1591943D02*
X15464D01*
G01X15962Y1592888D02*
X15464D01*
G01X12600Y1593085D02*
X15077D01*
G01X15962Y1595880D02*
X15464D01*
G01X15962Y1596825D02*
X15464D01*
G01X12600Y1597022D02*
X15077D01*
G01X15962Y1599817D02*
X15464D01*
G01X15962Y1600762D02*
X15464D01*
G01X12600Y1600959D02*
X15077D01*
G01X15962Y1603754D02*
X15464D01*
G01X15962Y1604699D02*
X15464D01*
G01X12600Y1604896D02*
X15077D01*
G01X15962Y1607691D02*
X15464D01*
G01X15962Y1608636D02*
X15464D01*
G01X12600Y1608833D02*
X15077D01*
G01X15962Y1591943D02*
X15077Y1591746D01*
G01X14579D02*
X15464Y1591943D01*
G01X15962Y1595880D02*
X15077Y1595683D01*
G01X14579D02*
X15464Y1595880D01*
G01X15962Y1599817D02*
X15077Y1599620D01*
G01X14579D02*
X15464Y1599817D01*
G01X15962Y1603754D02*
X15077Y1603557D01*
G01X14579D02*
X15464Y1603754D01*
G01X15962Y1607691D02*
X15077Y1607494D01*
G01X14579D02*
X15464Y1607691D01*
G01X12600Y1628518D02*
Y1627180D01*
G01Y1624581D02*
Y1623243D01*
G01Y1616707D02*
Y1615369D01*
G01Y1620644D02*
Y1619306D01*
G01Y1612770D02*
Y1611431D01*
G01X13423Y1628518D02*
Y1627180D01*
G01Y1624581D02*
Y1623243D01*
G01Y1616707D02*
Y1615369D01*
G01Y1620644D02*
Y1619306D01*
G01Y1612770D02*
Y1611431D01*
G01X15464Y1628321D02*
Y1627376D01*
G01Y1624384D02*
Y1623439D01*
G01Y1616510D02*
Y1615565D01*
G01Y1620447D02*
Y1619502D01*
G01Y1612573D02*
Y1611628D01*
G01X15962Y1628321D02*
Y1627376D01*
G01Y1624384D02*
Y1623439D01*
G01Y1620447D02*
Y1619502D01*
G01Y1616510D02*
Y1615565D01*
G01Y1612573D02*
Y1611628D01*
G01X14579Y1612770D02*
X15464Y1612573D01*
G01X15962D02*
X15077Y1612770D01*
G01X14579Y1616707D02*
X15464Y1616510D01*
G01X15962D02*
X15077Y1616707D01*
G01X14579Y1620644D02*
X15464Y1620447D01*
G01X15962D02*
X15077Y1620644D01*
G01X14579Y1624581D02*
X15464Y1624384D01*
G01X15962D02*
X15077Y1624581D01*
G01X14579Y1628518D02*
X15464Y1628321D01*
G01X15962D02*
X15077Y1628518D01*
G01X15962Y1611628D02*
X15464D01*
G01X15962Y1612573D02*
X15464D01*
G01X12600Y1612770D02*
X15077D01*
G01X15962Y1615565D02*
X15464D01*
G01X15962Y1616510D02*
X15464D01*
G01X12600Y1616707D02*
X15077D01*
G01X15962Y1619502D02*
X15464D01*
G01X15962Y1620447D02*
X15464D01*
G01X12600Y1620644D02*
X15077D01*
G01X15962Y1623439D02*
X15464D01*
G01X15962Y1624384D02*
X15464D01*
G01X12600Y1624581D02*
X15077D01*
G01X15962Y1627376D02*
X15464D01*
G01X15962Y1628321D02*
X15464D01*
G01X12600Y1628518D02*
X15077D01*
G01X15962Y1611628D02*
X15077Y1611431D01*
G01X14579D02*
X15464Y1611628D01*
G01X15962Y1615565D02*
X15077Y1615369D01*
G01X14579D02*
X15464Y1615565D01*
G01X15962Y1619502D02*
X15077Y1619306D01*
G01X14579D02*
X15464Y1619502D01*
G01X15962Y1623439D02*
X15077Y1623243D01*
G01X14579D02*
X15464Y1623439D01*
G01X15962Y1627376D02*
X15077Y1627180D01*
G01X14579D02*
X15464Y1627376D01*
G01X12600Y1640329D02*
Y1638991D01*
G01Y1636392D02*
Y1635054D01*
G01Y1632455D02*
Y1631117D01*
G01X13423Y1640329D02*
Y1638991D01*
G01Y1636392D02*
Y1635054D01*
G01Y1632455D02*
Y1631117D01*
G01X15464Y1640132D02*
Y1639187D01*
G01Y1636195D02*
Y1635250D01*
G01Y1632258D02*
Y1631313D01*
G01X15962Y1640132D02*
Y1639187D01*
G01Y1636195D02*
Y1635250D01*
G01Y1632258D02*
Y1631313D01*
G01X14579Y1632455D02*
X15464Y1632258D01*
G01X15962D02*
X15077Y1632455D01*
G01X14579Y1636392D02*
X15464Y1636195D01*
G01X15962D02*
X15077Y1636392D01*
G01X15962Y1631313D02*
X15464D01*
G01X15962Y1632258D02*
X15464D01*
G01X12600Y1632455D02*
X15077D01*
G01X15962Y1635250D02*
X15464D01*
G01X15962Y1636195D02*
X15464D01*
G01X12600Y1636392D02*
X15077D01*
G01X15962Y1639187D02*
X15464D01*
G01X15962Y1631313D02*
X15077Y1631117D01*
G01X14579D02*
X15464Y1631313D01*
G01X15962Y1635250D02*
X15077Y1635054D01*
G01X14579D02*
X15464Y1635250D01*
G01X15962Y1639187D02*
X15077Y1638991D01*
G01X14579D02*
X15464Y1639187D01*
G01X72638Y1639094D02*
G03I-3740J0D01*
G01X59252Y1638307D02*
X78543D01*
G01X78740Y1638110D02*
X59055D01*
G01Y1637126D02*
X78740D01*
G01X59055Y1635137D02*
X78740D01*
G01X59055Y1633169D02*
X78740D01*
G01X82677Y1629232D02*
X55118D01*
G01X82677Y1642185D02*
Y1629232D01*
G01X78740Y1633169D02*
Y1646122D01*
G01X78543Y1638307D02*
Y1639882D01*
G01X73189D02*
Y1638307D01*
G01X71850D02*
Y1638110D01*
G01Y1639882D02*
Y1638307D01*
G01X71654Y1639882D02*
Y1638307D01*
G01X70079D02*
Y1639882D01*
G01X67717Y1638307D02*
Y1639882D01*
G01X66142Y1638307D02*
Y1639882D01*
G01X65945Y1638307D02*
Y1639882D01*
G01Y1638307D02*
Y1638110D01*
G01X64606Y1638307D02*
Y1639882D01*
G01X59252D02*
Y1638307D01*
G01X59055Y1633169D02*
Y1646122D01*
G01X55118Y1629232D02*
Y1642185D01*
G01X12600Y1648203D02*
Y1646865D01*
G01Y1644266D02*
Y1642928D01*
G01X13423Y1648203D02*
Y1646865D01*
G01Y1644266D02*
Y1642928D01*
G01X15464Y1648006D02*
Y1647061D01*
G01Y1644069D02*
Y1643124D01*
G01X15962Y1648006D02*
Y1647061D01*
G01Y1644069D02*
Y1643124D01*
G01X14579Y1640329D02*
X15464Y1640132D01*
G01X15962D02*
X15077Y1640329D01*
G01X14579Y1644266D02*
X15464Y1644069D01*
G01X15962D02*
X15077Y1644266D01*
G01X14579Y1648203D02*
X15464Y1648006D01*
G01X15962D02*
X15077Y1648203D01*
G01X15962Y1640132D02*
X15464D01*
G01X12600Y1640329D02*
X15077D01*
G01X15962Y1643124D02*
X15464D01*
G01X15962Y1644069D02*
X15464D01*
G01X12600Y1644266D02*
X15077D01*
G01X15962Y1647061D02*
X15464D01*
G01X15962Y1648006D02*
X15464D01*
G01X12600Y1648203D02*
X15077D01*
G01X15962Y1643124D02*
X15077Y1642928D01*
G01X14579D02*
X15464Y1643124D01*
G01X15962Y1647061D02*
X15077Y1646865D01*
G01X14579D02*
X15464Y1647061D01*
G01X12600Y1667888D02*
Y1666550D01*
G01Y1671825D02*
Y1670487D01*
G01Y1663951D02*
Y1662613D01*
G01Y1660014D02*
Y1658676D01*
G01Y1656077D02*
Y1654739D01*
G01Y1652140D02*
Y1650802D01*
G01X13423Y1667888D02*
Y1666550D01*
G01Y1671825D02*
Y1670487D01*
G01Y1663951D02*
Y1662613D01*
G01Y1660014D02*
Y1658676D01*
G01Y1656077D02*
Y1654739D01*
G01Y1652140D02*
Y1650802D01*
G01X15464Y1671628D02*
Y1670683D01*
G01Y1667691D02*
Y1666746D01*
G01Y1663754D02*
Y1662809D01*
G01Y1659817D02*
Y1658872D01*
G01Y1655880D02*
Y1654935D01*
G01Y1651943D02*
Y1650998D01*
G01X15962Y1671628D02*
Y1670683D01*
G01Y1667691D02*
Y1666746D01*
G01Y1663754D02*
Y1662809D01*
G01Y1659817D02*
Y1658872D01*
G01Y1655880D02*
Y1654935D01*
G01Y1651943D02*
Y1650998D01*
G01X14579Y1652140D02*
X15464Y1651943D01*
G01X15962D02*
X15077Y1652140D01*
G01X14579Y1656077D02*
X15464Y1655880D01*
G01X15962D02*
X15077Y1656077D01*
G01X14579Y1660014D02*
X15464Y1659817D01*
G01X15962D02*
X15077Y1660014D01*
G01X14579Y1663951D02*
X15464Y1663754D01*
G01X15962D02*
X15077Y1663951D01*
G01X14579Y1667888D02*
X15464Y1667691D01*
G01X15962D02*
X15077Y1667888D01*
G01X15962Y1650998D02*
X15464D01*
G01X15962Y1651943D02*
X15464D01*
G01X12600Y1652140D02*
X15077D01*
G01X15962Y1654935D02*
X15464D01*
G01X15962Y1655880D02*
X15464D01*
G01X12600Y1656077D02*
X15077D01*
G01X15962Y1658872D02*
X15464D01*
G01X15962Y1659817D02*
X15464D01*
G01X12600Y1660014D02*
X15077D01*
G01X15962Y1662809D02*
X15464D01*
G01X15962Y1663754D02*
X15464D01*
G01X12600Y1663951D02*
X15077D01*
G01X15962Y1666746D02*
X15464D01*
G01X15962Y1667691D02*
X15464D01*
G01X12600Y1667888D02*
X15077D01*
G01X15962Y1670683D02*
X15464D01*
G01X15962Y1650998D02*
X15077Y1650802D01*
G01X14579D02*
X15464Y1650998D01*
G01X15962Y1654935D02*
X15077Y1654739D01*
G01X14579D02*
X15464Y1654935D01*
G01X15962Y1658872D02*
X15077Y1658676D01*
G01X14579D02*
X15464Y1658872D01*
G01X15962Y1662809D02*
X15077Y1662613D01*
G01X14579D02*
X15464Y1662809D01*
G01X15962Y1666746D02*
X15077Y1666550D01*
G01X14579D02*
X15464Y1666746D01*
G01X15962Y1670683D02*
X15077Y1670487D01*
G01X14579D02*
X15464Y1670683D01*
G01X12600Y1683636D02*
Y1682298D01*
G01Y1679699D02*
Y1678361D01*
G01Y1675762D02*
Y1674424D01*
G01X13423Y1683636D02*
Y1682298D01*
G01Y1679699D02*
Y1678361D01*
G01Y1675762D02*
Y1674424D01*
G01X15464Y1683439D02*
Y1682494D01*
G01Y1679502D02*
Y1678557D01*
G01Y1675565D02*
Y1674620D01*
G01X15962Y1683439D02*
Y1682494D01*
G01Y1679502D02*
Y1678557D01*
G01Y1675565D02*
Y1674620D01*
G01X22834Y1714168D02*
Y1688577D01*
G01X24802D02*
Y1714168D01*
G01X14579Y1671825D02*
X15464Y1671628D01*
G01X15962D02*
X15077Y1671825D01*
G01X14579Y1675762D02*
X15464Y1675565D01*
G01X15962D02*
X15077Y1675762D01*
G01X14579Y1679699D02*
X15464Y1679502D01*
G01X15962D02*
X15077Y1679699D01*
G01X14579Y1683636D02*
X15464Y1683439D01*
G01X15962D02*
X15077Y1683636D01*
G01X15962Y1671628D02*
X15464D01*
G01X12600Y1671825D02*
X15077D01*
G01X15962Y1674620D02*
X15464D01*
G01X15962Y1675565D02*
X15464D01*
G01X12600Y1675762D02*
X15077D01*
G01X15962Y1678557D02*
X15464D01*
G01X15962Y1679502D02*
X15464D01*
G01X12600Y1679699D02*
X15077D01*
G01X15962Y1682494D02*
X15464D01*
G01X15962Y1683439D02*
X15464D01*
G01X12600Y1683636D02*
X15077D01*
G01X15962Y1674620D02*
X15077Y1674424D01*
G01X14579D02*
X15464Y1674620D01*
G01X15962Y1678557D02*
X15077Y1678361D01*
G01X14579D02*
X15464Y1678557D01*
G01X15962Y1682494D02*
X15077Y1682298D01*
G01X14579D02*
X15464Y1682494D01*
G01X80167Y1649330D02*
G03Y1652480I-2017J1575D01*
G01X76133D02*
G03Y1649330I2017J-1575D01*
G01X75780Y1653267D02*
G03Y1648543I2370J-2362D01*
G01X80520D02*
G03Y1653267I-2370J2362D01*
G01X81654Y1650905D02*
G03I-3504J0D01*
G01X75472Y1654055D02*
G03Y1647756I2678J-3149D01*
G01X80827D02*
G03Y1654055I-2677J3149D01*
G01X77559Y1719094D02*
X82677Y1720275D01*
G01X70866Y1720570D02*
X69685D01*
G01X38583Y1719094D02*
X69685D01*
G01X77559D02*
X72835D01*
G01X69685Y1718996D02*
X89567D01*
G01X40344D02*
X69685D01*
G01Y1717421D02*
X89567D01*
G01X40344D02*
X69685D01*
G01X72835Y1717322D02*
X77559D01*
G01X38583D02*
X69685D01*
G01Y1715846D02*
X70866D01*
G01X38583Y1714094D02*
X70866D01*
G01X79528D02*
X74803D01*
G01X70866Y1713996D02*
X88110D01*
G01X40344D02*
X70866D01*
G01Y1712421D02*
X88110D01*
G01X40344D02*
X70866D01*
G01X74803Y1712322D02*
X79528D01*
G01X38583D02*
X70866D01*
G01X38583Y1709094D02*
X70866D01*
G01X79528D02*
X74803D01*
G01X70866Y1708996D02*
X88110D01*
G01X40344D02*
X70866D01*
G01Y1707421D02*
X88110D01*
G01X40344D02*
X70866D01*
G01X74803Y1707322D02*
X79528D01*
G01X38583D02*
X70866D01*
G01Y1707086D02*
X77756D01*
G01Y1704330D02*
X70866D01*
G01X38583Y1704094D02*
X70866D01*
G01X79528D02*
X74803D01*
G01X70866Y1703996D02*
X88110D01*
G01X40344D02*
X70866D01*
G01Y1702421D02*
X88110D01*
G01X40344D02*
X70866D01*
G01X74803Y1702322D02*
X79528D01*
G01X38583D02*
X70866D01*
G01X38583Y1699094D02*
X70866D01*
G01X79528D02*
X74803D01*
G01X70866Y1698996D02*
X88110D01*
G01X40344D02*
X70866D01*
G01Y1697421D02*
X88110D01*
G01X40344D02*
X70866D01*
G01X74803Y1697322D02*
X79528D01*
G01X38583D02*
X70866D01*
G01X38583Y1694094D02*
X70866D01*
G01X79528D02*
X74803D01*
G01X70866Y1693996D02*
X88110D01*
G01X40344D02*
X70866D01*
G01Y1692421D02*
X88110D01*
G01X40344D02*
X70866D01*
G01X74803Y1692322D02*
X79528D01*
G01X38583D02*
X70866D01*
G01X77559Y1679094D02*
X82677Y1680275D01*
G01X38583Y1689094D02*
X70866D01*
G01X79528D02*
X74803D01*
G01X70866Y1688996D02*
X88110D01*
G01X40344D02*
X70866D01*
G01Y1687421D02*
X88110D01*
G01X40344D02*
X70866D01*
G01X74803Y1687322D02*
X79528D01*
G01X38583D02*
X70866D01*
G01X38583Y1684094D02*
X70866D01*
G01X79528D02*
X74803D01*
G01X70866Y1683996D02*
X88110D01*
G01X40344D02*
X70866D01*
G01Y1682421D02*
X88110D01*
G01X40344D02*
X70866D01*
G01X74803Y1682322D02*
X79528D01*
G01X38583D02*
X70866D01*
G01Y1682086D02*
X77756D01*
G01X70866Y1680570D02*
X69685D01*
G01X77756Y1679330D02*
X70866D01*
G01X38583Y1679094D02*
X69685D01*
G01X77559D02*
X72835D01*
G01X69685Y1678996D02*
X89567D01*
G01X40344D02*
X69685D01*
G01Y1677421D02*
X89567D01*
G01X40344D02*
X69685D01*
G01X72835Y1677322D02*
X77559D01*
G01X38583D02*
X69685D01*
G01Y1675846D02*
X70866D01*
G01X38583Y1674094D02*
X70866D01*
G01X79528D02*
X74803D01*
G01X70866Y1673996D02*
X88110D01*
G01X40344D02*
X70866D01*
G01Y1672421D02*
X88110D01*
G01X40344D02*
X70866D01*
G01X74803Y1672322D02*
X79528D01*
G01X38583D02*
X70866D01*
G01X38583Y1669094D02*
X70866D01*
G01X79528D02*
X74803D01*
G01X70866Y1668996D02*
X88110D01*
G01X40344D02*
X70866D01*
G01Y1667421D02*
X88110D01*
G01X40344D02*
X70866D01*
G01X74803Y1667322D02*
X79528D01*
G01X38583D02*
X70866D01*
G01X38583Y1664094D02*
X70866D01*
G01X79528D02*
X74803D01*
G01X70866Y1663996D02*
X88110D01*
G01X40344D02*
X70866D01*
G01Y1662421D02*
X88110D01*
G01X40344D02*
X70866D01*
G01X74803Y1662322D02*
X79528D01*
G01X38583D02*
X70866D01*
G01X69587Y1659389D02*
X70866D01*
G01X39764D02*
X68209D01*
G01X90551D02*
X70866D01*
G01Y1657618D02*
X90551D01*
G01X40551Y1654468D02*
X90551D01*
G01X35300D02*
X38583D01*
G01X75472Y1654055D02*
X80827D01*
G01X80520Y1653267D02*
X75780D01*
G01X80167Y1652480D02*
X76133D01*
G01X70079Y1651515D02*
X90551D01*
G01X59055D02*
X70079D01*
G01X80167Y1649330D02*
X76133D01*
G01X75780Y1648543D02*
X80520D01*
G01X80827Y1647756D02*
X75472D01*
G01X70079Y1647303D02*
X36614D01*
G01Y1646122D02*
X90551D01*
G01X59055Y1644153D02*
X78740D01*
G01X82677Y1642185D02*
X94488D01*
G01X55118D02*
X27953D01*
G01X78740Y1641063D02*
X59055D01*
G01Y1640078D02*
X78740D01*
G01X59252Y1639882D02*
X78543D01*
G01X82677Y1716141D02*
X77559Y1717322D01*
G01X82677Y1676141D02*
X77559Y1677322D01*
G01X82677Y1721141D02*
X79528Y1722322D01*
G01X82677Y1711141D02*
X79528Y1712322D01*
G01X82677Y1706141D02*
X79528Y1707322D01*
G01X82677Y1701141D02*
X79528Y1702322D01*
G01X82677Y1696141D02*
X79528Y1697322D01*
G01X82677Y1691141D02*
X79528Y1692322D01*
G01X82677Y1686141D02*
X79528Y1687322D01*
G01X82677Y1681141D02*
X79528Y1682322D01*
G01X82677Y1671141D02*
X79528Y1672322D01*
G01X82677Y1666141D02*
X79528Y1667322D01*
G01X82677Y1661141D02*
X79528Y1662322D01*
G01X38583Y1656437D02*
X40551Y1654468D01*
G01X31890Y1651871D02*
X36610Y1647229D01*
G01X36614Y1646122D02*
X31890Y1650767D01*
G01X94488Y1642185D02*
Y1809232D01*
G01X90551Y1646122D02*
Y1659389D01*
G01X89567Y1678996D02*
Y1677421D01*
G01Y1718996D02*
Y1717421D01*
G01X88110Y1663996D02*
Y1662421D01*
G01Y1668996D02*
Y1667421D01*
G01Y1673996D02*
Y1672421D01*
G01Y1683996D02*
Y1682421D01*
G01Y1688996D02*
Y1687421D01*
G01Y1693996D02*
Y1692421D01*
G01Y1698996D02*
Y1697421D01*
G01Y1703996D02*
Y1702421D01*
G01Y1708996D02*
Y1707421D01*
G01Y1713996D02*
Y1712421D01*
G01X83189Y1717421D02*
Y1718996D01*
G01Y1712421D02*
Y1713996D01*
G01Y1707421D02*
Y1708996D01*
G01Y1702421D02*
Y1703996D01*
G01Y1697421D02*
Y1698996D01*
G01Y1692421D02*
Y1693996D01*
G01Y1687421D02*
Y1688996D01*
G01Y1682421D02*
Y1683996D01*
G01Y1677421D02*
Y1678996D01*
G01Y1672421D02*
Y1673996D01*
G01Y1667421D02*
Y1668996D01*
G01Y1662421D02*
Y1663996D01*
G01X82795D02*
Y1662421D01*
G01Y1668996D02*
Y1667421D01*
G01Y1673996D02*
Y1672421D01*
G01Y1678996D02*
Y1677421D01*
G01Y1683996D02*
Y1682421D01*
G01Y1688996D02*
Y1687421D01*
G01Y1693996D02*
Y1692421D01*
G01Y1698996D02*
Y1697421D01*
G01Y1703996D02*
Y1702421D01*
G01Y1708996D02*
Y1707421D01*
G01Y1713996D02*
Y1712421D01*
G01Y1718996D02*
Y1717421D01*
G01X82677Y1661141D02*
Y1659389D01*
G01Y1666141D02*
Y1665275D01*
G01Y1671141D02*
Y1670275D01*
G01Y1676141D02*
Y1675275D01*
G01Y1681141D02*
Y1680275D01*
G01Y1686141D02*
Y1685275D01*
G01Y1691141D02*
Y1690275D01*
G01Y1696141D02*
Y1695275D01*
G01Y1701141D02*
Y1700275D01*
G01Y1706141D02*
Y1705275D01*
G01Y1711141D02*
Y1710275D01*
G01Y1716141D02*
Y1715275D01*
G01Y1721141D02*
Y1720275D01*
G01X82008Y1663996D02*
Y1662421D01*
G01Y1668996D02*
Y1667421D01*
G01Y1673996D02*
Y1672421D01*
G01Y1678996D02*
Y1677421D01*
G01Y1683996D02*
Y1682421D01*
G01Y1688996D02*
Y1687421D01*
G01Y1693996D02*
Y1692421D01*
G01Y1698996D02*
Y1697421D01*
G01Y1703996D02*
Y1702421D01*
G01Y1708996D02*
Y1707421D01*
G01Y1713996D02*
Y1712421D01*
G01Y1718996D02*
Y1717421D01*
G01X80433Y1663996D02*
Y1662421D01*
G01Y1668996D02*
Y1667421D01*
G01Y1673996D02*
Y1672421D01*
G01Y1678996D02*
Y1677421D01*
G01Y1683996D02*
Y1682421D01*
G01Y1688996D02*
Y1687421D01*
G01Y1693996D02*
Y1692421D01*
G01Y1698996D02*
Y1697421D01*
G01Y1703996D02*
Y1702421D01*
G01Y1708996D02*
Y1707421D01*
G01Y1713996D02*
Y1712421D01*
G01Y1718996D02*
Y1717421D01*
G01X77756Y1704330D02*
Y1707086D01*
G01Y1679330D02*
Y1682086D01*
G01X74803Y1662421D02*
Y1662322D01*
G01Y1664094D02*
Y1663996D01*
G01Y1667421D02*
Y1667322D01*
G01Y1663996D02*
Y1662421D01*
G01Y1669094D02*
Y1668996D01*
G01Y1672421D02*
Y1672322D01*
G01Y1668996D02*
Y1667421D01*
G01Y1674094D02*
Y1673996D01*
G01D02*
Y1672421D01*
G01Y1682421D02*
Y1682322D01*
G01Y1684094D02*
Y1683996D01*
G01D02*
Y1682421D01*
G01Y1687421D02*
Y1687322D01*
G01Y1689094D02*
Y1688996D01*
G01D02*
Y1687421D01*
G01Y1692421D02*
Y1692322D01*
G01Y1694094D02*
Y1693996D01*
G01D02*
Y1692421D01*
G01Y1697421D02*
Y1697322D01*
G01Y1699094D02*
Y1698996D01*
G01D02*
Y1697421D01*
G01Y1702421D02*
Y1702322D01*
G01Y1704094D02*
Y1703996D01*
G01D02*
Y1702421D01*
G01Y1707421D02*
Y1707322D01*
G01Y1709094D02*
Y1708996D01*
G01D02*
Y1707421D01*
G01Y1712421D02*
Y1712322D01*
G01Y1714094D02*
Y1713996D01*
G01D02*
Y1712421D01*
G01X72835Y1677421D02*
Y1677322D01*
G01Y1679094D02*
Y1678996D01*
G01D02*
Y1677421D01*
G01Y1717421D02*
Y1717322D01*
G01Y1719094D02*
Y1718996D01*
G01D02*
Y1717421D01*
G01X71850Y1639882D02*
Y1640078D01*
G01X70866Y1717421D02*
Y1718996D01*
G01D02*
Y1735669D01*
G01Y1677421D02*
Y1678996D01*
G01D02*
Y1717421D01*
G01Y1657618D02*
Y1677421D01*
G01X70079Y1646122D02*
Y1654468D01*
G01X69685Y1680570D02*
Y1675846D01*
G01Y1720570D02*
Y1715846D01*
G01X69587Y1659389D02*
Y1792027D01*
G01X68209D02*
Y1659389D01*
G01X66929D02*
Y1792027D01*
G01X65945Y1640078D02*
Y1639882D01*
G01X59055Y1646122D02*
Y1805295D01*
G01X46553Y1663996D02*
Y1662421D01*
G01Y1668996D02*
Y1667421D01*
G01Y1673996D02*
Y1672421D01*
G01Y1678996D02*
Y1677421D01*
G01Y1683996D02*
Y1682421D01*
G01Y1688996D02*
Y1687421D01*
G01Y1693996D02*
Y1692421D01*
G01Y1698996D02*
Y1697421D01*
G01Y1703996D02*
Y1702421D01*
G01Y1708996D02*
Y1707421D01*
G01Y1713996D02*
Y1712421D01*
G01Y1718996D02*
Y1717421D01*
G01X45447Y1663996D02*
Y1662421D01*
G01Y1668996D02*
Y1667421D01*
G01Y1673996D02*
Y1672421D01*
G01Y1678996D02*
Y1677421D01*
G01Y1683996D02*
Y1682421D01*
G01Y1688996D02*
Y1687421D01*
G01Y1693996D02*
Y1692421D01*
G01Y1698996D02*
Y1697421D01*
G01Y1703996D02*
Y1702421D01*
G01Y1708996D02*
Y1707421D01*
G01Y1713996D02*
Y1712421D01*
G01Y1718996D02*
Y1717421D01*
G01X45201Y1663996D02*
Y1662421D01*
G01Y1668996D02*
Y1667421D01*
G01Y1673996D02*
Y1672421D01*
G01Y1678996D02*
Y1677421D01*
G01Y1683996D02*
Y1682421D01*
G01Y1688996D02*
Y1687421D01*
G01Y1693996D02*
Y1692421D01*
G01Y1698996D02*
Y1697421D01*
G01Y1703996D02*
Y1702421D01*
G01Y1708996D02*
Y1707421D01*
G01Y1713996D02*
Y1712421D01*
G01Y1718996D02*
Y1717421D01*
G01X41535Y1664094D02*
Y1662322D01*
G01Y1669094D02*
Y1667322D01*
G01Y1674094D02*
Y1672322D01*
G01Y1679094D02*
Y1677322D01*
G01Y1684094D02*
Y1682322D01*
G01Y1689094D02*
Y1687322D01*
G01Y1694094D02*
Y1692322D01*
G01Y1699094D02*
Y1697322D01*
G01Y1704094D02*
Y1702322D01*
G01Y1709094D02*
Y1707322D01*
G01Y1714094D02*
Y1712322D01*
G01Y1719094D02*
Y1717322D01*
G01X41026Y1717421D02*
Y1718996D01*
G01Y1712421D02*
Y1713996D01*
G01Y1707421D02*
Y1708996D01*
G01Y1702421D02*
Y1703996D01*
G01Y1697421D02*
Y1698996D01*
G01Y1692421D02*
Y1693996D01*
G01Y1687421D02*
Y1688996D01*
G01Y1682421D02*
Y1683996D01*
G01Y1677421D02*
Y1678996D01*
G01Y1672421D02*
Y1673996D01*
G01Y1667421D02*
Y1668996D01*
G01Y1662421D02*
Y1663996D01*
G01X40344D02*
Y1662421D01*
G01Y1668996D02*
Y1667421D01*
G01Y1673996D02*
Y1672421D01*
G01Y1678996D02*
Y1677421D01*
G01Y1683996D02*
Y1682421D01*
G01Y1688996D02*
Y1687421D01*
G01Y1693996D02*
Y1692421D01*
G01Y1698996D02*
Y1697421D01*
G01Y1703996D02*
Y1702421D01*
G01Y1708996D02*
Y1707421D01*
G01Y1713996D02*
Y1712421D01*
G01Y1718996D02*
Y1717421D01*
G01X39764Y1659389D02*
Y1792027D01*
G01X38583Y1654468D02*
Y1796948D01*
G01X36614Y1647303D02*
Y1654468D01*
G01X31890Y1650767D02*
Y1652500D01*
G01X27953Y1809232D02*
Y1642185D01*
G01X79528Y1664094D02*
X82677Y1665275D01*
G01X79528Y1669094D02*
X82677Y1670275D01*
G01X79528Y1674094D02*
X82677Y1675275D01*
G01X79528Y1684094D02*
X82677Y1685275D01*
G01X79528Y1689094D02*
X82677Y1690275D01*
G01X79528Y1694094D02*
X82677Y1695275D01*
G01X79528Y1699094D02*
X82677Y1700275D01*
G01X79528Y1704094D02*
X82677Y1705275D01*
G01X79528Y1709094D02*
X82677Y1710275D01*
G01X79528Y1714094D02*
X82677Y1715275D01*
G01X35300Y1654468D02*
X31890Y1652500D01*
G01X39764Y1659389D02*
X38583Y1658208D01*
G01X22851Y1760244D02*
Y1734654D01*
G01X24802Y1760244D02*
Y1734654D01*
G01X26771Y1873630D02*
Y1732685D01*
G01X12829Y1768910D02*
Y1770248D01*
G01Y1764973D02*
Y1766311D01*
G01X13613D02*
Y1764973D01*
G01Y1770248D02*
Y1768910D01*
G01X15464Y1770052D02*
Y1769107D01*
G01Y1766115D02*
Y1765170D01*
G01X16248D02*
Y1766115D01*
G01Y1769107D02*
Y1770052D01*
G01X14688Y1766311D02*
X15464Y1766115D01*
G01X16248D02*
X15472Y1766311D01*
G01X14688Y1770248D02*
X15464Y1770052D01*
G01X16248D02*
X15472Y1770248D01*
G01Y1764973D02*
X12829D01*
G01X16248Y1765170D02*
X15464D01*
G01X16248Y1766115D02*
X15464D01*
G01X15472Y1766311D02*
X12829D01*
G01X15472Y1768910D02*
X12829D01*
G01X16248Y1769107D02*
X15464D01*
G01X16248Y1770052D02*
X15464D01*
G01X15472Y1770248D02*
X12829D01*
G01X15472Y1764973D02*
X16248Y1765170D01*
G01X15464D02*
X14688Y1764973D01*
G01X15472Y1768910D02*
X16248Y1769107D01*
G01X15464D02*
X14688Y1768910D01*
G01X12829Y1772847D02*
Y1774185D01*
G01Y1776784D02*
Y1778122D01*
G01Y1780721D02*
Y1782059D01*
G01Y1784658D02*
Y1785996D01*
G01Y1788595D02*
Y1789933D01*
G01X13613D02*
Y1788595D01*
G01Y1785996D02*
Y1784658D01*
G01Y1782059D02*
Y1780721D01*
G01Y1778122D02*
Y1776784D01*
G01Y1774185D02*
Y1772847D01*
G01X15464Y1789737D02*
Y1788792D01*
G01Y1785800D02*
Y1784855D01*
G01Y1781863D02*
Y1780918D01*
G01Y1777926D02*
Y1776981D01*
G01Y1773989D02*
Y1773044D01*
G01X16248D02*
Y1773989D01*
G01Y1776981D02*
Y1777926D01*
G01Y1780918D02*
Y1781863D01*
G01Y1784855D02*
Y1785800D01*
G01Y1788792D02*
Y1789737D01*
G01X14688Y1774185D02*
X15464Y1773989D01*
G01X16248D02*
X15472Y1774185D01*
G01X14688Y1778122D02*
X15464Y1777926D01*
G01X16248D02*
X15472Y1778122D01*
G01X14688Y1782059D02*
X15464Y1781863D01*
G01X16248D02*
X15472Y1782059D01*
G01X14688Y1785996D02*
X15464Y1785800D01*
G01X16248D02*
X15472Y1785996D01*
G01X14688Y1789933D02*
X15464Y1789737D01*
G01X16248D02*
X15472Y1789933D01*
G01Y1772847D02*
X12829D01*
G01X16248Y1773044D02*
X15464D01*
G01X16248Y1773989D02*
X15464D01*
G01X15472Y1774185D02*
X12829D01*
G01X15472Y1776784D02*
X12829D01*
G01X16248Y1776981D02*
X15464D01*
G01X16248Y1777926D02*
X15464D01*
G01X15472Y1778122D02*
X12829D01*
G01X15472Y1780721D02*
X12829D01*
G01X16248Y1780918D02*
X15464D01*
G01X16248Y1781863D02*
X15464D01*
G01X15472Y1782059D02*
X12829D01*
G01X15472Y1784658D02*
X12829D01*
G01X16248Y1784855D02*
X15464D01*
G01X16248Y1785800D02*
X15464D01*
G01X15472Y1785996D02*
X12829D01*
G01X15472Y1788595D02*
X12829D01*
G01X16248Y1788792D02*
X15464D01*
G01X16248Y1789737D02*
X15464D01*
G01X15472Y1789933D02*
X12829D01*
G01X15472Y1772847D02*
X16248Y1773044D01*
G01X15464D02*
X14688Y1772847D01*
G01X15472Y1776784D02*
X16248Y1776981D01*
G01X15464D02*
X14688Y1776784D01*
G01X15472Y1780721D02*
X16248Y1780918D01*
G01X15464D02*
X14688Y1780721D01*
G01X15472Y1784658D02*
X16248Y1784855D01*
G01X15464D02*
X14688Y1784658D01*
G01X15472Y1788595D02*
X16248Y1788792D01*
G01X15464D02*
X14688Y1788595D01*
G01X12829Y1792532D02*
Y1793870D01*
G01Y1796469D02*
Y1797807D01*
G01Y1800406D02*
Y1801744D01*
G01Y1804343D02*
Y1805681D01*
G01X13613D02*
Y1804343D01*
G01Y1801744D02*
Y1800406D01*
G01Y1797807D02*
Y1796469D01*
G01Y1793870D02*
Y1792532D01*
G01X15464Y1805485D02*
Y1804540D01*
G01Y1801548D02*
Y1800603D01*
G01Y1797611D02*
Y1796666D01*
G01Y1793674D02*
Y1792729D01*
G01X16248D02*
Y1793674D01*
G01Y1796666D02*
Y1797611D01*
G01Y1800603D02*
Y1801548D01*
G01Y1804540D02*
Y1805485D01*
G01X14688Y1793870D02*
X15464Y1793674D01*
G01X16248D02*
X15472Y1793870D01*
G01X14688Y1797807D02*
X15464Y1797611D01*
G01X16248D02*
X15472Y1797807D01*
G01X14688Y1801744D02*
X15464Y1801548D01*
G01X16248D02*
X15472Y1801744D01*
G01Y1792532D02*
X12829D01*
G01X16248Y1792729D02*
X15464D01*
G01X16248Y1793674D02*
X15464D01*
G01X15472Y1793870D02*
X12829D01*
G01X15472Y1796469D02*
X12829D01*
G01X16248Y1796666D02*
X15464D01*
G01X16248Y1797611D02*
X15464D01*
G01X15472Y1797807D02*
X12829D01*
G01X15472Y1800406D02*
X12829D01*
G01X16248Y1800603D02*
X15464D01*
G01X16248Y1801548D02*
X15464D01*
G01X15472Y1801744D02*
X12829D01*
G01X15472Y1804343D02*
X12829D01*
G01X16248Y1804540D02*
X15464D01*
G01X15472Y1792532D02*
X16248Y1792729D01*
G01X15464D02*
X14688Y1792532D01*
G01X15472Y1796469D02*
X16248Y1796666D01*
G01X15464D02*
X14688Y1796469D01*
G01X15472Y1800406D02*
X16248Y1800603D01*
G01X15464D02*
X14688Y1800406D01*
G01X15472Y1804343D02*
X16248Y1804540D01*
G01X15464D02*
X14688Y1804343D01*
G01X78224Y1796378D02*
X78150D01*
G01X78075Y1804645D02*
X78150D01*
G01X80709Y1800511D02*
G03I-2559J0D01*
G01X81496D02*
G03I-3346J0D01*
G01X81654D02*
G03I-3504J0D01*
G01X78075Y1804645D02*
G03X78150Y1796378I74J-4133D01*
G01X78224D02*
G03X78150Y1804645I-73J4133D01*
G01X85589Y1789042D02*
X85723Y1789074D01*
G01X36614Y1804114D02*
X70079D01*
G01Y1799901D02*
X59055D01*
G01X90551D02*
X70079D01*
G01X35300Y1796948D02*
X38583D01*
G01X90551D02*
X40551D01*
G01X90551Y1793799D02*
X70866D01*
G01Y1792027D02*
X90551D01*
G01X69587D02*
X70866D01*
G01X68209D02*
X39764D01*
G01X38583Y1789094D02*
X70866D01*
G01X79528D02*
X74803D01*
G01X85723Y1789074D02*
X85857D01*
G01X70866Y1788996D02*
X88110D01*
G01X40344D02*
X70866D01*
G01X85824Y1788878D02*
X85757D01*
G01X86427Y1788156D02*
X86527D01*
G01X86561Y1787959D02*
X86393D01*
G01X85857Y1787696D02*
X85589D01*
G01X86929Y1787500D02*
X85622D01*
G01X70866Y1787421D02*
X88110D01*
G01X40344D02*
X70866D01*
G01X74803Y1787322D02*
X79528D01*
G01X38583D02*
X70866D01*
G01X85354Y1787303D02*
X86929D01*
G01X38583Y1784094D02*
X70866D01*
G01X79528D02*
X74803D01*
G01X70866Y1783996D02*
X88110D01*
G01X40344D02*
X70866D01*
G01Y1782421D02*
X88110D01*
G01X40344D02*
X70866D01*
G01X74803Y1782322D02*
X79528D01*
G01X38583D02*
X70866D01*
G01X38583Y1779094D02*
X70866D01*
G01X79528D02*
X74803D01*
G01X70866Y1778996D02*
X88110D01*
G01X40344D02*
X70866D01*
G01Y1777421D02*
X88110D01*
G01X40344D02*
X70866D01*
G01X74803Y1777322D02*
X79528D01*
G01X38583D02*
X70866D01*
G01X38583Y1774094D02*
X70866D01*
G01X79528D02*
X74803D01*
G01X70866Y1773996D02*
X88110D01*
G01X40344D02*
X70866D01*
G01Y1772421D02*
X88110D01*
G01X40344D02*
X70866D01*
G01X74803Y1772322D02*
X79528D01*
G01X38583D02*
X70866D01*
G01X38583Y1769094D02*
X70866D01*
G01X79528D02*
X74803D01*
G01X70866Y1768996D02*
X88110D01*
G01X40344D02*
X70866D01*
G01X78306Y1756325D02*
X78440Y1756358D01*
G01X70866Y1767421D02*
X88110D01*
G01X40344D02*
X70866D01*
G01X74803Y1767322D02*
X79528D01*
G01X38583D02*
X70866D01*
G01Y1767086D02*
X77756D01*
G01Y1764330D02*
X70866D01*
G01X38583Y1764094D02*
X70866D01*
G01X79528D02*
X74803D01*
G01X70866Y1763996D02*
X88110D01*
G01X40344D02*
X70866D01*
G01Y1762421D02*
X88110D01*
G01X40344D02*
X70866D01*
G01X74803Y1762322D02*
X79528D01*
G01X38583D02*
X70866D01*
G01X41535Y1759094D02*
X70866D01*
G01X79528D02*
X74803D01*
G01X70866Y1758996D02*
X88110D01*
G01X40465D02*
X70866D01*
G01X38583Y1757913D02*
X70866D01*
G01Y1757421D02*
X88110D01*
G01X40465D02*
X70866D01*
G01X74803Y1757322D02*
X78937D01*
G01X41535D02*
X70866D01*
G01X78937Y1756732D02*
X75591D01*
G01X78440Y1756358D02*
X78574D01*
G01X78540Y1756161D02*
X78473D01*
G01X38780Y1755846D02*
X68110D01*
G01X38780D02*
X38583D01*
G01X73228D02*
X70866D01*
G01X68110Y1755748D02*
X80118D01*
G01X42006D02*
X68110D01*
G01X40551Y1755472D02*
X59055D01*
G01X79143Y1755439D02*
X79244D01*
G01X79277Y1755243D02*
X79110D01*
G01X79143Y1754980D02*
X79244D01*
G01X78473Y1754947D02*
X78574D01*
G01X79143Y1754816D02*
X79244D01*
G01X78473Y1754783D02*
X78540D01*
G01X68110Y1754567D02*
X80118D01*
G01X68110D02*
X42006D01*
G01X38780Y1754468D02*
X68110D01*
G01X38583D02*
X38780D01*
G01X73228D02*
X70866D01*
G01X78540Y1753996D02*
X78473D01*
G01X79244Y1753963D02*
X79143D01*
G01X78574Y1753832D02*
X78473D01*
G01X79244Y1753799D02*
X79143D01*
G01X38780Y1752696D02*
X68110D01*
G01X38780D02*
X38583D01*
G01X73228D02*
X70866D01*
G01X68110Y1752598D02*
X80118D01*
G01X42006D02*
X68110D01*
G01Y1751417D02*
X80118D01*
G01X68110D02*
X42006D01*
G01X38780Y1751319D02*
X68110D01*
G01X38583D02*
X38780D01*
G01X73228D02*
X70866D01*
G01X38780Y1749547D02*
X68110D01*
G01X38780D02*
X38583D01*
G01X73228D02*
X70866D01*
G01X68110Y1749448D02*
X80118D01*
G01X42006D02*
X68110D01*
G01Y1748267D02*
X80118D01*
G01X68110D02*
X42006D01*
G01X38780Y1748169D02*
X68110D01*
G01X38583D02*
X38780D01*
G01X73228D02*
X70866D01*
G01X38780Y1746397D02*
X68110D01*
G01X38780D02*
X38583D01*
G01X73228D02*
X70866D01*
G01X68110Y1746299D02*
X80118D01*
G01X42006D02*
X68110D01*
G01Y1745118D02*
X80118D01*
G01X68110D02*
X42006D01*
G01X38780Y1745019D02*
X68110D01*
G01X38583D02*
X38780D01*
G01X73228D02*
X70866D01*
G01X38780Y1743248D02*
X68110D01*
G01X38780D02*
X38583D01*
G01X73228D02*
X70866D01*
G01X68110Y1743149D02*
X80118D01*
G01X42006D02*
X68110D01*
G01Y1741968D02*
X80118D01*
G01X68110D02*
X42006D01*
G01X38780Y1741870D02*
X68110D01*
G01X38583D02*
X38780D01*
G01X73228D02*
X70866D01*
G01X38780Y1740098D02*
X68110D01*
G01X38780D02*
X38583D01*
G01X73228D02*
X70866D01*
G01X68110Y1740000D02*
X80118D01*
G01X42006D02*
X68110D01*
G01Y1738819D02*
X80118D01*
G01X68110D02*
X42006D01*
G01X38780Y1738720D02*
X68110D01*
G01X38583D02*
X38780D01*
G01X73228D02*
X70866D01*
G01X38780Y1736948D02*
X38583D01*
G01X68110D02*
X38780D01*
G01X73228D02*
X70866D01*
G01X68110Y1736850D02*
X80118D01*
G01X42006D02*
X68110D01*
G01X59055Y1735945D02*
X40551D01*
G01X68110Y1735669D02*
X80118D01*
G01X68110D02*
X42006D01*
G01X38583Y1735570D02*
X38780D01*
G01X68110D02*
X38780D01*
G01X73228D02*
X70866D01*
G01X75591Y1734685D02*
X78937D01*
G01X86890Y1734133D02*
X85315D01*
G01X70866Y1734094D02*
X41535D01*
G01X78937D02*
X74803D01*
G01X70866Y1733996D02*
X89567D01*
G01X40465D02*
X70866D01*
G01X85483Y1733937D02*
X85985D01*
G01X86186D02*
X86890D01*
G01X38583Y1733504D02*
X70866D01*
G01X85784Y1733117D02*
X85684D01*
G01Y1732920D02*
X85818D01*
G01Y1732657D02*
X85550D01*
G01X86890Y1732460D02*
X85583D01*
G01X70866Y1732421D02*
X89567D01*
G01X40465D02*
X70866D01*
G01X74803Y1732322D02*
X79528D01*
G01X41535D02*
X70866D01*
G01X85315Y1732263D02*
X86890D01*
G01X70866Y1732086D02*
X77756D01*
G01Y1729330D02*
X70866D01*
G01X38583Y1729094D02*
X70866D01*
G01X79528D02*
X74803D01*
G01X70866Y1728996D02*
X88110D01*
G01X40344D02*
X70866D01*
G01Y1727421D02*
X88110D01*
G01X40344D02*
X70866D01*
G01X74803Y1727322D02*
X79528D01*
G01X38583D02*
X70866D01*
G01X38583Y1724094D02*
X70866D01*
G01X79528D02*
X74803D01*
G01X70866Y1723996D02*
X88110D01*
G01X40344D02*
X70866D01*
G01Y1722421D02*
X88110D01*
G01X40344D02*
X70866D01*
G01X74803Y1722322D02*
X79528D01*
G01X38583D02*
X70866D01*
G01X86494Y1789173D02*
X86628Y1789140D01*
G01X85857Y1789074D02*
X85991Y1789042D01*
G01X79210Y1756456D02*
X79344Y1756424D01*
G01X78574Y1756358D02*
X78708Y1756325D01*
G01X79244Y1754980D02*
X79411Y1754914D01*
G01X79143Y1753799D02*
X78976Y1753865D01*
G01X78473Y1753832D02*
X78306Y1753897D01*
G01X82677Y1786141D02*
X79528Y1787322D01*
G01X82677Y1781141D02*
X79528Y1782322D01*
G01X82677Y1776141D02*
X79528Y1777322D01*
G01X82677Y1771141D02*
X79528Y1772322D01*
G01X82677Y1766141D02*
X79528Y1767322D01*
G01X82677Y1761141D02*
X79528Y1762322D01*
G01X86594Y1788943D02*
X86494Y1788976D01*
G01X85924Y1788845D02*
X85824Y1788878D01*
G01X85723Y1788058D02*
X85622Y1788090D01*
G01X79311Y1756227D02*
X79210Y1756259D01*
G01X78641Y1756128D02*
X78540Y1756161D01*
G01X78440Y1755341D02*
X78339Y1755374D01*
G01X85684Y1733117D02*
X85583Y1733149D01*
G01Y1732952D02*
X85684Y1732920D01*
G01X75591Y1753779D02*
X73228Y1754468D01*
G01X75591Y1750630D02*
X73228Y1751319D01*
G01X75591Y1747480D02*
X73228Y1748169D01*
G01X75591Y1744330D02*
X73228Y1745019D01*
G01X75591Y1741181D02*
X73228Y1741870D01*
G01X75591Y1738031D02*
X73228Y1738720D01*
G01X75591Y1734882D02*
X73228Y1735570D01*
G01X86393Y1787959D02*
X86259Y1788024D01*
G01X85656Y1788287D02*
X85723Y1788254D01*
G01X79110Y1755243D02*
X78976Y1755308D01*
G01X78372Y1755570D02*
X78440Y1755538D01*
G01X78574Y1754947D02*
X78708Y1754882D01*
G01X82677Y1731141D02*
X79528Y1732322D01*
G01X82677Y1726141D02*
X79528Y1727322D01*
G01X86326Y1788221D02*
X86427Y1788156D01*
G01X79043Y1755505D02*
X79143Y1755439D01*
G01X78540Y1754783D02*
X78641Y1754717D01*
G01X78473Y1753996D02*
X78372Y1754061D01*
G01X86628Y1789140D02*
X86795Y1789042D01*
G01X79344Y1756424D02*
X79512Y1756325D01*
G01X31890Y1798917D02*
X35300Y1796948D01*
G01X85622Y1788090D02*
X85489Y1788189D01*
G01X79244Y1754816D02*
X79378Y1754717D01*
G01X78339Y1755374D02*
X78205Y1755472D01*
G01X79143Y1753963D02*
X79009Y1754061D01*
G01X85449Y1733051D02*
X85583Y1732952D01*
G01X86695Y1788845D02*
X86594Y1788943D01*
G01X85991Y1789042D02*
X86038Y1788996D01*
G01D02*
X86125Y1788910D01*
G01X86259Y1788024D02*
X86125Y1788156D01*
G01X85589Y1788353D02*
X85656Y1788287D01*
G01X39764Y1792027D02*
X38583Y1793208D01*
G01X40551Y1755472D02*
X38583Y1757441D01*
G01X79411Y1756128D02*
X79311Y1756227D01*
G01X78708Y1756325D02*
X78842Y1756194D01*
G01X79411Y1754914D02*
X79512Y1754816D01*
G01X78976Y1755308D02*
X78842Y1755439D01*
G01X78306Y1755636D02*
X78372Y1755570D01*
G01X78708Y1754882D02*
X78808Y1754783D01*
G01X78306Y1753897D02*
X78205Y1753996D01*
G01X85583Y1733149D02*
X85516Y1733215D01*
G01X85991Y1788746D02*
X85924Y1788845D01*
G01X86259Y1788320D02*
X86326Y1788221D01*
G01X85489Y1788189D02*
X85388Y1788320D01*
G01X78205Y1755472D02*
X78104Y1755603D01*
G01X78641Y1754717D02*
X78741Y1754586D01*
G01X78976Y1753865D02*
X78875Y1753996D01*
G01X78372Y1754061D02*
X78272Y1754193D01*
G01X85348Y1733182D02*
X85449Y1733051D01*
G01X86795Y1789042D02*
X86823Y1788996D01*
G01D02*
X86896Y1788878D01*
G01X79512Y1756325D02*
X79612Y1756161D01*
G01X79512Y1754816D02*
X79612Y1754652D01*
G01X78205Y1753996D02*
X78104Y1754160D01*
G01X78708Y1756030D02*
X78641Y1756128D01*
G01X78976Y1755603D02*
X79043Y1755505D01*
G01X86125Y1788910D02*
X86192Y1788779D01*
G01X86125Y1788156D02*
X86058Y1788287D01*
G01X78842Y1756194D02*
X78909Y1756063D01*
G01X79378Y1754717D02*
X79445Y1754586D01*
G01X78842Y1755439D02*
X78775Y1755570D01*
G01X78808Y1754783D02*
X78842Y1754717D01*
G01X79009Y1754061D02*
X78942Y1754193D01*
G01X78875Y1753996D02*
X78842Y1754061D01*
G01X86024Y1788648D02*
X85991Y1788746D01*
G01X85556Y1788451D02*
X85589Y1788353D01*
G01X78741Y1755932D02*
X78708Y1756030D01*
G01X78272Y1755735D02*
X78306Y1755636D01*
G01X85516Y1733215D02*
X85483Y1733313D01*
G01X86896Y1788878D02*
X86929Y1788713D01*
G01X86058Y1788287D02*
X86024Y1788451D01*
G01X85388Y1788320D02*
X85354Y1788484D01*
G01X85315Y1733346D02*
X85348Y1733182D01*
G01X79612Y1756161D02*
X79646Y1755997D01*
G01X79630Y1754567D02*
X79646Y1754488D01*
G01X79612Y1754652D02*
X79630Y1754567D01*
G01X78775Y1755570D02*
X78741Y1755735D01*
G01X78075Y1755748D02*
X78071Y1755767D01*
G01X78104Y1755603D02*
X78075Y1755748D01*
G01X78104Y1754160D02*
X78071Y1754324D01*
G01X86728Y1788713D02*
X86695Y1788845D01*
G01X86192Y1788779D02*
X86226Y1788648D01*
G01Y1788451D02*
X86259Y1788320D01*
G01X79445Y1755997D02*
X79411Y1756128D01*
G01X79450Y1754567D02*
X79478Y1754455D01*
G01X79445Y1754586D02*
X79450Y1754567D01*
G01X78909Y1756063D02*
X78942Y1755932D01*
G01Y1755735D02*
X78976Y1755603D01*
G01X78942Y1754193D02*
X78909Y1754324D01*
G01X78746Y1754567D02*
X78775Y1754455D01*
G01X78741Y1754586D02*
X78746Y1754567D01*
G01X78272Y1754193D02*
X78239Y1754324D01*
G01X90551Y1792027D02*
Y1805295D01*
G01X89567Y1733996D02*
Y1732421D01*
G01X88110Y1723996D02*
Y1722421D01*
G01Y1728996D02*
Y1727421D01*
G01Y1758996D02*
Y1757421D01*
G01Y1763996D02*
Y1762421D01*
G01Y1768996D02*
Y1767421D01*
G01Y1773996D02*
Y1772421D01*
G01Y1778996D02*
Y1777421D01*
G01Y1783996D02*
Y1782421D01*
G01Y1788996D02*
Y1787421D01*
G01X86929Y1787303D02*
Y1787421D01*
G01D02*
Y1787500D01*
G01Y1788713D02*
Y1788451D01*
G01X86890Y1733996D02*
Y1734133D01*
G01Y1733937D02*
Y1733996D01*
G01Y1732263D02*
Y1732421D01*
G01D02*
Y1732460D01*
G01X86728Y1788451D02*
Y1788713D01*
G01X86494Y1788996D02*
Y1789173D01*
G01Y1788976D02*
Y1788996D01*
G01X86226Y1788648D02*
Y1788451D01*
G01X86186Y1733346D02*
Y1733937D01*
G01X86024Y1788451D02*
Y1788648D01*
G01X85985Y1733937D02*
Y1733313D01*
G01X85723Y1788254D02*
Y1788058D01*
G01X85556Y1788648D02*
Y1788451D01*
G01X85483Y1733313D02*
Y1733937D01*
G01X85354Y1788484D02*
Y1788648D01*
G01Y1787421D02*
Y1787303D01*
G01Y1787500D02*
Y1787421D01*
G01X85315Y1732421D02*
Y1732263D01*
G01Y1732460D02*
Y1732421D01*
G01Y1734133D02*
Y1733996D01*
G01D02*
Y1733346D01*
G01X83189Y1787421D02*
Y1788996D01*
G01Y1782421D02*
Y1783996D01*
G01Y1777421D02*
Y1778996D01*
G01Y1772421D02*
Y1773996D01*
G01Y1767421D02*
Y1768996D01*
G01Y1762421D02*
Y1763996D01*
G01Y1757421D02*
Y1758996D01*
G01Y1732421D02*
Y1733996D01*
G01Y1727421D02*
Y1728996D01*
G01Y1722421D02*
Y1723996D01*
G01X82795D02*
Y1722421D01*
G01Y1728996D02*
Y1727421D01*
G01Y1733996D02*
Y1732421D01*
G01Y1758996D02*
Y1757421D01*
G01Y1763996D02*
Y1762421D01*
G01Y1768996D02*
Y1767421D01*
G01Y1773996D02*
Y1772421D01*
G01Y1778996D02*
Y1777421D01*
G01Y1783996D02*
Y1782421D01*
G01Y1788996D02*
Y1787421D01*
G01X82677Y1726141D02*
Y1725275D01*
G01Y1731141D02*
Y1730275D01*
G01Y1761141D02*
Y1760275D01*
G01Y1766141D02*
Y1765275D01*
G01Y1771141D02*
Y1770275D01*
G01Y1776141D02*
Y1775275D01*
G01Y1781141D02*
Y1780275D01*
G01Y1786141D02*
Y1785275D01*
G01Y1792027D02*
Y1790275D01*
G01X82008Y1723996D02*
Y1722421D01*
G01Y1728996D02*
Y1727421D01*
G01Y1733996D02*
Y1732421D01*
G01Y1758996D02*
Y1757421D01*
G01Y1763996D02*
Y1762421D01*
G01Y1768996D02*
Y1767421D01*
G01Y1773996D02*
Y1772421D01*
G01Y1778996D02*
Y1777421D01*
G01Y1783996D02*
Y1782421D01*
G01Y1788996D02*
Y1787421D01*
G01X80433Y1723996D02*
Y1722421D01*
G01Y1728996D02*
Y1727421D01*
G01Y1733996D02*
Y1732421D01*
G01Y1758996D02*
Y1757421D01*
G01Y1763996D02*
Y1762421D01*
G01Y1768996D02*
Y1767421D01*
G01Y1773996D02*
Y1772421D01*
G01Y1778996D02*
Y1777421D01*
G01Y1783996D02*
Y1782421D01*
G01Y1788996D02*
Y1787421D01*
G01X80118Y1736850D02*
Y1735669D01*
G01Y1740000D02*
Y1738819D01*
G01Y1746299D02*
Y1745118D01*
G01Y1743149D02*
Y1741968D01*
G01Y1749448D02*
Y1748267D01*
G01Y1752598D02*
Y1751417D01*
G01Y1755748D02*
Y1754567D01*
G01X79646Y1755997D02*
Y1755748D01*
G01Y1754488D02*
Y1754291D01*
G01Y1755748D02*
Y1755735D01*
G01X79478Y1754455D02*
Y1754324D01*
G01X79445Y1755748D02*
Y1755997D01*
G01Y1755735D02*
Y1755748D01*
G01X79210Y1756259D02*
Y1756456D01*
G01X78942Y1755932D02*
Y1755748D01*
G01D02*
Y1755735D01*
G01X78937Y1734685D02*
Y1734094D01*
G01Y1757322D02*
Y1756732D01*
G01X78909Y1754324D02*
Y1754455D01*
G01X78775D02*
Y1754324D01*
G01X78741Y1755748D02*
Y1755932D01*
G01Y1755735D02*
Y1755748D01*
G01X78440Y1755538D02*
Y1755341D01*
G01X78272Y1755932D02*
Y1755748D01*
G01D02*
Y1755735D01*
G01X78239Y1754324D02*
Y1754455D01*
G01X78071Y1755767D02*
Y1755932D01*
G01Y1754324D02*
Y1754455D01*
G01X77756Y1764330D02*
Y1767086D01*
G01Y1729330D02*
Y1732086D01*
G01X75591Y1734882D02*
Y1734685D01*
G01Y1738031D02*
Y1737637D01*
G01Y1741181D02*
Y1740787D01*
G01Y1744330D02*
Y1743937D01*
G01Y1750630D02*
Y1750236D01*
G01Y1747480D02*
Y1747086D01*
G01Y1756732D02*
Y1756535D01*
G01Y1753779D02*
Y1753385D01*
G01X75512Y1754567D02*
Y1755748D01*
G01Y1751417D02*
Y1752598D01*
G01Y1748267D02*
Y1749448D01*
G01Y1745118D02*
Y1746299D01*
G01Y1741968D02*
Y1743149D01*
G01Y1738819D02*
Y1740000D01*
G01Y1735669D02*
Y1736850D01*
G01X75118D02*
Y1735669D01*
G01Y1740000D02*
Y1738819D01*
G01Y1746299D02*
Y1745118D01*
G01Y1743149D02*
Y1741968D01*
G01Y1749448D02*
Y1748267D01*
G01Y1752598D02*
Y1751417D01*
G01Y1755748D02*
Y1754567D01*
G01X74803Y1722421D02*
Y1722322D01*
G01Y1723996D02*
Y1722421D01*
G01Y1724094D02*
Y1723996D01*
G01Y1727421D02*
Y1727322D01*
G01Y1729094D02*
Y1728996D01*
G01Y1732421D02*
Y1732322D01*
G01Y1728996D02*
Y1727421D01*
G01Y1734094D02*
Y1733996D01*
G01D02*
Y1732421D01*
G01Y1757421D02*
Y1757322D01*
G01Y1759094D02*
Y1758996D01*
G01D02*
Y1757421D01*
G01Y1762421D02*
Y1762322D01*
G01Y1764094D02*
Y1763996D01*
G01D02*
Y1762421D01*
G01Y1767421D02*
Y1767322D01*
G01Y1769094D02*
Y1768996D01*
G01D02*
Y1767421D01*
G01Y1772421D02*
Y1772322D01*
G01Y1774094D02*
Y1773996D01*
G01D02*
Y1772421D01*
G01Y1777421D02*
Y1777322D01*
G01Y1779094D02*
Y1778996D01*
G01D02*
Y1777421D01*
G01Y1782421D02*
Y1782322D01*
G01Y1784094D02*
Y1783996D01*
G01D02*
Y1782421D01*
G01Y1787421D02*
Y1787322D01*
G01Y1789094D02*
Y1788996D01*
G01D02*
Y1787421D01*
G01X74331Y1736850D02*
Y1735669D01*
G01Y1740000D02*
Y1738819D01*
G01Y1743149D02*
Y1741968D01*
G01Y1746299D02*
Y1745118D01*
G01Y1749448D02*
Y1748267D01*
G01Y1755748D02*
Y1754567D01*
G01Y1752598D02*
Y1751417D01*
G01X72756Y1736850D02*
Y1735669D01*
G01Y1740000D02*
Y1738819D01*
G01Y1746299D02*
Y1745118D01*
G01Y1743149D02*
Y1741968D01*
G01Y1749448D02*
Y1748267D01*
G01Y1755748D02*
Y1754567D01*
G01Y1752598D02*
Y1751417D01*
G01X70866Y1755748D02*
Y1793799D01*
G01Y1752598D02*
Y1754567D01*
G01D02*
Y1755748D01*
G01Y1751417D02*
Y1752598D01*
G01Y1749448D02*
Y1751417D01*
G01Y1746299D02*
Y1748267D01*
G01D02*
Y1749448D01*
G01Y1743149D02*
Y1745118D01*
G01D02*
Y1746299D01*
G01Y1741968D02*
Y1743149D01*
G01Y1740000D02*
Y1741968D01*
G01Y1736850D02*
Y1738819D01*
G01D02*
Y1740000D01*
G01Y1735669D02*
Y1736850D01*
G01X70079Y1805295D02*
Y1796948D01*
G01X68110Y1757913D02*
Y1733504D01*
G01X51039Y1736850D02*
Y1735669D01*
G01Y1740000D02*
Y1738819D01*
G01Y1743149D02*
Y1741968D01*
G01Y1746299D02*
Y1745118D01*
G01Y1749448D02*
Y1748267D01*
G01Y1755748D02*
Y1754567D01*
G01Y1752598D02*
Y1751417D01*
G01X48800Y1736850D02*
Y1735669D01*
G01Y1740000D02*
Y1738819D01*
G01Y1743149D02*
Y1741968D01*
G01Y1746299D02*
Y1745118D01*
G01Y1749448D02*
Y1748267D01*
G01Y1755748D02*
Y1754567D01*
G01Y1752598D02*
Y1751417D01*
G01X48302Y1754567D02*
Y1755748D01*
G01Y1751417D02*
Y1752598D01*
G01Y1748267D02*
Y1749448D01*
G01Y1741968D02*
Y1743149D01*
G01Y1745118D02*
Y1746299D01*
G01Y1738819D02*
Y1740000D01*
G01Y1735669D02*
Y1736850D01*
G01X47559Y1754468D02*
Y1755846D01*
G01Y1735570D02*
Y1736948D01*
G01Y1740098D02*
Y1738720D01*
G01Y1746397D02*
Y1745019D01*
G01Y1743248D02*
Y1741870D01*
G01Y1749547D02*
Y1748169D01*
G01Y1752696D02*
Y1751319D01*
G01X46553Y1723996D02*
Y1722421D01*
G01Y1728996D02*
Y1727421D01*
G01Y1733996D02*
Y1732421D01*
G01Y1758996D02*
Y1757421D01*
G01Y1763996D02*
Y1762421D01*
G01Y1768996D02*
Y1767421D01*
G01Y1773996D02*
Y1772421D01*
G01Y1778996D02*
Y1777421D01*
G01Y1783996D02*
Y1782421D01*
G01Y1788996D02*
Y1787421D01*
G01X45447Y1723996D02*
Y1722421D01*
G01Y1728996D02*
Y1727421D01*
G01Y1733996D02*
Y1732421D01*
G01Y1758996D02*
Y1757421D01*
G01Y1763996D02*
Y1762421D01*
G01Y1768996D02*
Y1767421D01*
G01Y1773996D02*
Y1772421D01*
G01Y1778996D02*
Y1777421D01*
G01Y1783996D02*
Y1782421D01*
G01Y1788996D02*
Y1787421D01*
G01X45201Y1757421D02*
Y1758996D01*
G01Y1732421D02*
Y1733996D01*
G01Y1723996D02*
Y1722421D01*
G01Y1728996D02*
Y1727421D01*
G01Y1763996D02*
Y1762421D01*
G01Y1768996D02*
Y1767421D01*
G01Y1773996D02*
Y1772421D01*
G01Y1778996D02*
Y1777421D01*
G01Y1783996D02*
Y1782421D01*
G01Y1788996D02*
Y1787421D01*
G01X42744Y1736850D02*
Y1735669D01*
G01Y1740000D02*
Y1738819D01*
G01Y1743149D02*
Y1741968D01*
G01Y1746299D02*
Y1745118D01*
G01Y1749448D02*
Y1748267D01*
G01Y1755748D02*
Y1754567D01*
G01Y1752598D02*
Y1751417D01*
G01X42006D02*
Y1752598D01*
G01Y1754567D02*
Y1755748D01*
G01Y1748267D02*
Y1749448D01*
G01Y1745118D02*
Y1746299D01*
G01Y1741968D02*
Y1743149D01*
G01Y1738819D02*
Y1740000D01*
G01Y1735669D02*
Y1736850D01*
G01X41535Y1724094D02*
Y1722322D01*
G01Y1729094D02*
Y1727322D01*
G01Y1734094D02*
Y1732322D01*
G01Y1759094D02*
Y1757322D01*
G01Y1764094D02*
Y1762322D01*
G01Y1769094D02*
Y1767322D01*
G01Y1774094D02*
Y1772322D01*
G01Y1779094D02*
Y1777322D01*
G01Y1784094D02*
Y1782322D01*
G01Y1789094D02*
Y1787322D01*
G01X41454Y1757421D02*
Y1758996D01*
G01Y1732421D02*
Y1733996D01*
G01X41026Y1787421D02*
Y1788996D01*
G01Y1782421D02*
Y1783996D01*
G01Y1777421D02*
Y1778996D01*
G01Y1772421D02*
Y1773996D01*
G01Y1767421D02*
Y1768996D01*
G01Y1762421D02*
Y1763996D01*
G01Y1727421D02*
Y1728996D01*
G01Y1722421D02*
Y1723996D01*
G01X40551Y1733504D02*
Y1757913D01*
G01X40465Y1733996D02*
Y1732421D01*
G01Y1758996D02*
Y1757421D01*
G01X40344Y1723996D02*
Y1722421D01*
G01Y1728996D02*
Y1727421D01*
G01Y1763996D02*
Y1762421D01*
G01Y1768996D02*
Y1767421D01*
G01Y1773996D02*
Y1772421D01*
G01Y1778996D02*
Y1777421D01*
G01Y1783996D02*
Y1782421D01*
G01Y1788996D02*
Y1787421D01*
G01X38780Y1751319D02*
Y1752696D01*
G01Y1754468D02*
Y1755846D01*
G01Y1748169D02*
Y1749547D01*
G01Y1741870D02*
Y1743248D01*
G01Y1745019D02*
Y1746397D01*
G01Y1738720D02*
Y1740098D01*
G01Y1736948D02*
Y1735570D01*
G01X36614Y1796948D02*
Y1804114D01*
G01X31890Y1798917D02*
Y1800649D01*
G01X86153Y1733182D02*
X86186Y1733346D01*
G01X86929Y1788451D02*
X86896Y1788287D01*
G01X79646Y1754291D02*
X79612Y1754127D01*
G01X79646Y1755735D02*
X79612Y1755570D01*
G01X78071Y1754455D02*
X78094Y1754567D01*
G01D02*
X78104Y1754619D01*
G01X85985Y1733313D02*
X85952Y1733215D01*
G01X78306Y1756030D02*
X78272Y1755932D01*
G01X85589Y1788746D02*
X85556Y1788648D01*
G01X79478Y1754324D02*
X79445Y1754193D01*
G01X79411Y1755603D02*
X79445Y1755735D01*
G01X78909Y1754455D02*
X78937Y1754567D01*
G01D02*
X78942Y1754586D01*
G01X78775Y1754324D02*
X78741Y1754193D01*
G01X78239Y1754455D02*
X78267Y1754567D01*
G01D02*
X78272Y1754586D01*
G01X86695Y1788320D02*
X86728Y1788451D01*
G01X78071Y1755932D02*
X78104Y1756063D01*
G01X85354Y1788648D02*
X85388Y1788779D01*
G01X79445Y1754193D02*
X79378Y1754061D01*
G01X79612Y1755570D02*
X79545Y1755439D01*
G01X78842Y1754061D02*
X78808Y1753996D01*
G01X78942Y1754586D02*
X79009Y1754717D01*
G01X78842D02*
X78875Y1754783D01*
G01X78104Y1756063D02*
X78172Y1756194D01*
G01X86896Y1788287D02*
X86829Y1788156D01*
G01X85388Y1788779D02*
X85455Y1788910D01*
G01X86052Y1733051D02*
X86153Y1733182D01*
G01X78741Y1754193D02*
X78641Y1754061D01*
G01X78875Y1754783D02*
X78976Y1754914D01*
G01X78272Y1754586D02*
X78372Y1754717D01*
G01X79344Y1755505D02*
X79411Y1755603D01*
G01X78372Y1756128D02*
X78306Y1756030D01*
G01X86628Y1788221D02*
X86695Y1788320D01*
G01X85656Y1788845D02*
X85589Y1788746D01*
G01X79612Y1754127D02*
X79512Y1753963D01*
G01X78104Y1754619D02*
X78205Y1754783D01*
G01X73228Y1736948D02*
X75591Y1737637D01*
G01X73228Y1740098D02*
X75591Y1740787D01*
G01X73228Y1743248D02*
X75591Y1743937D01*
G01X73228Y1746397D02*
X75591Y1747086D01*
G01X73228Y1749547D02*
X75591Y1750236D01*
G01X73228Y1752696D02*
X75591Y1753385D01*
G01X73228Y1755846D02*
X75591Y1756535D01*
G01X85818Y1732920D02*
X85918Y1732952D01*
G01X85885Y1733149D02*
X85784Y1733117D01*
G01X78473Y1756161D02*
X78372Y1756128D01*
G01X85757Y1788878D02*
X85656Y1788845D01*
G01X79528Y1724094D02*
X82677Y1725275D01*
G01X79528Y1729094D02*
X82677Y1730275D01*
G01X79528Y1759094D02*
X82677Y1760275D01*
G01X79528Y1764094D02*
X82677Y1765275D01*
G01X79528Y1769094D02*
X82677Y1770275D01*
G01X79528Y1774094D02*
X82677Y1775275D01*
G01X79528Y1779094D02*
X82677Y1780275D01*
G01X79528Y1784094D02*
X82677Y1785275D01*
G01X79528Y1789094D02*
X82677Y1790275D01*
G01X79411Y1753865D02*
X79244Y1753799D01*
G01X78976Y1754914D02*
X79143Y1754980D01*
G01X78306Y1754882D02*
X78473Y1754947D01*
G01X78708Y1753897D02*
X78574Y1753832D01*
G01X79411Y1755308D02*
X79277Y1755243D01*
G01X86695Y1788024D02*
X86561Y1787959D01*
G01X78641Y1754061D02*
X78540Y1753996D01*
G01X78372Y1754717D02*
X78473Y1754783D01*
G01X79244Y1755439D02*
X79344Y1755505D01*
G01X86527Y1788156D02*
X86628Y1788221D01*
G01X85918Y1732952D02*
X86052Y1733051D01*
G01X79378Y1754061D02*
X79244Y1753963D01*
G01X79009Y1754717D02*
X79143Y1754816D01*
G01X85583Y1732460D02*
X85818Y1732657D01*
G01X85550D02*
X85315Y1732460D01*
G01X85622Y1787500D02*
X85857Y1787696D01*
G01X85589D02*
X85354Y1787500D01*
G01X85952Y1733215D02*
X85885Y1733149D01*
G01X79512Y1753963D02*
X79411Y1753865D01*
G01X78808Y1753996D02*
X78708Y1753897D01*
G01X79545Y1755439D02*
X79411Y1755308D01*
G01X78205Y1754783D02*
X78306Y1754882D01*
G01X78172Y1756194D02*
X78306Y1756325D01*
G01X86829Y1788156D02*
X86695Y1788024D01*
G01X85542Y1788996D02*
X85589Y1789042D01*
G01X85455Y1788910D02*
X85542Y1788996D01*
G01X40551Y1735945D02*
X38583Y1733976D01*
G01X36610Y1804187D02*
X31890Y1799546D01*
G01Y1800649D02*
X36614Y1805295D01*
G01X40551Y1796948D02*
X38583Y1794980D01*
G01X15550Y1807538D02*
X18700Y1808672D01*
G01X15550Y1814546D02*
Y1807538D01*
G01X18700Y1813412D02*
Y1808672D01*
G01X14688Y1805681D02*
X15464Y1805485D01*
G01X16248D02*
X15472Y1805681D01*
G01X16248Y1805485D02*
X15464D01*
G01X15472Y1805681D02*
X12829D01*
G01X19881Y1807283D02*
G03Y1814764I0J3740D01*
G01X12829Y1816154D02*
Y1817493D01*
G01Y1820091D02*
Y1821430D01*
G01Y1824028D02*
Y1825367D01*
G01Y1827965D02*
Y1829304D01*
G01X13613D02*
Y1827965D01*
G01Y1825367D02*
Y1824028D01*
G01Y1821430D02*
Y1820091D01*
G01Y1817493D02*
Y1816154D01*
G01X15464Y1829107D02*
Y1828162D01*
G01Y1825170D02*
Y1824225D01*
G01Y1821233D02*
Y1820288D01*
G01Y1817296D02*
Y1816351D01*
G01X16248D02*
Y1817296D01*
G01Y1820288D02*
Y1821233D01*
G01Y1824225D02*
Y1825170D01*
G01Y1828162D02*
Y1829107D01*
G01X15550Y1814546D02*
X18700Y1813412D01*
G01X14688Y1817493D02*
X15464Y1817296D01*
G01X16248D02*
X15472Y1817493D01*
G01X14688Y1821430D02*
X15464Y1821233D01*
G01X16248D02*
X15472Y1821430D01*
G01X14688Y1825367D02*
X15464Y1825170D01*
G01X16248D02*
X15472Y1825367D01*
G01X14688Y1829304D02*
X15464Y1829107D01*
G01X16248D02*
X15472Y1829304D01*
G01Y1816154D02*
X12829D01*
G01X16248Y1816351D02*
X15464D01*
G01X16248Y1817296D02*
X15464D01*
G01X15472Y1817493D02*
X12829D01*
G01X15472Y1820091D02*
X12829D01*
G01X16248Y1820288D02*
X15464D01*
G01X16248Y1821233D02*
X15464D01*
G01X15472Y1821430D02*
X12829D01*
G01X15472Y1824028D02*
X12829D01*
G01X16248Y1824225D02*
X15464D01*
G01X16248Y1825170D02*
X15464D01*
G01X15472Y1825367D02*
X12829D01*
G01X15472Y1827965D02*
X12829D01*
G01X16248Y1828162D02*
X15464D01*
G01X16248Y1829107D02*
X15464D01*
G01X15472Y1829304D02*
X12829D01*
G01X15472Y1816154D02*
X16248Y1816351D01*
G01X15464D02*
X14688Y1816154D01*
G01X15472Y1820091D02*
X16248Y1820288D01*
G01X15464D02*
X14688Y1820091D01*
G01X15472Y1824028D02*
X16248Y1824225D01*
G01X15464D02*
X14688Y1824028D01*
G01X15472Y1827965D02*
X16248Y1828162D01*
G01X15464D02*
X14688Y1827965D01*
G01X12829Y1831902D02*
Y1833241D01*
G01Y1835839D02*
Y1837178D01*
G01Y1839776D02*
Y1841115D01*
G01X13613D02*
Y1839776D01*
G01Y1837178D02*
Y1835839D01*
G01Y1833241D02*
Y1831902D01*
G01X15464Y1836981D02*
Y1836036D01*
G01Y1840918D02*
Y1839973D01*
G01Y1833044D02*
Y1832099D01*
G01X16248D02*
Y1833044D01*
G01Y1836036D02*
Y1836981D01*
G01Y1839973D02*
Y1840918D01*
G01X22851Y1871662D02*
Y1846071D01*
G01X24802Y1871662D02*
Y1846071D01*
G01X14688Y1833241D02*
X15464Y1833044D01*
G01X16248D02*
X15472Y1833241D01*
G01X14688Y1837178D02*
X15464Y1836981D01*
G01X16248D02*
X15472Y1837178D01*
G01X14688Y1841115D02*
X15464Y1840918D01*
G01X16248D02*
X15472Y1841115D01*
G01Y1831902D02*
X12829D01*
G01X16248Y1832099D02*
X15464D01*
G01X16248Y1833044D02*
X15464D01*
G01X15472Y1833241D02*
X12829D01*
G01X15472Y1835839D02*
X12829D01*
G01X16248Y1836036D02*
X15464D01*
G01X16248Y1836981D02*
X15464D01*
G01X15472Y1837178D02*
X12829D01*
G01X15472Y1839776D02*
X12829D01*
G01X16248Y1839973D02*
X15464D01*
G01X16248Y1840918D02*
X15464D01*
G01X15472Y1841115D02*
X12829D01*
G01X15472Y1831902D02*
X16248Y1832099D01*
G01X15464D02*
X14688Y1831902D01*
G01X15472Y1835839D02*
X16248Y1836036D01*
G01X15464D02*
X14688Y1835839D01*
G01X15472Y1839776D02*
X16248Y1839973D01*
G01X15464D02*
X14688Y1839776D01*
G01X65664Y1828928D02*
X65758Y1829039D01*
G01Y1828912D02*
X65664Y1828801D01*
G01X64172Y1832343D02*
Y1830374D01*
G01Y1827815D02*
Y1829783D01*
G01X65664Y1828801D02*
Y1828928D01*
G01X65747Y1830866D02*
Y1829291D01*
G01Y1828110D02*
Y1827520D01*
G01X65758Y1828291D02*
Y1828912D01*
G01X65851Y1829039D02*
Y1828291D01*
G01X66495Y1830039D02*
Y1980315D01*
G01X66731Y1827520D02*
Y1832638D01*
G01X66928D02*
Y1827520D01*
G01X67322Y1829783D02*
Y1827815D01*
G01Y1830374D02*
Y1832343D01*
G01X65747Y1827520D02*
X72046D01*
G01X67322Y1827815D02*
X65747D01*
G01D02*
X64172D01*
G01X65851Y1828291D02*
X65758D01*
G01Y1829039D02*
X65851D01*
G01X65747Y1829783D02*
X67322D01*
G01X64172D02*
X65747D01*
G01X72046Y1830039D02*
X66495D01*
G01X65747Y1830374D02*
X67322D01*
G01X64172D02*
X65747D01*
G01Y1830866D02*
G03Y1832047I0J590D01*
G01Y1828110D02*
G03Y1829291I0J591D01*
G01Y1832638D02*
Y1832047D01*
G01X67322Y1832343D02*
X65747D01*
G01D02*
X64172D01*
G01X65747Y1832638D02*
X72046D01*
G01X70471Y1829783D02*
Y1827815D01*
G01Y1830374D02*
Y1832343D01*
G01X70865Y1832638D02*
Y1827520D01*
G01X71062D02*
Y1832638D01*
G01X72046Y1827520D02*
Y1828110D01*
G01Y1829291D02*
Y1830866D01*
G01X73621Y1832343D02*
Y1830374D01*
G01Y1827815D02*
Y1829783D01*
G01X70471Y1827815D02*
X72046D01*
G01D02*
X73621D01*
G01X72046Y1829783D02*
X70471D01*
G01X73621D02*
X72046D01*
G01X110235Y1830039D02*
X72046D01*
G01Y1830374D02*
X70471D01*
G01X73621D02*
X72046D01*
G01Y1832047D02*
G03Y1830866I0J-591D01*
G01Y1829291D02*
G03Y1828110I0J-590D01*
G01Y1832047D02*
Y1832638D01*
G01X70471Y1832343D02*
X72046D01*
G01D02*
X73621D01*
G01X89172Y1882913D02*
Y1884144D01*
G01X99015Y1882913D02*
X89172D01*
G01Y1884144D02*
X93151D01*
G01D02*
Y1889885D01*
G01X94408D02*
Y1884144D01*
G01D02*
X99015D01*
G01X72638Y1812323D02*
G03I-3740J0D01*
G01X55118Y1822185D02*
X82677D01*
G01X78740Y1818248D02*
X59055D01*
G01X78740Y1816279D02*
X59055D01*
G01X78740Y1814291D02*
X59055D01*
G01Y1813307D02*
X78740D01*
G01X59252Y1813110D02*
X78543D01*
G01X59252Y1811535D02*
X78543D01*
G01X78740Y1811338D02*
X59055D01*
G01Y1810354D02*
X78740D01*
G01X27953Y1809232D02*
X55118D01*
G01X94488D02*
X82677D01*
G01X78740Y1807263D02*
X59055D01*
G01X36614Y1805295D02*
X90551D01*
G01X82677Y1822185D02*
Y1809232D01*
G01X78740Y1805295D02*
Y1818248D01*
G01X78543Y1811535D02*
Y1813110D01*
G01X73189D02*
Y1811535D01*
G01X71850Y1813110D02*
Y1813307D01*
G01Y1811535D02*
Y1811338D01*
G01Y1813110D02*
Y1811535D01*
G01X71654Y1813110D02*
Y1811535D01*
G01X70079D02*
Y1813110D01*
G01X67717Y1811535D02*
Y1813110D01*
G01X66142Y1811535D02*
Y1813110D01*
G01X65945Y1811535D02*
Y1813110D01*
G01Y1811535D02*
Y1811338D01*
G01Y1813307D02*
Y1813110D01*
G01X64606Y1811535D02*
Y1813110D01*
G01X59252D02*
Y1811535D01*
G01X59055Y1805295D02*
Y1818248D01*
G01X55118Y1809232D02*
Y1822185D01*
G01X89172Y1889885D02*
Y1891115D01*
G01X93151Y1889885D02*
X89172D01*
G01Y1891115D02*
X99015D01*
G01X89172Y1907109D02*
X89382Y1908340D01*
G01X89172Y1899933D02*
Y1901163D01*
G01Y1906289D02*
Y1907109D01*
G01X89382Y1904854D02*
X89172Y1906289D01*
G01X90638Y1898702D02*
X89172Y1899933D01*
G01Y1901163D02*
X99015D01*
G01Y1889885D02*
X94408D01*
G01X91476Y1908955D02*
X90848Y1908545D01*
G01X91895Y1896652D02*
X92523Y1897062D01*
G01X89801Y1909160D02*
X90638Y1909980D01*
G01X90848Y1908545D02*
X90429Y1907930D01*
G01X89382Y1908340D02*
X89801Y1909160D01*
G01X93989Y1894191D02*
X95455Y1897062D01*
G01X96083Y1896652D02*
X93989Y1892756D01*
G01X90429Y1907930D02*
X90219Y1906905D01*
G01D02*
Y1906084D01*
G01X91476Y1904034D02*
Y1903009D01*
G01X92314Y1911826D02*
Y1912851D01*
G01X90219Y1906084D02*
X90429Y1905059D01*
G01X93989Y1892756D02*
X91895Y1896652D01*
G01X92523Y1897062D02*
X93989Y1894191D01*
G01X89801Y1904034D02*
X89382Y1904854D01*
G01X90429Y1905059D02*
X90848Y1904444D01*
G01X97968Y1902804D02*
X92732Y1908545D01*
G01X93361Y1909570D02*
X97968Y1904444D01*
G01X90638Y1903214D02*
X89801Y1904034D01*
G01X90848Y1899933D02*
X92314Y1898702D01*
G01X90848Y1904444D02*
X91476Y1904034D01*
G01X92732Y1909980D02*
X93361Y1909570D01*
G01X92732Y1908545D02*
X91895Y1908955D01*
G01X91476Y1903009D02*
X90638Y1903214D01*
G01X91895Y1910185D02*
X92732Y1909980D01*
G01X92314Y1898702D02*
X90638D01*
G01X99015Y1899933D02*
X90848D01*
G01X91895Y1908955D02*
X91476D01*
G01Y1910185D02*
X91895D01*
G01X99015Y1911826D02*
X92314D01*
G01X90638Y1909980D02*
X91476Y1910185D01*
G01X93989Y1927615D02*
X93570Y1927410D01*
G01X93989Y1924334D02*
X93570Y1924129D01*
G01X93989Y1918387D02*
X93570Y1918182D01*
G01X93989Y1915107D02*
X93570Y1914902D01*
G01X92942Y1928230D02*
X93989Y1928640D01*
G01X92942Y1919003D02*
X93989Y1919413D01*
G01X92523Y1927820D02*
X92942Y1928230D01*
G01X93570Y1927410D02*
X93361Y1927205D01*
G01X92523Y1924539D02*
X93151Y1925154D01*
G01X93570Y1924129D02*
X93361Y1923924D01*
G01X92523Y1918593D02*
X92942Y1919003D01*
G01X93570Y1918182D02*
X93361Y1917978D01*
G01X92523Y1915312D02*
X93151Y1915927D01*
G01X93570Y1914902D02*
X93361Y1914696D01*
G01Y1927205D02*
X93151Y1926794D01*
G01X93361Y1923924D02*
X93151Y1923514D01*
G01X93361Y1917978D02*
X93151Y1917567D01*
G01X93361Y1914696D02*
X93151Y1914287D01*
G01X92314Y1927205D02*
X92523Y1927820D01*
G01X92314Y1923924D02*
X92523Y1924539D01*
G01X92314Y1917978D02*
X92523Y1918593D01*
G01X92314Y1914696D02*
X92523Y1915312D01*
G01X92314Y1913876D02*
Y1914696D01*
G01Y1917157D02*
Y1917978D01*
G01Y1923104D02*
Y1923924D01*
G01Y1921053D02*
Y1922078D01*
G01Y1926385D02*
Y1927205D01*
G01X93151Y1926794D02*
Y1926180D01*
G01Y1923514D02*
Y1923104D01*
G01Y1917567D02*
Y1916952D01*
G01Y1914287D02*
Y1913876D01*
G01X92523Y1913261D02*
X92314Y1913876D01*
G01X93151D02*
X93361Y1913261D01*
G01X92523Y1916542D02*
X92314Y1917157D01*
G01X92523Y1922489D02*
X92314Y1923104D01*
G01X93151D02*
X93361Y1922489D01*
G01X92523Y1925769D02*
X92314Y1926385D01*
G01X93151Y1916952D02*
X93361Y1916542D01*
G01X93151Y1926180D02*
X93361Y1925769D01*
G01X92942Y1912851D02*
X92523Y1913261D01*
G01X93361D02*
X93779Y1912851D01*
G01X93151Y1915927D02*
X92523Y1916542D01*
G01X93361D02*
X93570Y1916337D01*
G01X92942Y1922078D02*
X92523Y1922489D01*
G01X93361D02*
X93779Y1922078D01*
G01X93151Y1925154D02*
X92523Y1925769D01*
G01X93361D02*
X93570Y1925564D01*
G01Y1916337D02*
X93989Y1916132D01*
G01X93570Y1925564D02*
X93989Y1925359D01*
G01X93779Y1912851D02*
X99015D01*
G01X92314D02*
X92942D01*
G01X99015Y1915107D02*
X93989D01*
G01Y1916132D02*
X99015D01*
G01Y1918387D02*
X93989D01*
G01Y1919413D02*
X99015D01*
G01Y1921053D02*
X92314D01*
G01X93779Y1922078D02*
X99015D01*
G01X92314D02*
X92942D01*
G01X99015Y1924334D02*
X93989D01*
G01Y1925359D02*
X99015D01*
G01Y1927615D02*
X93989D01*
G01Y1928640D02*
X99015D01*
G01X66495Y1980315D02*
X137794D01*
G01X108267Y-38936D02*
Y-57873D01*
G01X169723Y35433D02*
X98424D01*
G01D02*
Y204094D01*
G01X145668Y17717D02*
G03I-15748J0D01*
G01X137794D02*
G03I-7874J0D01*
G01X169723Y162087D02*
Y35433D01*
G01X152282Y78622D02*
X142440D01*
G01Y79852D02*
X146419D01*
G01X147675D02*
X152282D01*
G01X142440Y78622D02*
Y79852D01*
G01X146419D02*
Y85594D01*
G01X147675D02*
Y79852D01*
G01X152282Y85594D02*
X147675D01*
G01X146419D02*
X142440D01*
G01Y86824D02*
X152282D01*
G01X144743Y98717D02*
X143906Y98922D01*
G01X148723Y92771D02*
X149351Y92361D01*
G01X144116Y100153D02*
X144743Y99743D01*
G01X143906Y94411D02*
X142440Y95641D01*
G01X144116D02*
X145581Y94411D01*
G01X143906Y98922D02*
X143068Y99743D01*
G01X145581Y94411D02*
X143906D01*
G01X152282Y95641D02*
X144116D01*
G01X142440Y96872D02*
X152282D01*
G01X151236Y98512D02*
X146000Y104254D01*
G01X146629Y105279D02*
X151236Y100153D01*
G01X143697Y100768D02*
X144116Y100153D01*
G01X147256Y88465D02*
X145162Y92361D01*
G01X145791Y92771D02*
X147256Y89900D01*
G01X143068Y99743D02*
X142649Y100563D01*
G01X143487Y101793D02*
X143697Y100768D01*
G01X142649Y100563D02*
X142440Y101998D01*
G01Y85594D02*
Y86824D01*
G01Y95641D02*
Y96872D01*
G01Y101998D02*
Y102818D01*
G01X143487Y102613D02*
Y101793D01*
G01X144743Y99743D02*
Y98717D01*
G01X142440Y102818D02*
X142649Y104048D01*
G01X143697Y103639D02*
X143487Y102613D01*
G01X147256Y89900D02*
X148723Y92771D01*
G01X149351Y92361D02*
X147256Y88465D01*
G01X144116Y104254D02*
X143697Y103639D01*
G01X145162Y92361D02*
X145791Y92771D01*
G01X145162Y105894D02*
X146000Y105689D01*
G01Y104254D02*
X145162Y104664D01*
G01X146838Y112046D02*
X147256Y111841D01*
G01X146838Y121273D02*
X147256Y121068D01*
G01X146000Y105689D02*
X146629Y105279D01*
G01X145162Y104664D02*
X144743D01*
G01Y105894D02*
X145162D01*
G01X152282Y107535D02*
X145581D01*
G01X147047Y108560D02*
X152282D01*
G01X145581D02*
X146210D01*
G01X152282Y110815D02*
X147256D01*
G01Y111841D02*
X152282D01*
G01Y114096D02*
X147256D01*
G01Y115121D02*
X152282D01*
G01Y116762D02*
X145581D01*
G01X147047Y117787D02*
X152282D01*
G01X145581D02*
X146210D01*
G01X152282Y120043D02*
X147256D01*
G01Y121068D02*
X152282D01*
G01Y123324D02*
X147256D01*
G01X146210Y108560D02*
X145791Y108970D01*
G01X146629D02*
X147047Y108560D01*
G01X146419Y111635D02*
X145791Y112251D01*
G01X146629D02*
X146838Y112046D01*
G01X146210Y117787D02*
X145791Y118197D01*
G01X146629D02*
X147047Y117787D01*
G01X146419Y120863D02*
X145791Y121478D01*
G01X146629D02*
X146838Y121273D01*
G01X143906Y105689D02*
X144743Y105894D01*
G01X146419Y112661D02*
X146629Y112251D01*
G01X146419Y121888D02*
X146629Y121478D01*
G01X145791Y108970D02*
X145581Y109585D01*
G01X146419D02*
X146629Y108970D01*
G01X145791Y112251D02*
X145581Y112866D01*
G01X145791Y118197D02*
X145581Y118812D01*
G01X146419D02*
X146629Y118197D01*
G01X145791Y121478D02*
X145581Y122093D01*
G01Y107535D02*
Y108560D01*
G01Y112866D02*
Y113686D01*
G01Y109585D02*
Y110405D01*
G01Y116762D02*
Y117787D01*
G01Y122093D02*
Y122913D01*
G01Y118812D02*
Y119633D01*
G01X146419Y119222D02*
Y118812D01*
G01Y122503D02*
Y121888D01*
G01Y109995D02*
Y109585D01*
G01Y113276D02*
Y112661D01*
G01X145581Y122913D02*
X145791Y123529D01*
G01X145581Y119633D02*
X145791Y120248D01*
G01X145581Y113686D02*
X145791Y114301D01*
G01X145581Y110405D02*
X145791Y111020D01*
G01X146629Y122913D02*
X146419Y122503D01*
G01X146629Y119633D02*
X146419Y119222D01*
G01X146629Y113686D02*
X146419Y113276D01*
G01X142649Y104048D02*
X143068Y104869D01*
G01X146629Y110405D02*
X146419Y109995D01*
G01X145791Y123529D02*
X146210Y123939D01*
G01X146838Y123119D02*
X146629Y122913D01*
G01X145791Y120248D02*
X146419Y120863D01*
G01X146838Y119838D02*
X146629Y119633D01*
G01X145791Y114301D02*
X146210Y114711D01*
G01X146838Y113891D02*
X146629Y113686D01*
G01X145791Y111020D02*
X146419Y111635D01*
G01X146838Y110610D02*
X146629Y110405D01*
G01X143068Y104869D02*
X143906Y105689D01*
G01X144743Y104664D02*
X144116Y104254D01*
G01X147256Y123324D02*
X146838Y123119D01*
G01X147256Y120043D02*
X146838Y119838D01*
G01X147256Y114096D02*
X146838Y113891D01*
G01X147256Y110815D02*
X146838Y110610D01*
G01X146210Y114711D02*
X147256Y115121D01*
G01Y124349D02*
X152282D01*
G01X146210Y123939D02*
X147256Y124349D01*
G01X152282Y79852D02*
Y78622D01*
G01Y98512D02*
X151236D01*
G01Y100153D02*
Y105894D01*
G01X152282D02*
Y98512D01*
G01Y96872D02*
Y95641D01*
G01Y86824D02*
Y85594D01*
G01X151236Y105894D02*
X152282D01*
G01Y124349D02*
Y123324D01*
G01Y121068D02*
Y120043D01*
G01Y115121D02*
Y114096D01*
G01Y117787D02*
Y116762D01*
G01Y111841D02*
Y110815D01*
G01Y108560D02*
Y107535D01*
G01X125983Y162087D02*
X164172D01*
G01X125983Y263150D02*
Y162087D01*
G01X164172Y159488D02*
X170471D01*
G01X165747Y159783D02*
X164172D01*
G01D02*
X162597D01*
G01X168897D02*
X170471D01*
G01Y161752D02*
X168897D01*
G01X164172D02*
X165747D01*
G01X162597D02*
X164172D01*
G01Y162087D02*
X169723D01*
G01X170471Y162343D02*
X168897D01*
G01X164172D02*
X165747D01*
G01X162597D02*
X164172D01*
G01X162597Y164311D02*
Y162343D01*
G01Y159783D02*
Y161752D01*
G01X164172Y162835D02*
Y161260D01*
G01Y160079D02*
Y159488D01*
G01X165156Y164606D02*
Y159488D01*
G01X165353D02*
Y164606D01*
G01X165747Y161752D02*
Y159783D01*
G01Y162343D02*
Y164311D01*
G01X168897Y161752D02*
Y159783D01*
G01Y162343D02*
Y164311D01*
G01X169290Y159488D02*
Y164606D01*
G01X169487D02*
Y159488D01*
G01X164172Y160079D02*
G03Y161260I0J591D01*
G01Y162835D02*
G03Y164016I0J591D01*
G01X165747Y164311D02*
X164172D01*
G01D02*
X162597D01*
G01X168897D02*
X170471D01*
G01X164172Y164606D02*
X170471D01*
G01X164172D02*
Y164016D01*
G01X170471Y159783D02*
X172046D01*
G01Y161752D02*
X170471D01*
G01X172046Y162343D02*
X170471D01*
G01X170461Y163087D02*
X170367D01*
G01Y163835D02*
X170461D01*
G01X170367Y163087D02*
Y163835D01*
G01X170461D02*
Y163214D01*
G01X170471Y159488D02*
Y160079D01*
G01Y161260D02*
Y162835D01*
G01X170554Y163326D02*
Y163198D01*
G01X172046Y164311D02*
Y162343D01*
G01Y159783D02*
Y161752D01*
G01X170461Y163214D02*
X170554Y163326D01*
G01Y163198D02*
X170461Y163087D01*
G01X170471Y161260D02*
G03Y160079I1J-591D01*
G01Y164016D02*
G03Y162835I1J-590D01*
G01Y164311D02*
X172046D01*
G01X170471Y164016D02*
Y164606D01*
G01X157996Y195747D02*
X158071Y195748D01*
G01X158146Y187480D02*
X158071D01*
G01X160630Y191614D02*
G03I-2559J0D01*
G01X161417D02*
G03I-3346J0D01*
G01X161575D02*
G03I-3504J0D01*
G01X158146Y187481D02*
G03X158071Y195748I-75J4133D01*
G01X157996Y195747D02*
G03X158071Y187480I74J-4133D01*
G01X171063Y179803D02*
G03I-3740J0D01*
G01X150464Y203248D02*
X150565Y203280D01*
G01X156693Y203031D02*
X153543Y201850D01*
G01X156693Y208031D02*
X153543Y206850D01*
G01X156693Y213031D02*
X153543Y211850D01*
G01X156693Y218031D02*
X153543Y216850D01*
G01X156693Y223031D02*
X153543Y221850D01*
G01X156693Y228031D02*
X153543Y226850D01*
G01X156693Y233031D02*
X153543Y231850D01*
G01X149526Y204101D02*
X149660Y204166D01*
G01X149694Y203969D02*
X149593Y203904D01*
G01X150632Y204429D02*
X150866Y204626D01*
G01X150598D02*
X150364Y204429D01*
G01X150679Y203130D02*
X150632Y203083D01*
G01X150766Y203215D02*
X150679Y203130D01*
G01X149392Y203969D02*
X149526Y204101D01*
G01X150565Y203280D02*
X150632Y203379D01*
G01X149593Y203904D02*
X149526Y203806D01*
G01X150833Y203346D02*
X150766Y203215D01*
G01X149325Y203838D02*
X149392Y203969D01*
G01X150632Y203379D02*
X150665Y203477D01*
G01X150866D02*
X150833Y203346D01*
G01X149526Y203806D02*
X149493Y203674D01*
G01X149291D02*
X149325Y203838D01*
G01X177165Y186830D02*
Y346004D01*
G01Y173878D02*
Y186830D01*
G01X176969Y179015D02*
Y180590D01*
G01X171614D02*
Y179015D01*
G01X170276Y180590D02*
Y180787D01*
G01Y178819D02*
Y179015D01*
G01Y180590D02*
Y179015D01*
G01X170079Y180590D02*
Y179015D01*
G01X169291Y332736D02*
Y200098D01*
G01X168504Y180590D02*
Y179015D01*
G01X168012Y200098D02*
Y332736D01*
G01X166634D02*
Y200098D01*
G01X166142Y186830D02*
Y195177D01*
G01Y180590D02*
Y179015D01*
G01X165354Y198326D02*
Y236378D01*
G01X164567Y179015D02*
Y180590D01*
G01X164370D02*
Y180787D01*
G01Y179015D02*
Y180590D01*
G01Y179015D02*
Y178819D01*
G01X163032Y179015D02*
Y180590D01*
G01X161417Y229704D02*
Y229803D01*
G01Y228031D02*
Y228130D01*
G01D02*
Y229704D01*
G01Y224704D02*
Y224803D01*
G01Y223031D02*
Y223130D01*
G01D02*
Y224704D01*
G01Y219704D02*
Y219803D01*
G01Y218031D02*
Y218130D01*
G01D02*
Y219704D01*
G01Y214704D02*
Y214803D01*
G01Y213031D02*
Y213130D01*
G01D02*
Y214704D01*
G01Y209704D02*
Y209803D01*
G01Y208031D02*
Y208130D01*
G01D02*
Y209704D01*
G01Y204704D02*
Y204803D01*
G01Y203031D02*
Y203130D01*
G01D02*
Y204704D01*
G01X158465Y227795D02*
Y225039D01*
G01X157677Y180590D02*
Y179015D01*
G01X157480Y173878D02*
Y186830D01*
G01X155787Y228130D02*
Y229704D01*
G01Y223130D02*
Y224704D01*
G01Y218130D02*
Y219704D01*
G01Y213130D02*
Y214704D01*
G01Y208130D02*
Y209704D01*
G01Y203130D02*
Y204704D01*
G01X154213Y228130D02*
Y229704D01*
G01Y223130D02*
Y224704D01*
G01Y218130D02*
Y219704D01*
G01Y213130D02*
Y214704D01*
G01Y208130D02*
Y209704D01*
G01Y203130D02*
Y204704D01*
G01X153543Y230984D02*
Y231850D01*
G01Y225984D02*
Y226850D01*
G01Y220984D02*
Y221850D01*
G01Y215984D02*
Y216850D01*
G01Y210984D02*
Y211850D01*
G01Y205984D02*
Y206850D01*
G01Y200098D02*
Y201850D01*
G01Y169941D02*
Y182893D01*
G01X153425Y204704D02*
Y203130D01*
G01Y209704D02*
Y208130D01*
G01Y214704D02*
Y213130D01*
G01Y219704D02*
Y218130D01*
G01Y224704D02*
Y223130D01*
G01Y229704D02*
Y228130D01*
G01X153032Y204704D02*
Y203130D01*
G01Y209704D02*
Y208130D01*
G01Y214704D02*
Y213130D01*
G01Y219704D02*
Y218130D01*
G01Y224704D02*
Y223130D01*
G01Y229704D02*
Y228130D01*
G01X150866Y204704D02*
Y204822D01*
G01Y204626D02*
Y204704D01*
G01Y203641D02*
Y203477D01*
G01X150665D02*
Y203674D01*
G01X150498Y203871D02*
Y204068D01*
G01X150196Y203674D02*
Y203477D01*
G01X149995D02*
Y203674D01*
G01X149727Y203130D02*
Y202952D01*
G01Y203149D02*
Y203130D01*
G01X149493Y203674D02*
Y203412D01*
G01X149291D02*
Y203674D01*
G01Y204822D02*
Y204704D01*
G01D02*
Y204626D01*
G01X148110Y228130D02*
Y229704D01*
G01Y223130D02*
Y224704D01*
G01Y218130D02*
Y219704D01*
G01Y213130D02*
Y214704D01*
G01Y208130D02*
Y209704D01*
G01Y203130D02*
Y204704D01*
G01X145669Y186830D02*
Y200098D01*
G01X141732Y349941D02*
Y182893D01*
G01X150833Y203806D02*
X150866Y203641D01*
G01X150163Y203838D02*
X150196Y203674D01*
G01X149325Y203248D02*
X149291Y203412D01*
G01X149995Y203674D02*
X149961Y203806D01*
G01X150029Y203346D02*
X149995Y203477D01*
G01X149493Y203412D02*
X149526Y203280D01*
G01X150665Y203674D02*
X150632Y203772D01*
G01X150196Y203477D02*
X150230Y203379D01*
G01X150096Y203969D02*
X150163Y203838D01*
G01X150096Y203215D02*
X150029Y203346D01*
G01X149426Y203083D02*
X149397Y203130D01*
G01D02*
X149325Y203248D01*
G01X150632Y203083D02*
X150498Y203051D01*
G01X149961Y203806D02*
X149895Y203904D01*
G01X150230Y203379D02*
X150297Y203280D01*
G01X150732Y203937D02*
X150833Y203806D01*
G01X150632Y203772D02*
X150565Y203838D01*
G01X149961Y204101D02*
X150096Y203969D01*
G01X150230Y203083D02*
X150183Y203130D01*
G01D02*
X150096Y203215D01*
G01X149526Y203280D02*
X149626Y203182D01*
G01X161417Y229803D02*
X156693D01*
G01X197638D02*
X165354D01*
G01Y229704D02*
X195877D01*
G01X148110D02*
X165354D01*
G01Y228130D02*
X195877D01*
G01X165354D02*
X148110D01*
G01X165354Y228031D02*
X197638D01*
G01X156693D02*
X161417D01*
G01X158465Y227795D02*
X165354D01*
G01Y225039D02*
X158465D01*
G01X165354Y224803D02*
X197638D01*
G01X161417D02*
X156693D01*
G01X165354Y224704D02*
X195877D01*
G01X148110D02*
X165354D01*
G01Y223130D02*
X195877D01*
G01X165354D02*
X148110D01*
G01X165354Y223031D02*
X197638D01*
G01X156693D02*
X161417D01*
G01X165354Y219803D02*
X197638D01*
G01X161417D02*
X156693D01*
G01X165354Y219704D02*
X195877D01*
G01X148110D02*
X165354D01*
G01Y218130D02*
X195877D01*
G01X165354D02*
X148110D01*
G01X165354Y218031D02*
X197638D01*
G01X156693D02*
X161417D01*
G01X165354Y214803D02*
X197638D01*
G01X161417D02*
X156693D01*
G01X165354Y214704D02*
X195877D01*
G01X148110D02*
X165354D01*
G01Y213130D02*
X195877D01*
G01X165354D02*
X148110D01*
G01X165354Y213031D02*
X197638D01*
G01X156693D02*
X161417D01*
G01X165354Y209803D02*
X197638D01*
G01X161417D02*
X156693D01*
G01X165354Y209704D02*
X195877D01*
G01X148110D02*
X165354D01*
G01Y208130D02*
X195877D01*
G01X165354D02*
X148110D01*
G01X165354Y208031D02*
X197638D01*
G01X156693D02*
X161417D01*
G01X150866Y204822D02*
X149291D01*
G01X165354Y204803D02*
X197638D01*
G01X161417D02*
X156693D01*
G01X165354Y204704D02*
X195877D01*
G01X148110D02*
X165354D01*
G01X149291Y204626D02*
X150598D01*
G01X150364Y204429D02*
X150632D01*
G01X149660Y204166D02*
X149828D01*
G01X149794Y203969D02*
X149694D01*
G01X150397Y203248D02*
X150464D01*
G01X165354Y203130D02*
X195877D01*
G01X165354D02*
X148110D01*
G01X150498Y203051D02*
X150364D01*
G01X165354Y203031D02*
X197638D01*
G01X156693D02*
X161417D01*
G01X168012Y200098D02*
X196457D01*
G01X165354D02*
X166634D01*
G01X165354D02*
X145669D01*
G01Y198326D02*
X165354D01*
G01X145669Y195177D02*
X195669D01*
G01X166142Y192224D02*
X177165D01*
G01X145669D02*
X166142D01*
G01X199606Y188011D02*
X166142D01*
G01X199606Y186830D02*
X145669D01*
G01X157480Y184862D02*
X177165D01*
G01X141732Y182893D02*
X153543D01*
G01X177165Y181771D02*
X157480D01*
G01Y180787D02*
X177165D01*
G01X176969Y180590D02*
X157677D01*
G01X176969Y179015D02*
X157677D01*
G01X177165Y178819D02*
X157480D01*
G01Y177834D02*
X177165D01*
G01X157480Y175846D02*
X177165D01*
G01X157480Y173878D02*
X177165D01*
G01X181102Y169941D02*
X153543D01*
G01X150598Y204035D02*
X150732Y203937D01*
G01X149895Y203904D02*
X149794Y203969D01*
G01X149593Y202985D02*
X149426Y203083D01*
G01X150565Y203838D02*
X150498Y203871D01*
G01X149828Y204166D02*
X149961Y204101D01*
G01X153543Y230984D02*
X156693Y229803D01*
G01X153543Y225984D02*
X156693Y224803D01*
G01X153543Y220984D02*
X156693Y219803D01*
G01X153543Y215984D02*
X156693Y214803D01*
G01X153543Y210984D02*
X156693Y209803D01*
G01X153543Y205984D02*
X156693Y204803D01*
G01X150498Y204068D02*
X150598Y204035D01*
G01X150297Y203280D02*
X150397Y203248D01*
G01X149626Y203182D02*
X149727Y203149D01*
G01X150364Y203051D02*
X150230Y203083D01*
G01X149727Y202952D02*
X149593Y202985D01*
G01X162992Y236279D02*
X160630Y235590D01*
G01X162992Y239429D02*
X160630Y238740D01*
G01X162992Y242578D02*
X160630Y241889D01*
G01X162992Y245728D02*
X160630Y245039D01*
G01X162992Y248878D02*
X160630Y248189D01*
G01X162992Y252027D02*
X160630Y251338D01*
G01X162992Y255177D02*
X160630Y254488D01*
G01X157748Y235964D02*
X157848Y235997D01*
G01X150336Y258976D02*
X150437Y259009D01*
G01X150403Y259206D02*
X150302Y259173D01*
G01X156693Y263031D02*
X153543Y261850D01*
G01X156693Y268031D02*
X153543Y266850D01*
G01X156693Y278031D02*
X153543Y276850D01*
G01X157915Y237244D02*
X157748Y237178D01*
G01X157245Y237211D02*
X157078Y237145D01*
G01X156809Y238261D02*
X156977Y238326D01*
G01X156693Y283031D02*
X153543Y281850D01*
G01X156693Y288031D02*
X153543Y286850D01*
G01X156693Y293031D02*
X153543Y291850D01*
G01X156693Y298031D02*
X153543Y296850D01*
G01X156693Y303031D02*
X153543Y301850D01*
G01X156693Y308031D02*
X153543Y306850D01*
G01X156809Y236817D02*
X156944Y236883D01*
G01X157513Y238228D02*
X157647Y238294D01*
G01X156977Y236686D02*
X156876Y236620D01*
G01X157848Y237408D02*
X157748Y237342D01*
G01X157580Y238064D02*
X157681Y238130D01*
G01X157211Y237408D02*
X157078Y237309D01*
G01X156843Y238064D02*
X156977Y238162D01*
G01X150302Y259173D02*
X150169Y259074D01*
G01X150671Y259468D02*
X150906Y259665D01*
G01X150638D02*
X150403Y259468D01*
G01X158049Y235932D02*
X157915Y235800D01*
G01X158016Y237342D02*
X157915Y237244D01*
G01X156676Y236686D02*
X156809Y236817D01*
G01X157413Y238130D02*
X157513Y238228D01*
G01X156709Y238162D02*
X156809Y238261D01*
G01X150269Y258910D02*
X150336Y258976D01*
G01X157949Y237539D02*
X157848Y237408D01*
G01X157346Y237342D02*
X157245Y237211D01*
G01X157480Y237933D02*
X157580Y238064D01*
G01X150169Y259074D02*
X150068Y258943D01*
G01X157848Y235997D02*
X157915Y236095D01*
G01X156876Y236620D02*
X156809Y236522D01*
G01X158116Y237506D02*
X158016Y237342D01*
G01X156608Y237998D02*
X156709Y238162D01*
G01X158116Y236063D02*
X158049Y235932D01*
G01X157379Y237408D02*
X157346Y237342D01*
G01X157279Y237539D02*
X157211Y237408D01*
G01X157379Y238064D02*
X157413Y238130D01*
G01X156608Y236555D02*
X156676Y236686D01*
G01X156776Y237933D02*
X156843Y238064D01*
G01X157915Y236095D02*
X157949Y236194D01*
G01X150235Y258812D02*
X150269Y258910D01*
G01X158150Y236194D02*
X158116Y236063D01*
G01X157982Y237670D02*
X157954Y237559D01*
G01D02*
X157949Y237539D01*
G01X157446Y237802D02*
X157480Y237933D01*
G01X157284Y237559D02*
X157279Y237539D01*
G01X157312Y237670D02*
X157284Y237559D01*
G01X156809Y236522D02*
X156776Y236391D01*
G01X156743Y237802D02*
X156776Y237933D01*
G01X158150Y237670D02*
X158127Y237559D01*
G01D02*
X158116Y237506D01*
G01X156575Y236391D02*
X156608Y236555D01*
G01X156575Y237834D02*
X156608Y237998D01*
G01X150068Y258943D02*
X150035Y258779D01*
G01X168110Y234212D02*
Y258622D01*
G01X166535Y311555D02*
Y316279D01*
G01Y271555D02*
Y276279D01*
G01X165354Y314704D02*
Y334508D01*
G01Y274704D02*
Y313130D01*
G01Y256456D02*
Y273130D01*
G01Y239527D02*
Y237559D01*
G01D02*
Y236378D01*
G01Y242677D02*
Y240708D01*
G01D02*
Y239527D01*
G01Y243858D02*
Y242677D01*
G01Y245826D02*
Y243858D01*
G01Y248976D02*
Y247008D01*
G01D02*
Y245826D01*
G01Y252126D02*
Y250157D01*
G01D02*
Y248976D01*
G01Y253307D02*
Y252126D01*
G01Y255275D02*
Y253307D01*
G01Y256456D02*
Y255275D01*
G01Y274704D02*
Y273130D01*
G01Y314704D02*
Y313130D01*
G01X163465Y255275D02*
Y256456D01*
G01Y252126D02*
Y253307D01*
G01Y248976D02*
Y250157D01*
G01Y245826D02*
Y247008D01*
G01Y239527D02*
Y240708D01*
G01Y242677D02*
Y243858D01*
G01Y236378D02*
Y237559D01*
G01X163386Y314704D02*
Y314803D01*
G01Y313031D02*
Y313130D01*
G01D02*
Y314704D01*
G01Y274704D02*
Y274803D01*
G01Y273031D02*
Y273130D01*
G01D02*
Y274704D01*
G01X161890Y255275D02*
Y256456D01*
G01Y252126D02*
Y253307D01*
G01Y248976D02*
Y250157D01*
G01Y245826D02*
Y247008D01*
G01Y242677D02*
Y243858D01*
G01Y239527D02*
Y240708D01*
G01Y236378D02*
Y237559D01*
G01X161417Y309704D02*
Y309803D01*
G01Y308031D02*
Y308130D01*
G01D02*
Y309704D01*
G01Y304704D02*
Y304803D01*
G01Y303031D02*
Y303130D01*
G01D02*
Y304704D01*
G01Y299704D02*
Y299803D01*
G01Y298031D02*
Y298130D01*
G01D02*
Y299704D01*
G01Y294704D02*
Y294803D01*
G01Y293031D02*
Y293130D01*
G01D02*
Y294704D01*
G01Y289704D02*
Y289803D01*
G01Y288031D02*
Y288130D01*
G01D02*
Y289704D01*
G01Y284704D02*
Y284803D01*
G01Y283031D02*
Y283130D01*
G01D02*
Y284704D01*
G01Y279704D02*
Y279803D01*
G01Y278031D02*
Y278130D01*
G01D02*
Y279704D01*
G01Y269704D02*
Y269803D01*
G01Y268130D02*
Y269704D01*
G01Y268031D02*
Y268130D01*
G01Y264704D02*
Y264803D01*
G01Y263130D02*
Y264704D01*
G01Y263031D02*
Y263130D01*
G01Y259704D02*
Y259803D01*
G01Y258130D02*
Y259704D01*
G01Y258031D02*
Y258130D01*
G01Y234704D02*
Y234803D01*
G01Y233031D02*
Y233130D01*
G01D02*
Y234704D01*
G01X161102Y237559D02*
Y236378D01*
G01Y240708D02*
Y239527D01*
G01Y243858D02*
Y242677D01*
G01Y247008D02*
Y245826D01*
G01Y250157D02*
Y248976D01*
G01Y253307D02*
Y252126D01*
G01Y256456D02*
Y255275D01*
G01X160709Y237559D02*
Y236378D01*
G01Y240708D02*
Y239527D01*
G01Y243858D02*
Y242677D01*
G01Y247008D02*
Y245826D01*
G01Y253307D02*
Y252126D01*
G01Y250157D02*
Y248976D01*
G01Y256456D02*
Y255275D01*
G01X160630Y257244D02*
Y257441D01*
G01Y254094D02*
Y254488D01*
G01Y250945D02*
Y251338D01*
G01Y244645D02*
Y245039D01*
G01Y247795D02*
Y248189D01*
G01Y241496D02*
Y241889D01*
G01Y235393D02*
Y235590D01*
G01Y238346D02*
Y238740D01*
G01X158465Y262795D02*
Y260039D01*
G01Y287795D02*
Y285039D01*
G01Y312795D02*
Y310039D01*
G01X158150Y236358D02*
Y236194D01*
G01Y237802D02*
Y237670D01*
G01X157982Y237802D02*
Y237670D01*
G01X157949Y236194D02*
Y236378D01*
G01D02*
Y236391D01*
G01X157781Y236587D02*
Y236784D01*
G01X157480Y236378D02*
Y236194D01*
G01Y236391D02*
Y236378D01*
G01X157446Y237670D02*
Y237802D01*
G01X157312D02*
Y237670D01*
G01X157284Y257441D02*
Y258031D01*
G01Y234803D02*
Y235393D01*
G01X157279Y236194D02*
Y236378D01*
G01D02*
Y236391D01*
G01X157011Y235866D02*
Y235669D01*
G01X156776Y236378D02*
Y236128D01*
G01Y236391D02*
Y236378D01*
G01X156743Y237670D02*
Y237802D01*
G01X156575Y236128D02*
Y236378D01*
G01Y237637D02*
Y237834D01*
G01Y236378D02*
Y236391D01*
G01X156102Y255275D02*
Y256456D01*
G01Y248976D02*
Y250157D01*
G01Y252126D02*
Y253307D01*
G01Y245826D02*
Y247008D01*
G01Y239527D02*
Y240708D01*
G01Y242677D02*
Y243858D01*
G01Y236378D02*
Y237559D01*
G01X155787Y313130D02*
Y314704D01*
G01Y308130D02*
Y309704D01*
G01Y303130D02*
Y304704D01*
G01Y298130D02*
Y299704D01*
G01Y293130D02*
Y294704D01*
G01Y288130D02*
Y289704D01*
G01Y283130D02*
Y284704D01*
G01Y278130D02*
Y279704D01*
G01Y273130D02*
Y274704D01*
G01Y268130D02*
Y269704D01*
G01Y263130D02*
Y264704D01*
G01Y258130D02*
Y259704D01*
G01Y233130D02*
Y234704D01*
G01X154213Y313130D02*
Y314704D01*
G01Y308130D02*
Y309704D01*
G01Y303130D02*
Y304704D01*
G01Y298130D02*
Y299704D01*
G01Y293130D02*
Y294704D01*
G01Y288130D02*
Y289704D01*
G01Y283130D02*
Y284704D01*
G01Y278130D02*
Y279704D01*
G01Y273130D02*
Y274704D01*
G01Y268130D02*
Y269704D01*
G01Y263130D02*
Y264704D01*
G01Y258130D02*
Y259704D01*
G01Y233130D02*
Y234704D01*
G01X153543Y310984D02*
Y311850D01*
G01Y305984D02*
Y306850D01*
G01Y300984D02*
Y301850D01*
G01Y295984D02*
Y296850D01*
G01Y290984D02*
Y291850D01*
G01Y285984D02*
Y286850D01*
G01Y280984D02*
Y281850D01*
G01Y275984D02*
Y276850D01*
G01Y270984D02*
Y271850D01*
G01Y265984D02*
Y266850D01*
G01Y260984D02*
Y261850D01*
G01X153425Y234704D02*
Y233130D01*
G01Y259704D02*
Y258130D01*
G01Y264704D02*
Y263130D01*
G01Y269704D02*
Y268130D01*
G01Y274704D02*
Y273130D01*
G01Y279704D02*
Y278130D01*
G01Y284704D02*
Y283130D01*
G01Y289704D02*
Y288130D01*
G01Y294704D02*
Y293130D01*
G01Y299704D02*
Y298130D01*
G01Y304704D02*
Y303130D01*
G01Y309704D02*
Y308130D01*
G01Y314704D02*
Y313130D01*
G01X153032Y234704D02*
Y233130D01*
G01Y259704D02*
Y258130D01*
G01Y264704D02*
Y263130D01*
G01Y269704D02*
Y268130D01*
G01Y274704D02*
Y273130D01*
G01Y279704D02*
Y278130D01*
G01Y284704D02*
Y283130D01*
G01Y289704D02*
Y288130D01*
G01Y294704D02*
Y293130D01*
G01Y299704D02*
Y298130D01*
G01Y304704D02*
Y303130D01*
G01Y309704D02*
Y308130D01*
G01Y314704D02*
Y313130D01*
G01X150906Y259704D02*
Y259862D01*
G01Y259665D02*
Y259704D01*
G01Y257992D02*
Y258130D01*
G01D02*
Y258779D01*
G01X150738Y258812D02*
Y258189D01*
G01X150235D02*
Y258812D01*
G01X150035Y258779D02*
Y258189D01*
G01X149331Y258130D02*
Y257992D01*
G01Y258189D02*
Y258130D01*
G01Y259862D02*
Y259704D01*
G01D02*
Y259665D01*
G01X148110Y308130D02*
Y309704D01*
G01Y303130D02*
Y304704D01*
G01Y298130D02*
Y299704D01*
G01Y293130D02*
Y294704D01*
G01Y288130D02*
Y289704D01*
G01Y283130D02*
Y284704D01*
G01Y278130D02*
Y279704D01*
G01Y268130D02*
Y269704D01*
G01Y263130D02*
Y264704D01*
G01Y233130D02*
Y234704D01*
G01X146654Y313130D02*
Y314704D01*
G01Y273130D02*
Y274704D01*
G01Y258130D02*
Y259704D01*
G01X158116Y237965D02*
X158150Y237802D01*
G01X158146Y236378D02*
X158150Y236358D01*
G01X158116Y236522D02*
X158146Y236378D01*
G01X157446Y236555D02*
X157480Y236391D01*
G01X156591Y237559D02*
X156575Y237637D01*
G01X156608Y237473D02*
X156591Y237559D01*
G01X156608Y235964D02*
X156575Y236128D01*
G01X150906Y258779D02*
X150872Y258943D01*
G01X157949Y237933D02*
X157982Y237802D01*
G01X157474Y237559D02*
X157446Y237670D01*
G01X157480Y237539D02*
X157474Y237559D01*
G01X157279Y237933D02*
X157312Y237802D01*
G01X157279Y236391D02*
X157245Y236522D01*
G01X157312Y236063D02*
X157279Y236194D01*
G01X156771Y237559D02*
X156743Y237670D01*
G01X156776Y237539D02*
X156771Y237559D01*
G01X156776Y236128D02*
X156809Y235997D01*
G01X150705Y258910D02*
X150738Y258812D01*
G01X157949Y236391D02*
X157915Y236489D01*
G01X157480Y236194D02*
X157513Y236095D01*
G01X158661Y313031D02*
X153543Y311850D01*
G01X157346Y238130D02*
X157379Y238064D01*
G01X157211D02*
X157279Y237933D01*
G01X157413Y237342D02*
X157379Y237408D01*
G01Y236686D02*
X157446Y236555D01*
G01X156843Y237408D02*
X156776Y237539D01*
G01X157379Y235932D02*
X157312Y236063D01*
G01X158661Y273031D02*
X153543Y271850D01*
G01X157915Y235800D02*
X157781Y235767D01*
G01X158016Y238130D02*
X158116Y237965D01*
G01X156709Y237309D02*
X156608Y237473D01*
G01X156709Y235800D02*
X156608Y235964D01*
G01X157245Y236522D02*
X157178Y236620D01*
G01X157513Y236095D02*
X157580Y235997D01*
G01X150872Y258943D02*
X150772Y259074D01*
G01X157848Y238064D02*
X157949Y237933D01*
G01X157245Y238261D02*
X157346Y238130D01*
G01X157580Y237408D02*
X157480Y237539D01*
G01X158016Y236653D02*
X158116Y236522D01*
G01X153543Y315984D02*
X158661Y314803D01*
G01X163386D02*
X158661D01*
G01X197638D02*
X166535D01*
G01Y314704D02*
X195877D01*
G01X146654D02*
X166535D01*
G01Y313130D02*
X195877D01*
G01X146654D02*
X166535D01*
G01Y313031D02*
X197638D01*
G01X158661D02*
X163386D01*
G01X158465Y312795D02*
X165354D01*
G01Y311555D02*
X166535D01*
G01X165354Y310039D02*
X158465D01*
G01X165354Y309803D02*
X197638D01*
G01X161417D02*
X156693D01*
G01X165354Y309704D02*
X195877D01*
G01X148110D02*
X165354D01*
G01Y308130D02*
X195877D01*
G01X165354D02*
X148110D01*
G01X165354Y308031D02*
X197638D01*
G01X156693D02*
X161417D01*
G01X165354Y304803D02*
X197638D01*
G01X161417D02*
X156693D01*
G01X165354Y304704D02*
X195877D01*
G01X148110D02*
X165354D01*
G01Y303130D02*
X195877D01*
G01X165354D02*
X148110D01*
G01X165354Y303031D02*
X197638D01*
G01X156693D02*
X161417D01*
G01X165354Y299803D02*
X197638D01*
G01X161417D02*
X156693D01*
G01X165354Y299704D02*
X195877D01*
G01X148110D02*
X165354D01*
G01Y298130D02*
X195877D01*
G01X165354D02*
X148110D01*
G01X165354Y298031D02*
X197638D01*
G01X156693D02*
X161417D01*
G01X165354Y294803D02*
X197638D01*
G01X161417D02*
X156693D01*
G01X165354Y294704D02*
X195877D01*
G01X148110D02*
X165354D01*
G01Y293130D02*
X195877D01*
G01X165354D02*
X148110D01*
G01X165354Y293031D02*
X197638D01*
G01X156693D02*
X161417D01*
G01X165354Y289803D02*
X197638D01*
G01X161417D02*
X156693D01*
G01X165354Y289704D02*
X195877D01*
G01X148110D02*
X165354D01*
G01Y288130D02*
X195877D01*
G01X165354D02*
X148110D01*
G01X165354Y288031D02*
X197638D01*
G01X156693D02*
X161417D01*
G01X158465Y287795D02*
X165354D01*
G01Y285039D02*
X158465D01*
G01X165354Y284803D02*
X197638D01*
G01X161417D02*
X156693D01*
G01X165354Y284704D02*
X195877D01*
G01X148110D02*
X165354D01*
G01Y283130D02*
X195877D01*
G01X165354D02*
X148110D01*
G01X165354Y283031D02*
X197638D01*
G01X156693D02*
X161417D01*
G01X165354Y279803D02*
X197638D01*
G01X161417D02*
X156693D01*
G01X165354Y279704D02*
X195877D01*
G01X148110D02*
X165354D01*
G01Y278130D02*
X195877D01*
G01X165354D02*
X148110D01*
G01X165354Y278031D02*
X197638D01*
G01X156693D02*
X161417D01*
G01X166535Y276279D02*
X165354D01*
G01X163386Y274803D02*
X158661D01*
G01X197638D02*
X166535D01*
G01Y274704D02*
X195877D01*
G01X146654D02*
X166535D01*
G01Y273130D02*
X195877D01*
G01X146654D02*
X166535D01*
G01Y273031D02*
X197638D01*
G01X158661D02*
X163386D01*
G01X165354Y271555D02*
X166535D01*
G01X165354Y269803D02*
X197638D01*
G01X161417D02*
X156693D01*
G01X165354Y269704D02*
X195877D01*
G01X148110D02*
X165354D01*
G01Y268130D02*
X195877D01*
G01X165354D02*
X148110D01*
G01X165354Y268031D02*
X197638D01*
G01X156693D02*
X161417D01*
G01X165354Y264803D02*
X197638D01*
G01X161417D02*
X156693D01*
G01X165354Y264704D02*
X195877D01*
G01X148110D02*
X165354D01*
G01Y263130D02*
X148110D01*
G01X195877D02*
X165354D01*
G01Y263031D02*
X197638D01*
G01X156693D02*
X161417D01*
G01X158465Y262795D02*
X165354D01*
G01Y260039D02*
X158465D01*
G01X150906Y259862D02*
X149331D01*
G01X165354Y259803D02*
X194685D01*
G01X161417D02*
X156693D01*
G01X165354Y259704D02*
X195756D01*
G01X146654D02*
X165354D01*
G01X149331Y259665D02*
X150638D01*
G01X150403Y259468D02*
X150671D01*
G01X150537Y259206D02*
X150403D01*
G01X150437Y259009D02*
X150537D01*
G01X165354Y258622D02*
X197638D01*
G01X150738Y258189D02*
X150235D01*
G01X150035D02*
X149331D01*
G01X165354Y258130D02*
X195756D01*
G01X146654D02*
X165354D01*
G01Y258031D02*
X194685D01*
G01X157284D02*
X161417D01*
G01X149331Y257992D02*
X150906D01*
G01X160630Y257441D02*
X157284D01*
G01X168110Y256555D02*
X197441D01*
G01X162992D02*
X165354D01*
G01X168110Y256456D02*
X194215D01*
G01X156102D02*
X168110D01*
G01X177165Y256181D02*
X195669D01*
G01X156102Y255275D02*
X168110D01*
G01X194215D02*
X168110D01*
G01Y255177D02*
X197441D01*
G01X162992D02*
X165354D01*
G01X168110Y253405D02*
X197441D01*
G01X162992D02*
X165354D01*
G01X168110Y253307D02*
X194215D01*
G01X156102D02*
X168110D01*
G01X156102Y252126D02*
X168110D01*
G01X194215D02*
X168110D01*
G01Y252027D02*
X197441D01*
G01X162992D02*
X165354D01*
G01X168110Y250256D02*
X197441D01*
G01X162992D02*
X165354D01*
G01X168110Y250157D02*
X194215D01*
G01X156102D02*
X168110D01*
G01X156102Y248976D02*
X168110D01*
G01X194215D02*
X168110D01*
G01Y248878D02*
X197441D01*
G01X162992D02*
X165354D01*
G01X168110Y247106D02*
X197441D01*
G01X162992D02*
X165354D01*
G01X168110Y247008D02*
X194215D01*
G01X156102D02*
X168110D01*
G01X156102Y245826D02*
X168110D01*
G01X194215D02*
X168110D01*
G01Y245728D02*
X197441D01*
G01X162992D02*
X165354D01*
G01X150638Y258976D02*
X150705Y258910D01*
G01X157915Y238228D02*
X158016Y238130D01*
G01X157513Y237244D02*
X157413Y237342D01*
G01X157915Y236489D02*
X157848Y236555D01*
G01X157245Y236817D02*
X157379Y236686D01*
G01X156809Y237211D02*
X156709Y237309D01*
G01X157513Y235800D02*
X157379Y235932D01*
G01X156809Y235997D02*
X156910Y235898D01*
G01X150772Y259074D02*
X150638Y259173D01*
G01X157078Y238162D02*
X157211Y238064D01*
G01X157882Y236752D02*
X158016Y236653D01*
G01X156977Y237309D02*
X156843Y237408D01*
G01X153543Y310984D02*
X156693Y309803D01*
G01X153543Y305984D02*
X156693Y304803D01*
G01X153543Y300984D02*
X156693Y299803D01*
G01X153543Y295984D02*
X156693Y294803D01*
G01X153543Y290984D02*
X156693Y289803D01*
G01X153543Y285984D02*
X156693Y284803D01*
G01X153543Y280984D02*
X156693Y279803D01*
G01X153543Y270984D02*
X156693Y269803D01*
G01X153543Y265984D02*
X156693Y264803D01*
G01X153543Y260984D02*
X156693Y259803D01*
G01X150638Y259173D02*
X150537Y259206D01*
G01Y259009D02*
X150638Y258976D01*
G01X160630Y257244D02*
X162992Y256555D01*
G01X160630Y254094D02*
X162992Y253405D01*
G01X160630Y250945D02*
X162992Y250256D01*
G01X160630Y247795D02*
X162992Y247106D01*
G01X160630Y244645D02*
X162992Y243956D01*
G01X160630Y241496D02*
X162992Y240807D01*
G01X157647Y235767D02*
X157513Y235800D01*
G01X157011Y235669D02*
X156876Y235702D01*
G01X153543Y275984D02*
X158661Y274803D01*
G01X168110Y243956D02*
X197441D01*
G01X162992D02*
X165354D01*
G01X168110Y243858D02*
X194215D01*
G01X156102D02*
X168110D01*
G01X156102Y242677D02*
X168110D01*
G01X194215D02*
X168110D01*
G01Y242578D02*
X197441D01*
G01X162992D02*
X165354D01*
G01X168110Y240807D02*
X197441D01*
G01X162992D02*
X165354D01*
G01X168110Y240708D02*
X194215D01*
G01X156102D02*
X168110D01*
G01X156102Y239527D02*
X168110D01*
G01X194215D02*
X168110D01*
G01Y239429D02*
X197441D01*
G01X162992D02*
X165354D01*
G01X156977Y238326D02*
X157078D01*
G01X157647Y238294D02*
X157748D01*
G01X156977Y238162D02*
X157078D01*
G01X157681Y238130D02*
X157748D01*
G01X162992Y237657D02*
X165354D01*
G01X197441D02*
X168110D01*
G01Y237559D02*
X194215D01*
G01X156102D02*
X168110D01*
G01X157748Y237342D02*
X157681D01*
G01X157078Y237309D02*
X156977D01*
G01X157748Y237178D02*
X157647D01*
G01X157078Y237145D02*
X156977D01*
G01X156944Y236883D02*
X157111D01*
G01X157078Y236686D02*
X156977D01*
G01X195669Y236653D02*
X177165D01*
G01X156102Y236378D02*
X168110D01*
G01X194215D02*
X168110D01*
G01X162992Y236279D02*
X165354D01*
G01X197441D02*
X168110D01*
G01X157681Y235964D02*
X157748D01*
G01X157781Y235767D02*
X157647D01*
G01X157284Y235393D02*
X160630D01*
G01X161417Y234803D02*
X157284D01*
G01X194685D02*
X165354D01*
G01Y234704D02*
X195756D01*
G01X148110D02*
X165354D01*
G01Y234212D02*
X197638D01*
G01X165354Y233130D02*
X148110D01*
G01X195756D02*
X165354D01*
G01Y233031D02*
X194685D01*
G01X156693D02*
X161417D01*
G01X157748Y238130D02*
X157848Y238064D01*
G01X157681Y237342D02*
X157580Y237408D01*
G01X157178Y236620D02*
X157078Y236686D01*
G01X156876Y235702D02*
X156709Y235800D01*
G01X157647Y237178D02*
X157513Y237244D01*
G01X157848Y236555D02*
X157781Y236587D01*
G01X157111Y236883D02*
X157245Y236817D01*
G01X157748Y238294D02*
X157915Y238228D01*
G01X157078Y238326D02*
X157245Y238261D01*
G01X156977Y237145D02*
X156809Y237211D01*
G01X157781Y236784D02*
X157882Y236752D01*
G01X157580Y235997D02*
X157681Y235964D01*
G01X156910Y235898D02*
X157011Y235866D01*
G01X160630Y238346D02*
X162992Y237657D01*
G01X171063Y353031D02*
G03I-3740J0D01*
G01X156054Y342795D02*
G03Y339645I2017J-1575D01*
G01X160088D02*
G03Y342795I-2017J1575D01*
G01X160441Y338858D02*
G03Y343582I-2370J2362D01*
G01X155701D02*
G03Y338858I2370J-2362D01*
G01X161575Y341220D02*
G03I-3504J0D01*
G01X160748Y338070D02*
G03Y344370I-2677J3150D01*
G01X155394D02*
G03Y338070I2677J-3150D01*
G01X156693Y318031D02*
X153543Y316850D01*
G01X156693Y323031D02*
X153543Y321850D01*
G01X156693Y328031D02*
X153543Y326850D01*
G01X177165Y346004D02*
Y358956D01*
G01X176969Y352244D02*
Y353819D01*
G01X171614D02*
Y352244D01*
G01X170276Y353819D02*
Y354015D01*
G01Y352047D02*
Y352244D01*
G01Y353819D02*
Y352244D01*
G01X170079Y353819D02*
Y352244D01*
G01X168504Y353819D02*
Y352244D01*
G01X166142Y337657D02*
Y346004D01*
G01Y353819D02*
Y352244D01*
G01X164567D02*
Y353819D01*
G01X164370D02*
Y354015D01*
G01Y352244D02*
Y353819D01*
G01Y352244D02*
Y352047D01*
G01X163032Y352244D02*
Y353819D01*
G01X161417Y329704D02*
Y329803D01*
G01Y328130D02*
Y329704D01*
G01Y328031D02*
Y328130D01*
G01Y324704D02*
Y324803D01*
G01Y323130D02*
Y324704D01*
G01Y323031D02*
Y323130D01*
G01Y319704D02*
Y319803D01*
G01Y318130D02*
Y319704D01*
G01Y318031D02*
Y318130D01*
G01X157677Y353819D02*
Y352244D01*
G01X157480Y346004D02*
Y358956D01*
G01X155787Y328130D02*
Y329704D01*
G01Y323130D02*
Y324704D01*
G01Y318130D02*
Y319704D01*
G01X154213Y328130D02*
Y329704D01*
G01Y323130D02*
Y324704D01*
G01Y318130D02*
Y319704D01*
G01X153543Y349941D02*
Y362893D01*
G01Y330984D02*
Y332736D01*
G01Y325984D02*
Y326850D01*
G01Y320984D02*
Y321850D01*
G01Y315984D02*
Y316850D01*
G01X153425Y319704D02*
Y318130D01*
G01Y324704D02*
Y323130D01*
G01Y329704D02*
Y328130D01*
G01X153032Y319704D02*
Y318130D01*
G01Y324704D02*
Y323130D01*
G01Y329704D02*
Y328130D01*
G01X148110D02*
Y329704D01*
G01Y323130D02*
Y324704D01*
G01Y318130D02*
Y319704D01*
G01X145669Y332736D02*
Y346004D01*
G01X153543Y362893D02*
X181102D01*
G01X177165Y358956D02*
X157480D01*
G01X177165Y356988D02*
X157480D01*
G01X177165Y355000D02*
X157480D01*
G01Y354015D02*
X177165D01*
G01X176969Y353819D02*
X157677D01*
G01X176969Y352244D02*
X157677D01*
G01X177165Y352047D02*
X157480D01*
G01Y351063D02*
X177165D01*
G01X153543Y349941D02*
X141732D01*
G01X177165Y347972D02*
X157480D01*
G01X199606Y346004D02*
X145669D01*
G01X166142Y344822D02*
X199606D01*
G01X155394Y344370D02*
X160748D01*
G01X160441Y343582D02*
X155701D01*
G01X156054Y342795D02*
X160088D01*
G01X166142Y340610D02*
X145669D01*
G01X177165D02*
X166142D01*
G01X156054Y339645D02*
X160088D01*
G01X155701Y338858D02*
X160441D01*
G01X160748Y338070D02*
X155394D01*
G01X195669Y337657D02*
X145669D01*
G01X165354Y334508D02*
X145669D01*
G01Y332736D02*
X165354D01*
G01D02*
X166634D01*
G01X196457D02*
X168012D01*
G01X161417Y329803D02*
X156693D01*
G01X197638D02*
X165354D01*
G01Y329704D02*
X195877D01*
G01X148110D02*
X165354D01*
G01Y328130D02*
X195877D01*
G01X165354D02*
X148110D01*
G01X165354Y328031D02*
X197638D01*
G01X156693D02*
X161417D01*
G01X165354Y324803D02*
X197638D01*
G01X161417D02*
X156693D01*
G01X165354Y324704D02*
X195877D01*
G01X148110D02*
X165354D01*
G01Y323130D02*
X195877D01*
G01X165354D02*
X148110D01*
G01X165354Y323031D02*
X197638D01*
G01X156693D02*
X161417D01*
G01X153543Y330984D02*
X156693Y329803D01*
G01X165354Y319803D02*
X197638D01*
G01X161417D02*
X156693D01*
G01X165354Y319704D02*
X195877D01*
G01X148110D02*
X165354D01*
G01Y318130D02*
X195877D01*
G01X165354D02*
X148110D01*
G01X165354Y318031D02*
X197638D01*
G01X156693D02*
X161417D01*
G01X166535Y316279D02*
X165354D01*
G01X153543Y325984D02*
X156693Y324803D01*
G01X153543Y320984D02*
X156693Y319803D01*
G01X177755Y528091D02*
X157676D01*
G01X169487Y532028D02*
X168503D01*
G01X166928D02*
X165944D01*
G01X164369D02*
X163385D01*
G01X169487Y533915D02*
X168503D01*
G01X164369D02*
X163385D01*
G01X166928D02*
X165944D01*
G01X169487Y533996D02*
X168503D01*
G01X164369D02*
X163385D01*
G01X166928D02*
X165944D01*
G01X169487Y535391D02*
X168503D01*
G01X164369D02*
X163385D01*
G01X166928D02*
X165944D01*
G01X169487Y535472D02*
X168503D01*
G01X164369D02*
X163385D01*
G01X166928D02*
X165944D01*
G01X161613Y535669D02*
X173818D01*
G01X157676Y554665D02*
Y528091D01*
G01X161613Y547087D02*
Y535669D01*
G01X163385Y532028D02*
Y535669D01*
G01X164369Y532028D02*
Y535669D01*
G01X165944Y532028D02*
Y535669D01*
G01X166928Y532028D02*
Y535669D01*
G01X168503Y532028D02*
Y535669D01*
G01X169487Y532028D02*
Y535669D01*
G01X173818Y547087D02*
X161613D01*
G01X169487Y547283D02*
X168503D01*
G01X164369D02*
X163385D01*
G01X166928D02*
X165944D01*
G01X169487Y547365D02*
X168503D01*
G01X164369D02*
X163385D01*
G01X166928D02*
X165944D01*
G01X169487Y548760D02*
X168503D01*
G01X164369D02*
X163385D01*
G01X166928D02*
X165944D01*
G01X169487Y548841D02*
X168503D01*
G01X164369D02*
X163385D01*
G01X166928D02*
X165944D01*
G01X169487Y550728D02*
X168503D01*
G01X166928D02*
X165944D01*
G01X164369D02*
X163385D01*
G01X177755Y554665D02*
X157676D01*
G01X163385Y547087D02*
Y550728D01*
G01X164369Y547087D02*
Y550728D01*
G01X165944Y547087D02*
Y550728D01*
G01X166928Y547087D02*
Y550728D01*
G01X168503Y547087D02*
Y550728D01*
G01X169487Y547087D02*
Y550728D01*
G01X172046Y532028D02*
X171062D01*
G01X172046Y533915D02*
X171062D01*
G01X172046Y533996D02*
X171062D01*
G01X172046Y535391D02*
X171062D01*
G01X172046Y535472D02*
X171062D01*
G01Y532028D02*
Y535669D01*
G01X172046Y532028D02*
Y535669D01*
G01X173818D02*
Y547087D01*
G01X172243Y545315D02*
G03I-590J0D01*
G01X172176Y548415D02*
X172118Y548465D01*
G01X172184D02*
X172243Y548415D01*
G01X172046Y547283D02*
X171062D01*
G01X172046Y547365D02*
X171062D01*
G01X172046Y548366D02*
X171849D01*
G01X172243D02*
X172046D01*
G01X171849Y548415D02*
X172046D01*
G01D02*
X172176D01*
G01X172118Y548465D02*
X172184D01*
G01X172046Y548760D02*
X171062D01*
G01X172046Y548841D02*
X171062D01*
G01X172046Y550728D02*
X171062D01*
G01Y547087D02*
Y550728D01*
G01X171849Y548366D02*
Y548415D01*
G01X172046Y547087D02*
Y550728D01*
G01X172243Y548415D02*
Y548366D01*
G01X164172Y565000D02*
X170471D01*
G01X165747Y565295D02*
X164172D01*
G01D02*
X162597D01*
G01X168897D02*
X170471D01*
G01X162597D02*
Y567264D01*
G01X164172Y565591D02*
Y565000D01*
G01X165156Y570118D02*
Y565000D01*
G01X165353D02*
Y570118D01*
G01X165747Y567264D02*
Y565295D01*
G01X168897Y567264D02*
Y565295D01*
G01X169290Y565000D02*
Y570118D01*
G01X169487D02*
Y565000D01*
G01X164172Y565591D02*
G03Y566772I0J591D01*
G01X170471Y567264D02*
X168897D01*
G01X164172D02*
X165747D01*
G01X162597D02*
X164172D01*
G01X170471Y567854D02*
X168897D01*
G01X164172D02*
X165747D01*
G01X162597D02*
X164172D01*
G01X165747Y569823D02*
X164172D01*
G01D02*
X162597D01*
G01X168897D02*
X170471D01*
G01X164172Y570118D02*
X170471D01*
G01X162597Y569823D02*
Y567854D01*
G01X164172Y570118D02*
Y569528D01*
G01Y568346D02*
Y566772D01*
G01X165747Y567854D02*
Y569823D01*
G01X168897Y567854D02*
Y569823D01*
G01X164172Y568346D02*
G03Y569528I0J591D01*
G01X170471Y565295D02*
X172046D01*
G01X170471Y565000D02*
Y565591D01*
G01X172046Y565295D02*
Y567264D01*
G01X170471Y566772D02*
G03Y565591I1J-591D01*
G01X172046Y567264D02*
X170471D01*
G01X172046Y567854D02*
X170471D01*
G01X170461Y568598D02*
X170367D01*
G01Y569346D02*
X170461D01*
G01X170471Y569823D02*
X172046D01*
G01X170367Y568598D02*
Y569346D01*
G01X170461D02*
Y568726D01*
G01X170471Y566772D02*
Y568346D01*
G01Y569528D02*
Y570118D01*
G01X170554Y568837D02*
Y568710D01*
G01X172046Y569823D02*
Y567854D01*
G01X170461Y568726D02*
X170554Y568837D01*
G01Y568710D02*
X170461Y568598D01*
G01X170471Y569528D02*
G03Y568346I0J-591D01*
G01X157996Y601259D02*
X158071D01*
G01X158146Y592992D02*
X158071D01*
G01X171063Y585315D02*
G03I-3740J0D01*
G01X160630Y597126D02*
G03I-2559J0D01*
G01X161417D02*
G03I-3346J0D01*
G01X161575D02*
G03I-3504J0D01*
G01X158146Y592993D02*
G03X158071Y601259I-75J4133D01*
G01X157996D02*
G03X158071Y592992I74J-4133D01*
G01X162992Y641791D02*
X160630Y641102D01*
G01X150464Y608759D02*
X150565Y608792D01*
G01X162992Y644941D02*
X160630Y644252D01*
G01X157748Y641476D02*
X157848Y641509D01*
G01X156693Y608543D02*
X153543Y607362D01*
G01X156693Y613543D02*
X153543Y612362D01*
G01X156693Y618543D02*
X153543Y617362D01*
G01X156693Y623543D02*
X153543Y622362D01*
G01X156693Y628543D02*
X153543Y627362D01*
G01X156693Y633543D02*
X153543Y632362D01*
G01X156693Y638543D02*
X153543Y637362D01*
G01X157915Y642756D02*
X157748Y642690D01*
G01X157245Y642723D02*
X157078Y642657D01*
G01X156809Y643772D02*
X156977Y643838D01*
G01X149526Y609613D02*
X149660Y609678D01*
G01X156809Y642329D02*
X156944Y642395D01*
G01X157513Y643740D02*
X157647Y643806D01*
G01X149694Y609481D02*
X149593Y609416D01*
G01X156977Y642198D02*
X156876Y642132D01*
G01X157848Y642920D02*
X157748Y642854D01*
G01X157580Y643576D02*
X157681Y643641D01*
G01X157211Y642920D02*
X157078Y642821D01*
G01X156843Y643576D02*
X156977Y643674D01*
G01X150632Y609941D02*
X150866Y610137D01*
G01X150598D02*
X150364Y609941D01*
G01X150679Y608641D02*
X150632Y608595D01*
G01X150766Y608727D02*
X150679Y608641D01*
G01X149392Y609481D02*
X149526Y609613D01*
G01X158049Y641443D02*
X157915Y641312D01*
G01X158016Y642854D02*
X157915Y642756D01*
G01X156676Y642198D02*
X156809Y642329D01*
G01X157413Y643641D02*
X157513Y643740D01*
G01X156709Y643674D02*
X156809Y643772D01*
G01X157949Y643051D02*
X157848Y642920D01*
G01X157346Y642854D02*
X157245Y642723D01*
G01X157480Y643445D02*
X157580Y643576D01*
G01X150565Y608792D02*
X150632Y608891D01*
G01X149593Y609416D02*
X149526Y609317D01*
G01X157848Y641509D02*
X157915Y641607D01*
G01X156876Y642132D02*
X156809Y642034D01*
G01X158116Y643018D02*
X158016Y642854D01*
G01X156608Y643510D02*
X156709Y643674D01*
G01X150833Y608858D02*
X150766Y608727D01*
G01X149325Y609350D02*
X149392Y609481D01*
G01X158116Y641574D02*
X158049Y641443D01*
G01X157379Y642920D02*
X157346Y642854D01*
G01X157279Y643051D02*
X157211Y642920D01*
G01X157379Y643576D02*
X157413Y643641D01*
G01X156608Y642067D02*
X156676Y642198D01*
G01X156776Y643445D02*
X156843Y643576D01*
G01X157915Y641312D02*
X157781Y641279D01*
G01X150632Y608595D02*
X150498Y608563D01*
G01X150632Y608891D02*
X150665Y608989D01*
G01X157915Y641607D02*
X157949Y641706D01*
G01X150866Y608989D02*
X150833Y608858D01*
G01X158150Y641706D02*
X158116Y641574D01*
G01X149526Y609317D02*
X149493Y609186D01*
G01X157982Y643182D02*
X157954Y643070D01*
G01D02*
X157949Y643051D01*
G01X157446Y643313D02*
X157480Y643445D01*
G01X157312Y643182D02*
X157284Y643070D01*
G01D02*
X157279Y643051D01*
G01X156809Y642034D02*
X156776Y641902D01*
G01X156743Y643313D02*
X156776Y643445D01*
G01X158150Y643182D02*
X158127Y643070D01*
G01D02*
X158116Y643018D01*
G01X156575Y641902D02*
X156608Y642067D01*
G01X156575Y643346D02*
X156608Y643510D01*
G01X149291Y609186D02*
X149325Y609350D01*
G01X156102Y645039D02*
X168110D01*
G01X194215D02*
X168110D01*
G01Y644941D02*
X197441D01*
G01X162992D02*
X165354D01*
G01X156977Y643838D02*
X157078D01*
G01X157647Y643806D02*
X157748D01*
G01X156977Y643674D02*
X157078D01*
G01X157681Y643641D02*
X157748D01*
G01X162992Y643169D02*
X165354D01*
G01X197441D02*
X168110D01*
G01Y643070D02*
X194215D01*
G01X156102D02*
X168110D01*
G01X157748Y642854D02*
X157681D01*
G01X157078Y642821D02*
X156977D01*
G01X157748Y642690D02*
X157647D01*
G01X157078Y642657D02*
X156977D01*
G01X156944Y642395D02*
X157111D01*
G01X157078Y642198D02*
X156977D01*
G01X195669Y642165D02*
X177165D01*
G01X156102Y641889D02*
X168110D01*
G01X194215D02*
X168110D01*
G01X162992Y641791D02*
X165354D01*
G01X197441D02*
X168110D01*
G01X157681Y641476D02*
X157748D01*
G01X157781Y641279D02*
X157647D01*
G01X157284Y640905D02*
X160630D01*
G01X161417Y640315D02*
X157284D01*
G01X194685D02*
X165354D01*
G01Y640216D02*
X195756D01*
G01X148110D02*
X165354D01*
G01Y639724D02*
X197638D01*
G01X165354Y638641D02*
X148110D01*
G01X195756D02*
X165354D01*
G01Y638543D02*
X194685D01*
G01X156693D02*
X161417D01*
G01Y635315D02*
X156693D01*
G01X197638D02*
X165354D01*
G01Y635216D02*
X195877D01*
G01X148110D02*
X165354D01*
G01Y633641D02*
X195877D01*
G01X165354D02*
X148110D01*
G01X165354Y633543D02*
X197638D01*
G01X156693D02*
X161417D01*
G01X158465Y633307D02*
X165354D01*
G01Y630551D02*
X158465D01*
G01X165354Y630315D02*
X197638D01*
G01X161417D02*
X156693D01*
G01X165354Y630216D02*
X195877D01*
G01X148110D02*
X165354D01*
G01Y628641D02*
X195877D01*
G01X165354D02*
X148110D01*
G01X165354Y628543D02*
X197638D01*
G01X156693D02*
X161417D01*
G01X177165Y592342D02*
Y751515D01*
G01Y579389D02*
Y592342D01*
G01X176969Y584527D02*
Y586102D01*
G01X171614D02*
Y584527D01*
G01X170276Y586102D02*
Y586299D01*
G01Y584330D02*
Y584527D01*
G01Y586102D02*
Y584527D01*
G01X170079Y586102D02*
Y584527D01*
G01X169291Y738248D02*
Y605610D01*
G01X168504Y586102D02*
Y584527D01*
G01X168110Y639724D02*
Y664133D01*
G01X168012Y605610D02*
Y738248D01*
G01X166634D02*
Y605610D01*
G01X166142Y592342D02*
Y600689D01*
G01Y586102D02*
Y584527D01*
G01X165354Y603838D02*
Y641889D01*
G01Y645039D02*
Y643070D01*
G01D02*
Y641889D01*
G01Y646220D02*
Y645039D01*
G01X164567Y584527D02*
Y586102D01*
G01X164370D02*
Y586299D01*
G01Y584527D02*
Y586102D01*
G01Y584527D02*
Y584330D01*
G01X163465Y641889D02*
Y643070D01*
G01Y645039D02*
Y646220D01*
G01X163032Y584527D02*
Y586102D01*
G01X161890Y641889D02*
Y643070D01*
G01Y645039D02*
Y646220D01*
G01X161417Y640216D02*
Y640315D01*
G01Y638543D02*
Y638641D01*
G01D02*
Y640216D01*
G01Y635216D02*
Y635315D01*
G01Y633543D02*
Y633641D01*
G01D02*
Y635216D01*
G01Y630216D02*
Y630315D01*
G01Y628543D02*
Y628641D01*
G01D02*
Y630216D01*
G01Y625216D02*
Y625315D01*
G01Y623641D02*
Y625216D01*
G01Y623543D02*
Y623641D01*
G01Y620216D02*
Y620315D01*
G01Y618641D02*
Y620216D01*
G01Y618543D02*
Y618641D01*
G01Y615216D02*
Y615315D01*
G01Y613641D02*
Y615216D01*
G01Y613543D02*
Y613641D01*
G01Y610216D02*
Y610315D01*
G01Y608641D02*
Y610216D01*
G01Y608543D02*
Y608641D01*
G01X161102Y643070D02*
Y641889D01*
G01Y646220D02*
Y645039D01*
G01X160709Y643070D02*
Y641889D01*
G01Y646220D02*
Y645039D01*
G01X160630Y643858D02*
Y644252D01*
G01Y640905D02*
Y641102D01*
G01X158465Y633307D02*
Y630551D01*
G01X158150Y641870D02*
Y641706D01*
G01Y643313D02*
Y643182D01*
G01X157982Y643313D02*
Y643182D01*
G01X157949Y641706D02*
Y641889D01*
G01D02*
Y641902D01*
G01X157781Y642099D02*
Y642296D01*
G01X157677Y586102D02*
Y584527D01*
G01X157480Y579389D02*
Y592342D01*
G01Y641889D02*
Y641706D01*
G01Y641902D02*
Y641889D01*
G01X157446Y643182D02*
Y643313D01*
G01X157312D02*
Y643182D01*
G01X157284Y640315D02*
Y640905D01*
G01X157279Y641706D02*
Y641889D01*
G01D02*
Y641902D01*
G01X157011Y641378D02*
Y641181D01*
G01X156776Y641889D02*
Y641640D01*
G01Y641902D02*
Y641889D01*
G01X156743Y643182D02*
Y643313D01*
G01X156575Y643149D02*
Y643346D01*
G01Y641640D02*
Y641889D01*
G01D02*
Y641902D01*
G01X156102Y645039D02*
Y646220D01*
G01Y641889D02*
Y643070D01*
G01X155787Y638641D02*
Y640216D01*
G01Y633641D02*
Y635216D01*
G01Y628641D02*
Y630216D01*
G01Y623641D02*
Y625216D01*
G01Y618641D02*
Y620216D01*
G01Y613641D02*
Y615216D01*
G01Y608641D02*
Y610216D01*
G01X154213Y638641D02*
Y640216D01*
G01Y633641D02*
Y635216D01*
G01Y628641D02*
Y630216D01*
G01Y623641D02*
Y625216D01*
G01Y618641D02*
Y620216D01*
G01Y613641D02*
Y615216D01*
G01Y608641D02*
Y610216D01*
G01X153543Y636496D02*
Y637362D01*
G01Y631496D02*
Y632362D01*
G01Y626496D02*
Y627362D01*
G01Y621496D02*
Y622362D01*
G01Y616496D02*
Y617362D01*
G01Y611496D02*
Y612362D01*
G01Y605610D02*
Y607362D01*
G01Y575452D02*
Y588405D01*
G01X153425Y610216D02*
Y608641D01*
G01Y615216D02*
Y613641D01*
G01Y620216D02*
Y618641D01*
G01Y625216D02*
Y623641D01*
G01Y630216D02*
Y628641D01*
G01Y635216D02*
Y633641D01*
G01Y640216D02*
Y638641D01*
G01X153032Y610216D02*
Y608641D01*
G01Y615216D02*
Y613641D01*
G01Y620216D02*
Y618641D01*
G01Y625216D02*
Y623641D01*
G01Y630216D02*
Y628641D01*
G01Y635216D02*
Y633641D01*
G01Y640216D02*
Y638641D01*
G01X150866Y610216D02*
Y610334D01*
G01Y610137D02*
Y610216D01*
G01Y609153D02*
Y608989D01*
G01X150665D02*
Y609186D01*
G01X150498Y609383D02*
Y609580D01*
G01X150196Y609186D02*
Y608989D01*
G01X149995D02*
Y609186D01*
G01X149727Y608641D02*
Y608464D01*
G01Y608661D02*
Y608641D01*
G01X149493Y609186D02*
Y608924D01*
G01X149291D02*
Y609186D01*
G01Y610334D02*
Y610216D01*
G01D02*
Y610137D01*
G01X158116Y643477D02*
X158150Y643313D01*
G01X158146Y641889D02*
X158150Y641870D01*
G01X158116Y642034D02*
X158146Y641889D01*
G01X157446Y642067D02*
X157480Y641902D01*
G01X156591Y643070D02*
X156575Y643149D01*
G01X156608Y642985D02*
X156591Y643070D01*
G01X156608Y641476D02*
X156575Y641640D01*
G01X150833Y609317D02*
X150866Y609153D01*
G01X150163Y609350D02*
X150196Y609186D01*
G01X149325Y608759D02*
X149291Y608924D01*
G01X157949Y643445D02*
X157982Y643313D01*
G01X157474Y643070D02*
X157446Y643182D01*
G01X157480Y643051D02*
X157474Y643070D01*
G01X157279Y643445D02*
X157312Y643313D01*
G01X157279Y641902D02*
X157245Y642034D01*
G01X157312Y641574D02*
X157279Y641706D01*
G01X156771Y643070D02*
X156743Y643182D01*
G01X156776Y643051D02*
X156771Y643070D01*
G01X156776Y641640D02*
X156809Y641509D01*
G01X160630Y643858D02*
X162992Y643169D01*
G01X157647Y641279D02*
X157513Y641312D01*
G01X157011Y641181D02*
X156876Y641213D01*
G01X165354Y625315D02*
X197638D01*
G01X161417D02*
X156693D01*
G01X165354Y625216D02*
X195877D01*
G01X148110D02*
X165354D01*
G01Y623641D02*
X195877D01*
G01X165354D02*
X148110D01*
G01X165354Y623543D02*
X197638D01*
G01X156693D02*
X161417D01*
G01X165354Y620315D02*
X197638D01*
G01X161417D02*
X156693D01*
G01X165354Y620216D02*
X195877D01*
G01X148110D02*
X165354D01*
G01Y618641D02*
X195877D01*
G01X165354D02*
X148110D01*
G01X165354Y618543D02*
X197638D01*
G01X156693D02*
X161417D01*
G01X165354Y615315D02*
X197638D01*
G01X161417D02*
X156693D01*
G01X165354Y615216D02*
X195877D01*
G01X148110D02*
X165354D01*
G01Y613641D02*
X195877D01*
G01X165354D02*
X148110D01*
G01X165354Y613543D02*
X197638D01*
G01X156693D02*
X161417D01*
G01X150866Y610334D02*
X149291D01*
G01X165354Y610315D02*
X197638D01*
G01X161417D02*
X156693D01*
G01X165354Y610216D02*
X195877D01*
G01X148110D02*
X165354D01*
G01X149291Y610137D02*
X150598D01*
G01X150364Y609941D02*
X150632D01*
G01X149660Y609678D02*
X149828D01*
G01X149794Y609481D02*
X149694D01*
G01X150397Y608759D02*
X150464D01*
G01X165354Y608641D02*
X195877D01*
G01X165354D02*
X148110D01*
G01X150498Y608563D02*
X150364D01*
G01X165354Y608543D02*
X197638D01*
G01X156693D02*
X161417D01*
G01X168012Y605610D02*
X196457D01*
G01X165354D02*
X166634D01*
G01X165354D02*
X145669D01*
G01Y603838D02*
X165354D01*
G01X145669Y600689D02*
X195669D01*
G01X166142Y597736D02*
X177165D01*
G01X145669D02*
X166142D01*
G01X199606Y593523D02*
X166142D01*
G01X199606Y592342D02*
X145669D01*
G01X157480Y590374D02*
X177165D01*
G01X141732Y588405D02*
X153543D01*
G01X177165Y587283D02*
X157480D01*
G01Y586299D02*
X177165D01*
G01X176969Y586102D02*
X157677D01*
G01X176969Y584527D02*
X157677D01*
G01X177165Y584330D02*
X157480D01*
G01Y583346D02*
X177165D01*
G01X157480Y581358D02*
X177165D01*
G01X157480Y579389D02*
X177165D01*
G01X181102Y575452D02*
X153543D01*
G01X148110Y638641D02*
Y640216D01*
G01Y633641D02*
Y635216D01*
G01Y628641D02*
Y630216D01*
G01Y623641D02*
Y625216D01*
G01Y618641D02*
Y620216D01*
G01Y613641D02*
Y615216D01*
G01Y608641D02*
Y610216D01*
G01X145669Y592342D02*
Y605610D01*
G01X141732Y755452D02*
Y588405D01*
G01X149995Y609186D02*
X149961Y609317D01*
G01X150029Y608858D02*
X149995Y608989D01*
G01X149493Y608924D02*
X149526Y608792D01*
G01X157949Y641902D02*
X157915Y642001D01*
G01X157480Y641706D02*
X157513Y641607D01*
G01X150665Y609186D02*
X150632Y609284D01*
G01X150196Y608989D02*
X150230Y608891D01*
G01X157346Y643641D02*
X157379Y643576D01*
G01X157211D02*
X157279Y643445D01*
G01X157413Y642854D02*
X157379Y642920D01*
G01Y642198D02*
X157446Y642067D01*
G01X156843Y642920D02*
X156776Y643051D01*
G01X157379Y641443D02*
X157312Y641574D01*
G01X150096Y609481D02*
X150163Y609350D01*
G01X150096Y608727D02*
X150029Y608858D01*
G01X158016Y643641D02*
X158116Y643477D01*
G01X156709Y642821D02*
X156608Y642985D01*
G01X156709Y641312D02*
X156608Y641476D01*
G01X149426Y608595D02*
X149397Y608641D01*
G01D02*
X149325Y608759D01*
G01X157245Y642034D02*
X157178Y642132D01*
G01X157513Y641607D02*
X157580Y641509D01*
G01X157848Y643576D02*
X157949Y643445D01*
G01X157245Y643772D02*
X157346Y643641D01*
G01X157580Y642920D02*
X157480Y643051D01*
G01X158016Y642165D02*
X158116Y642034D01*
G01X157915Y643740D02*
X158016Y643641D01*
G01X157513Y642756D02*
X157413Y642854D01*
G01X157915Y642001D02*
X157848Y642067D01*
G01X157245Y642329D02*
X157379Y642198D01*
G01X156809Y642723D02*
X156709Y642821D01*
G01X157513Y641312D02*
X157379Y641443D01*
G01X156809Y641509D02*
X156910Y641410D01*
G01X157078Y643674D02*
X157211Y643576D01*
G01X157882Y642263D02*
X158016Y642165D01*
G01X156977Y642821D02*
X156843Y642920D01*
G01X157748Y643641D02*
X157848Y643576D01*
G01X157681Y642854D02*
X157580Y642920D01*
G01X157178Y642132D02*
X157078Y642198D01*
G01X156876Y641213D02*
X156709Y641312D01*
G01X149593Y608497D02*
X149426Y608595D01*
G01X157647Y642690D02*
X157513Y642756D01*
G01X157848Y642067D02*
X157781Y642099D01*
G01X157111Y642395D02*
X157245Y642329D01*
G01X150565Y609350D02*
X150498Y609383D01*
G01X149828Y609678D02*
X149961Y609613D01*
G01X157748Y643806D02*
X157915Y643740D01*
G01X157078Y643838D02*
X157245Y643772D01*
G01X156977Y642657D02*
X156809Y642723D01*
G01X153543Y636496D02*
X156693Y635315D01*
G01X153543Y631496D02*
X156693Y630315D01*
G01X153543Y626496D02*
X156693Y625315D01*
G01X153543Y621496D02*
X156693Y620315D01*
G01X153543Y616496D02*
X156693Y615315D01*
G01X153543Y611496D02*
X156693Y610315D01*
G01X157781Y642296D02*
X157882Y642263D01*
G01X157580Y641509D02*
X157681Y641476D01*
G01X156910Y641410D02*
X157011Y641378D01*
G01X150498Y609580D02*
X150598Y609547D01*
G01X150297Y608792D02*
X150397Y608759D01*
G01X149626Y608694D02*
X149727Y608661D01*
G01X150364Y608563D02*
X150230Y608595D01*
G01X149727Y608464D02*
X149593Y608497D01*
G01X149961Y609317D02*
X149895Y609416D01*
G01X150230Y608891D02*
X150297Y608792D01*
G01X150732Y609448D02*
X150833Y609317D01*
G01X150632Y609284D02*
X150565Y609350D01*
G01X149961Y609613D02*
X150096Y609481D01*
G01X150230Y608595D02*
X150183Y608641D01*
G01D02*
X150096Y608727D01*
G01X149526Y608792D02*
X149626Y608694D01*
G01X150598Y609547D02*
X150732Y609448D01*
G01X149895Y609416D02*
X149794Y609481D01*
G01X162992Y648090D02*
X160630Y647401D01*
G01X162992Y651240D02*
X160630Y650551D01*
G01X162992Y654389D02*
X160630Y653700D01*
G01X162992Y657539D02*
X160630Y656850D01*
G01X162992Y660689D02*
X160630Y660000D01*
G01X150336Y664488D02*
X150437Y664520D01*
G01X150403Y664717D02*
X150302Y664685D01*
G01X156693Y668543D02*
X153543Y667362D01*
G01X156693Y673543D02*
X153543Y672362D01*
G01X156693Y683543D02*
X153543Y682362D01*
G01X156693Y688543D02*
X153543Y687362D01*
G01X156693Y693543D02*
X153543Y692362D01*
G01X156693Y698543D02*
X153543Y697362D01*
G01X156693Y703543D02*
X153543Y702362D01*
G01X156693Y708543D02*
X153543Y707362D01*
G01X156693Y713543D02*
X153543Y712362D01*
G01X156693Y723543D02*
X153543Y722362D01*
G01X156693Y728543D02*
X153543Y727362D01*
G01X150302Y664685D02*
X150169Y664586D01*
G01X150671Y664980D02*
X150906Y665177D01*
G01X150638D02*
X150403Y664980D01*
G01X150269Y664422D02*
X150336Y664488D01*
G01X150169Y664586D02*
X150068Y664455D01*
G01X158661Y718543D02*
X153543Y717362D01*
G01X165354Y728641D02*
X195877D01*
G01X165354D02*
X148110D01*
G01X165354Y728543D02*
X197638D01*
G01X156693D02*
X161417D01*
G01X165354Y725315D02*
X197638D01*
G01X161417D02*
X156693D01*
G01X165354Y725216D02*
X195877D01*
G01X148110D02*
X165354D01*
G01Y723641D02*
X195877D01*
G01X165354D02*
X148110D01*
G01X165354Y723543D02*
X197638D01*
G01X156693D02*
X161417D01*
G01X166535Y721791D02*
X165354D01*
G01X163386Y720315D02*
X158661D01*
G01X197638D02*
X166535D01*
G01Y720216D02*
X195877D01*
G01X146654D02*
X166535D01*
G01Y718641D02*
X195877D01*
G01X146654D02*
X166535D01*
G01Y718543D02*
X197638D01*
G01X158661D02*
X163386D01*
G01X158465Y718307D02*
X165354D01*
G01Y717067D02*
X166535D01*
G01X165354Y715551D02*
X158465D01*
G01X165354Y715315D02*
X197638D01*
G01X161417D02*
X156693D01*
G01X165354Y715216D02*
X195877D01*
G01X148110D02*
X165354D01*
G01Y713641D02*
X195877D01*
G01X165354D02*
X148110D01*
G01X165354Y713543D02*
X197638D01*
G01X156693D02*
X161417D01*
G01X165354Y710315D02*
X197638D01*
G01X161417D02*
X156693D01*
G01X165354Y710216D02*
X195877D01*
G01X148110D02*
X165354D01*
G01Y708641D02*
X195877D01*
G01X165354D02*
X148110D01*
G01X165354Y708543D02*
X197638D01*
G01X156693D02*
X161417D01*
G01X165354Y705315D02*
X197638D01*
G01X161417D02*
X156693D01*
G01X165354Y705216D02*
X195877D01*
G01X148110D02*
X165354D01*
G01Y703641D02*
X195877D01*
G01X165354D02*
X148110D01*
G01X165354Y703543D02*
X197638D01*
G01X156693D02*
X161417D01*
G01X158661Y678543D02*
X153543Y677362D01*
G01X150235Y664324D02*
X150269Y664422D01*
G01X153543Y721496D02*
X158661Y720315D01*
G01X165354Y700315D02*
X197638D01*
G01X161417D02*
X156693D01*
G01X165354Y700216D02*
X195877D01*
G01X148110D02*
X165354D01*
G01Y698641D02*
X195877D01*
G01X165354D02*
X148110D01*
G01X165354Y698543D02*
X197638D01*
G01X156693D02*
X161417D01*
G01X165354Y695315D02*
X197638D01*
G01X161417D02*
X156693D01*
G01X165354Y695216D02*
X195877D01*
G01X148110D02*
X165354D01*
G01Y693641D02*
X195877D01*
G01X165354D02*
X148110D01*
G01X165354Y693543D02*
X197638D01*
G01X156693D02*
X161417D01*
G01X158465Y693307D02*
X165354D01*
G01Y690551D02*
X158465D01*
G01X165354Y690315D02*
X197638D01*
G01X161417D02*
X156693D01*
G01X165354Y690216D02*
X195877D01*
G01X148110D02*
X165354D01*
G01Y688641D02*
X195877D01*
G01X165354D02*
X148110D01*
G01X165354Y688543D02*
X197638D01*
G01X156693D02*
X161417D01*
G01X165354Y685315D02*
X197638D01*
G01X161417D02*
X156693D01*
G01X165354Y685216D02*
X195877D01*
G01X148110D02*
X165354D01*
G01Y683641D02*
X195877D01*
G01X165354D02*
X148110D01*
G01X165354Y683543D02*
X197638D01*
G01X156693D02*
X161417D01*
G01X166535Y681791D02*
X165354D01*
G01X163386Y680315D02*
X158661D01*
G01X197638D02*
X166535D01*
G01Y680216D02*
X195877D01*
G01X146654D02*
X166535D01*
G01Y678641D02*
X195877D01*
G01X146654D02*
X166535D01*
G01Y678543D02*
X197638D01*
G01X158661D02*
X163386D01*
G01X165354Y677067D02*
X166535D01*
G01X165354Y675315D02*
X197638D01*
G01X161417D02*
X156693D01*
G01X165354Y675216D02*
X195877D01*
G01X148110D02*
X165354D01*
G01Y673641D02*
X195877D01*
G01X165354D02*
X148110D01*
G01X165354Y673543D02*
X197638D01*
G01X156693D02*
X161417D01*
G01X165354Y670315D02*
X197638D01*
G01X161417D02*
X156693D01*
G01X165354Y670216D02*
X195877D01*
G01X148110D02*
X165354D01*
G01Y668641D02*
X148110D01*
G01X195877D02*
X165354D01*
G01Y668543D02*
X197638D01*
G01X156693D02*
X161417D01*
G01X158465Y668307D02*
X165354D01*
G01Y665551D02*
X158465D01*
G01X150906Y665374D02*
X149331D01*
G01X165354Y665315D02*
X194685D01*
G01X161417D02*
X156693D01*
G01X165354Y665216D02*
X195756D01*
G01X146654D02*
X165354D01*
G01X149331Y665177D02*
X150638D01*
G01X150403Y664980D02*
X150671D01*
G01X150537Y664717D02*
X150403D01*
G01X150437Y664520D02*
X150537D01*
G01X165354Y664133D02*
X197638D01*
G01X150738Y663700D02*
X150235D01*
G01X150035D02*
X149331D01*
G01X165354Y663641D02*
X195756D01*
G01X146654D02*
X165354D01*
G01Y663543D02*
X194685D01*
G01X157284D02*
X161417D01*
G01X149331Y663504D02*
X150906D01*
G01X160630Y662952D02*
X157284D01*
G01X168110Y662067D02*
X197441D01*
G01X162992D02*
X165354D01*
G01X168110Y661968D02*
X194215D01*
G01X156102D02*
X168110D01*
G01X177165Y661693D02*
X195669D01*
G01X156102Y660787D02*
X168110D01*
G01X194215D02*
X168110D01*
G01Y660689D02*
X197441D01*
G01X162992D02*
X165354D01*
G01X168110Y658917D02*
X197441D01*
G01X162992D02*
X165354D01*
G01X168110Y658819D02*
X194215D01*
G01X156102D02*
X168110D01*
G01X156102Y657637D02*
X168110D01*
G01X194215D02*
X168110D01*
G01Y657539D02*
X197441D01*
G01X162992D02*
X165354D01*
G01X168110Y655767D02*
X197441D01*
G01X162992D02*
X165354D01*
G01X168110Y655669D02*
X194215D01*
G01X156102D02*
X168110D01*
G01X156102Y654488D02*
X168110D01*
G01X194215D02*
X168110D01*
G01Y654389D02*
X197441D01*
G01X162992D02*
X165354D01*
G01X168110Y652618D02*
X197441D01*
G01X162992D02*
X165354D01*
G01X168110Y652519D02*
X194215D01*
G01X156102D02*
X168110D01*
G01X156102Y651338D02*
X168110D01*
G01X194215D02*
X168110D01*
G01Y651240D02*
X197441D01*
G01X162992D02*
X165354D01*
G01X168110Y649468D02*
X197441D01*
G01X162992D02*
X165354D01*
G01X168110Y649370D02*
X194215D01*
G01X156102D02*
X168110D01*
G01X156102Y648189D02*
X168110D01*
G01X194215D02*
X168110D01*
G01Y648090D02*
X197441D01*
G01X162992D02*
X165354D01*
G01X168110Y646319D02*
X197441D01*
G01X162992D02*
X165354D01*
G01X168110Y646220D02*
X194215D01*
G01X156102D02*
X168110D01*
G01X150068Y664455D02*
X150035Y664291D01*
G01X166535Y717067D02*
Y721791D01*
G01Y677067D02*
Y681791D01*
G01X165354Y720216D02*
Y740019D01*
G01Y680216D02*
Y718641D01*
G01Y661968D02*
Y678641D01*
G01Y648189D02*
Y646220D01*
G01Y651338D02*
Y649370D01*
G01D02*
Y648189D01*
G01Y654488D02*
Y652519D01*
G01D02*
Y651338D01*
G01Y655669D02*
Y654488D01*
G01Y657637D02*
Y655669D01*
G01Y660787D02*
Y658819D01*
G01D02*
Y657637D01*
G01Y661968D02*
Y660787D01*
G01Y680216D02*
Y678641D01*
G01Y720216D02*
Y718641D01*
G01X163465Y660787D02*
Y661968D01*
G01Y657637D02*
Y658819D01*
G01Y651338D02*
Y652519D01*
G01Y654488D02*
Y655669D01*
G01Y648189D02*
Y649370D01*
G01X163386Y720216D02*
Y720315D01*
G01Y718543D02*
Y718641D01*
G01D02*
Y720216D01*
G01Y680216D02*
Y680315D01*
G01Y678641D02*
Y680216D01*
G01Y678543D02*
Y678641D01*
G01X161890Y660787D02*
Y661968D01*
G01Y657637D02*
Y658819D01*
G01Y654488D02*
Y655669D01*
G01Y651338D02*
Y652519D01*
G01Y648189D02*
Y649370D01*
G01X161417Y728543D02*
Y728641D01*
G01D02*
Y730216D01*
G01Y725216D02*
Y725315D01*
G01Y723543D02*
Y723641D01*
G01D02*
Y725216D01*
G01Y715216D02*
Y715315D01*
G01Y713543D02*
Y713641D01*
G01D02*
Y715216D01*
G01Y710216D02*
Y710315D01*
G01Y708543D02*
Y708641D01*
G01D02*
Y710216D01*
G01Y705216D02*
Y705315D01*
G01Y703543D02*
Y703641D01*
G01D02*
Y705216D01*
G01Y700216D02*
Y700315D01*
G01Y698641D02*
Y700216D01*
G01Y698543D02*
Y698641D01*
G01Y695216D02*
Y695315D01*
G01Y693641D02*
Y695216D01*
G01Y693543D02*
Y693641D01*
G01Y690216D02*
Y690315D01*
G01Y688641D02*
Y690216D01*
G01Y688543D02*
Y688641D01*
G01Y685216D02*
Y685315D01*
G01Y683641D02*
Y685216D01*
G01Y683543D02*
Y683641D01*
G01Y675216D02*
Y675315D01*
G01Y673543D02*
Y673641D01*
G01D02*
Y675216D01*
G01Y670216D02*
Y670315D01*
G01Y668543D02*
Y668641D01*
G01D02*
Y670216D01*
G01Y665216D02*
Y665315D01*
G01Y663543D02*
Y663641D01*
G01D02*
Y665216D01*
G01X161102Y649370D02*
Y648189D01*
G01Y652519D02*
Y651338D01*
G01Y655669D02*
Y654488D01*
G01Y658819D02*
Y657637D01*
G01Y661968D02*
Y660787D01*
G01X160709Y649370D02*
Y648189D01*
G01Y652519D02*
Y651338D01*
G01Y655669D02*
Y654488D01*
G01Y658819D02*
Y657637D01*
G01Y661968D02*
Y660787D01*
G01X160630Y662756D02*
Y662952D01*
G01Y656456D02*
Y656850D01*
G01Y659606D02*
Y660000D01*
G01Y653307D02*
Y653700D01*
G01Y647008D02*
Y647401D01*
G01Y650157D02*
Y650551D01*
G01X158465Y668307D02*
Y665551D01*
G01Y693307D02*
Y690551D01*
G01Y718307D02*
Y715551D01*
G01X157284Y662952D02*
Y663543D01*
G01X156102Y660787D02*
Y661968D01*
G01Y657637D02*
Y658819D01*
G01Y651338D02*
Y652519D01*
G01Y654488D02*
Y655669D01*
G01Y648189D02*
Y649370D01*
G01X155787Y728641D02*
Y730216D01*
G01Y723641D02*
Y725216D01*
G01Y718641D02*
Y720216D01*
G01Y713641D02*
Y715216D01*
G01Y708641D02*
Y710216D01*
G01Y703641D02*
Y705216D01*
G01Y698641D02*
Y700216D01*
G01Y693641D02*
Y695216D01*
G01Y688641D02*
Y690216D01*
G01Y683641D02*
Y685216D01*
G01Y678641D02*
Y680216D01*
G01Y673641D02*
Y675216D01*
G01Y668641D02*
Y670216D01*
G01Y663641D02*
Y665216D01*
G01X154213Y728641D02*
Y730216D01*
G01Y723641D02*
Y725216D01*
G01Y718641D02*
Y720216D01*
G01Y713641D02*
Y715216D01*
G01Y708641D02*
Y710216D01*
G01Y703641D02*
Y705216D01*
G01Y698641D02*
Y700216D01*
G01Y693641D02*
Y695216D01*
G01Y688641D02*
Y690216D01*
G01Y683641D02*
Y685216D01*
G01Y678641D02*
Y680216D01*
G01Y673641D02*
Y675216D01*
G01Y668641D02*
Y670216D01*
G01Y663641D02*
Y665216D01*
G01X153543Y726496D02*
Y727362D01*
G01Y721496D02*
Y722362D01*
G01Y716496D02*
Y717362D01*
G01Y711496D02*
Y712362D01*
G01Y706496D02*
Y707362D01*
G01Y701496D02*
Y702362D01*
G01Y696496D02*
Y697362D01*
G01Y691496D02*
Y692362D01*
G01Y686496D02*
Y687362D01*
G01Y681496D02*
Y682362D01*
G01Y676496D02*
Y677362D01*
G01Y671496D02*
Y672362D01*
G01Y666496D02*
Y667362D01*
G01X153425Y665216D02*
Y663641D01*
G01Y670216D02*
Y668641D01*
G01Y675216D02*
Y673641D01*
G01Y680216D02*
Y678641D01*
G01Y685216D02*
Y683641D01*
G01Y690216D02*
Y688641D01*
G01Y695216D02*
Y693641D01*
G01Y700216D02*
Y698641D01*
G01Y705216D02*
Y703641D01*
G01Y710216D02*
Y708641D01*
G01Y715216D02*
Y713641D01*
G01Y720216D02*
Y718641D01*
G01Y725216D02*
Y723641D01*
G01Y730216D02*
Y728641D01*
G01X153032Y665216D02*
Y663641D01*
G01Y670216D02*
Y668641D01*
G01Y675216D02*
Y673641D01*
G01Y680216D02*
Y678641D01*
G01Y685216D02*
Y683641D01*
G01Y690216D02*
Y688641D01*
G01Y695216D02*
Y693641D01*
G01Y700216D02*
Y698641D01*
G01Y705216D02*
Y703641D01*
G01Y710216D02*
Y708641D01*
G01Y715216D02*
Y713641D01*
G01Y720216D02*
Y718641D01*
G01Y725216D02*
Y723641D01*
G01Y730216D02*
Y728641D01*
G01X150906Y665216D02*
Y665374D01*
G01Y663504D02*
Y663641D01*
G01Y665177D02*
Y665216D01*
G01Y663641D02*
Y664291D01*
G01X150738Y664324D02*
Y663700D01*
G01X150235D02*
Y664324D01*
G01X150035Y664291D02*
Y663700D01*
G01X149331Y665374D02*
Y665216D01*
G01Y663641D02*
Y663504D01*
G01Y665216D02*
Y665177D01*
G01Y663700D02*
Y663641D01*
G01X150906Y664291D02*
X150872Y664455D01*
G01X153543Y726496D02*
X156693Y725315D01*
G01X153543Y716496D02*
X156693Y715315D01*
G01X153543Y711496D02*
X156693Y710315D01*
G01X153543Y706496D02*
X156693Y705315D01*
G01X153543Y701496D02*
X156693Y700315D01*
G01X153543Y696496D02*
X156693Y695315D01*
G01X153543Y691496D02*
X156693Y690315D01*
G01X153543Y686496D02*
X156693Y685315D01*
G01X153543Y676496D02*
X156693Y675315D01*
G01X153543Y671496D02*
X156693Y670315D01*
G01X153543Y666496D02*
X156693Y665315D01*
G01X150638Y664685D02*
X150537Y664717D01*
G01Y664520D02*
X150638Y664488D01*
G01X160630Y662756D02*
X162992Y662067D01*
G01X160630Y659606D02*
X162992Y658917D01*
G01X160630Y656456D02*
X162992Y655767D01*
G01X160630Y653307D02*
X162992Y652618D01*
G01X160630Y650157D02*
X162992Y649468D01*
G01X160630Y647008D02*
X162992Y646319D01*
G01X153543Y681496D02*
X158661Y680315D01*
G01X148110Y728641D02*
Y730216D01*
G01Y723641D02*
Y725216D01*
G01Y713641D02*
Y715216D01*
G01Y708641D02*
Y710216D01*
G01Y703641D02*
Y705216D01*
G01Y698641D02*
Y700216D01*
G01Y693641D02*
Y695216D01*
G01Y688641D02*
Y690216D01*
G01Y683641D02*
Y685216D01*
G01Y673641D02*
Y675216D01*
G01Y668641D02*
Y670216D01*
G01X146654Y718641D02*
Y720216D01*
G01Y678641D02*
Y680216D01*
G01Y663641D02*
Y665216D01*
G01X150705Y664422D02*
X150738Y664324D01*
G01X150872Y664455D02*
X150772Y664586D01*
G01X150638Y664488D02*
X150705Y664422D01*
G01X150772Y664586D02*
X150638Y664685D01*
G01X171063Y758543D02*
G03I-3740J0D01*
G01X156054Y748307D02*
G03Y745157I2017J-1575D01*
G01X160088D02*
G03Y748307I-2017J1575D01*
G01X160441Y744370D02*
G03Y749094I-2370J2362D01*
G01X155701D02*
G03Y744370I2370J-2362D01*
G01X161575Y746732D02*
G03I-3504J0D01*
G01X160748Y743582D02*
G03Y749882I-2677J3150D01*
G01X155394D02*
G03Y743582I2677J-3150D01*
G01X156693Y733543D02*
X153543Y732362D01*
G01Y768405D02*
X181102D01*
G01X177165Y764468D02*
X157480D01*
G01X177165Y762500D02*
X157480D01*
G01X177165Y760511D02*
X157480D01*
G01Y759527D02*
X177165D01*
G01X176969Y759330D02*
X157677D01*
G01X176969Y757756D02*
X157677D01*
G01X177165Y757559D02*
X157480D01*
G01Y756574D02*
X177165D01*
G01X153543Y755452D02*
X141732D01*
G01X177165Y753484D02*
X157480D01*
G01X199606Y751515D02*
X145669D01*
G01X166142Y750334D02*
X199606D01*
G01X155394Y749882D02*
X160748D01*
G01X160441Y749094D02*
X155701D01*
G01X156054Y748307D02*
X160088D01*
G01X166142Y746122D02*
X145669D01*
G01X177165D02*
X166142D01*
G01X156054Y745157D02*
X160088D01*
G01X155701Y744370D02*
X160441D01*
G01X160748Y743582D02*
X155394D01*
G01X195669Y743169D02*
X145669D01*
G01X165354Y740019D02*
X145669D01*
G01Y738248D02*
X165354D01*
G01D02*
X166634D01*
G01X196457D02*
X168012D01*
G01X161417Y735315D02*
X156693D01*
G01X197638D02*
X165354D01*
G01Y735216D02*
X195877D01*
G01X148110D02*
X165354D01*
G01Y733641D02*
X195877D01*
G01X165354D02*
X148110D01*
G01X165354Y733543D02*
X197638D01*
G01X156693D02*
X161417D01*
G01X165354Y730315D02*
X197638D01*
G01X161417D02*
X156693D01*
G01X165354Y730216D02*
X195877D01*
G01X148110D02*
X165354D01*
G01X177165Y751515D02*
Y764468D01*
G01X176969Y757756D02*
Y759330D01*
G01X171614D02*
Y757756D01*
G01X170276Y757559D02*
Y757756D01*
G01Y759330D02*
Y759527D01*
G01Y759330D02*
Y757756D01*
G01X170079Y759330D02*
Y757756D01*
G01X168504Y759330D02*
Y757756D01*
G01X166142Y743169D02*
Y751515D01*
G01Y759330D02*
Y757756D01*
G01X164567D02*
Y759330D01*
G01X164370D02*
Y759527D01*
G01Y757756D02*
Y759330D01*
G01Y757756D02*
Y757559D01*
G01X163032Y757756D02*
Y759330D01*
G01X161417Y735216D02*
Y735315D01*
G01Y733543D02*
Y733641D01*
G01D02*
Y735216D01*
G01Y730216D02*
Y730315D01*
G01X157677Y759330D02*
Y757756D01*
G01X157480Y751515D02*
Y764468D01*
G01X155787Y733641D02*
Y735216D01*
G01X154213Y733641D02*
Y735216D01*
G01X153543Y755452D02*
Y768405D01*
G01Y736496D02*
Y738248D01*
G01Y731496D02*
Y732362D01*
G01X153425Y735216D02*
Y733641D01*
G01X153032Y735216D02*
Y733641D01*
G01X153543Y736496D02*
X156693Y735315D01*
G01X153543Y731496D02*
X156693Y730315D01*
G01X148110Y733641D02*
Y735216D01*
G01X145669Y738248D02*
Y751515D01*
G01X162597Y975335D02*
Y973366D01*
G01Y970807D02*
Y972776D01*
G01X164172Y975630D02*
Y975039D01*
G01Y971102D02*
Y970512D01*
G01Y973858D02*
Y972283D01*
G01X165156Y975630D02*
Y970512D01*
G01X165353D02*
Y975630D01*
G01X165747Y972776D02*
Y970807D01*
G01Y973366D02*
Y975335D01*
G01X168897Y972776D02*
Y970807D01*
G01Y973366D02*
Y975335D01*
G01X169290Y970512D02*
Y975630D01*
G01X169487D02*
Y970512D01*
G01X164172D02*
X170471D01*
G01X165747Y970807D02*
X164172D01*
G01D02*
X162597D01*
G01X168897D02*
X170471D01*
G01Y972776D02*
X168897D01*
G01X164172D02*
X165747D01*
G01X162597D02*
X164172D01*
G01X170471Y973366D02*
X168897D01*
G01X164172D02*
X165747D01*
G01X162597D02*
X164172D01*
G01X165747Y975335D02*
X164172D01*
G01D02*
X162597D01*
G01X168897D02*
X170471D01*
G01X164172Y975630D02*
X170471D01*
G01X164172Y971102D02*
G03Y972283I0J590D01*
G01Y973858D02*
G03Y975039I0J591D01*
G01X170367Y974110D02*
Y974858D01*
G01X170461D02*
Y974238D01*
G01X170471Y970512D02*
Y971102D01*
G01Y972283D02*
Y973858D01*
G01Y975039D02*
Y975630D01*
G01X170554Y974349D02*
Y974222D01*
G01X172046Y975335D02*
Y973366D01*
G01Y970807D02*
Y972776D01*
G01X170461Y974238D02*
X170554Y974349D01*
G01Y974222D02*
X170461Y974110D01*
G01X170471Y970807D02*
X172046D01*
G01Y972776D02*
X170471D01*
G01X172046Y973366D02*
X170471D01*
G01X170461Y974110D02*
X170367D01*
G01Y974858D02*
X170461D01*
G01X170471Y975335D02*
X172046D01*
G01X170471Y972283D02*
G03Y971102I1J-591D01*
G01Y975039D02*
G03Y973858I1J-590D01*
G01X157996Y1006771D02*
X158071D01*
G01X158146Y998504D02*
X158071D01*
G01X160630Y1002637D02*
G03I-2559J0D01*
G01X161417D02*
G03I-3346J0D01*
G01X161575D02*
G03I-3504J0D01*
G01X158146Y998504D02*
G03X158071Y1006771I-75J4133D01*
G01X157996Y1006770D02*
G03X158071Y998504I75J-4133D01*
G01X171063Y990826D02*
G03I-3740J0D01*
G01X157915Y1046824D02*
X157781Y1046791D01*
G01X150632Y1014107D02*
X150498Y1014074D01*
G01X156102Y1060000D02*
X168110D01*
G01X194215D02*
X168110D01*
G01Y1059901D02*
X197441D01*
G01X162992D02*
X165354D01*
G01X168110Y1058130D02*
X197441D01*
G01X162992D02*
X165354D01*
G01X168110Y1058031D02*
X194215D01*
G01X156102D02*
X168110D01*
G01X156102Y1056850D02*
X168110D01*
G01X194215D02*
X168110D01*
G01Y1056752D02*
X197441D01*
G01X162992D02*
X165354D01*
G01X168110Y1054980D02*
X197441D01*
G01X162992D02*
X165354D01*
G01X168110Y1054882D02*
X194215D01*
G01X156102D02*
X168110D01*
G01X156102Y1053700D02*
X168110D01*
G01X194215D02*
X168110D01*
G01Y1053602D02*
X197441D01*
G01X162992D02*
X165354D01*
G01X168110Y1051830D02*
X197441D01*
G01X162992D02*
X165354D01*
G01X168110Y1051732D02*
X194215D01*
G01X156102D02*
X168110D01*
G01X156102Y1050551D02*
X168110D01*
G01X194215D02*
X168110D01*
G01Y1050452D02*
X197441D01*
G01X162992D02*
X165354D01*
G01X156977Y1049350D02*
X157078D01*
G01X157647Y1049317D02*
X157748D01*
G01X156977Y1049186D02*
X157078D01*
G01X157681Y1049153D02*
X157748D01*
G01X162992Y1048681D02*
X165354D01*
G01X197441D02*
X168110D01*
G01Y1048582D02*
X194215D01*
G01X156102D02*
X168110D01*
G01X157748Y1048366D02*
X157681D01*
G01X157078Y1048333D02*
X156977D01*
G01X157748Y1048202D02*
X157647D01*
G01X157078Y1048169D02*
X156977D01*
G01X156944Y1047906D02*
X157111D01*
G01X157078Y1047709D02*
X156977D01*
G01X195669Y1047677D02*
X177165D01*
G01X156102Y1047401D02*
X168110D01*
G01X194215D02*
X168110D01*
G01X162992Y1047303D02*
X165354D01*
G01X197441D02*
X168110D01*
G01X157681Y1046988D02*
X157748D01*
G01X157781Y1046791D02*
X157647D01*
G01X157284Y1046417D02*
X160630D01*
G01X161417Y1045826D02*
X157284D01*
G01X194685D02*
X165354D01*
G01Y1045728D02*
X195756D01*
G01X148110D02*
X165354D01*
G01Y1045236D02*
X197638D01*
G01X165354Y1044153D02*
X148110D01*
G01X195756D02*
X165354D01*
G01Y1044055D02*
X194685D01*
G01X156693D02*
X161417D01*
G01Y1040826D02*
X156693D01*
G01X197638D02*
X165354D01*
G01Y1040728D02*
X195877D01*
G01X148110D02*
X165354D01*
G01Y1039153D02*
X195877D01*
G01X165354D02*
X148110D01*
G01X165354Y1039055D02*
X197638D01*
G01X156693D02*
X161417D01*
G01X158465Y1038819D02*
X165354D01*
G01Y1036063D02*
X158465D01*
G01X165354Y1035826D02*
X197638D01*
G01X161417D02*
X156693D01*
G01X165354Y1035728D02*
X195877D01*
G01X148110D02*
X165354D01*
G01Y1034153D02*
X195877D01*
G01X165354D02*
X148110D01*
G01X165354Y1034055D02*
X197638D01*
G01X156693D02*
X161417D01*
G01X165354Y1030826D02*
X197638D01*
G01X161417D02*
X156693D01*
G01X165354Y1030728D02*
X195877D01*
G01X148110D02*
X165354D01*
G01Y1029153D02*
X195877D01*
G01X165354D02*
X148110D01*
G01X165354Y1029055D02*
X197638D01*
G01X156693D02*
X161417D01*
G01X165354Y1025826D02*
X197638D01*
G01X161417D02*
X156693D01*
G01X165354Y1025728D02*
X195877D01*
G01X148110D02*
X165354D01*
G01Y1024153D02*
X195877D01*
G01X165354D02*
X148110D01*
G01X165354Y1024055D02*
X197638D01*
G01X156693D02*
X161417D01*
G01X165354Y1020826D02*
X197638D01*
G01X161417D02*
X156693D01*
G01X165354Y1020728D02*
X195877D01*
G01X148110D02*
X165354D01*
G01Y1019153D02*
X195877D01*
G01X165354D02*
X148110D01*
G01X165354Y1019055D02*
X197638D01*
G01X156693D02*
X161417D01*
G01X150866Y1015846D02*
X149291D01*
G01X165354Y1015826D02*
X197638D01*
G01X161417D02*
X156693D01*
G01X165354Y1015728D02*
X195877D01*
G01X148110D02*
X165354D01*
G01X149291Y1015649D02*
X150598D01*
G01X150364Y1015452D02*
X150632D01*
G01X149660Y1015190D02*
X149828D01*
G01X149794Y1014993D02*
X149694D01*
G01X150397Y1014271D02*
X150464D01*
G01X165354Y1014153D02*
X195877D01*
G01X165354D02*
X148110D01*
G01X150498Y1014074D02*
X150364D01*
G01X165354Y1014055D02*
X197638D01*
G01X156693D02*
X161417D01*
G01X168012Y1011122D02*
X196457D01*
G01X165354D02*
X166634D01*
G01X165354D02*
X145669D01*
G01Y1009350D02*
X165354D01*
G01X157781Y1047808D02*
X157882Y1047775D01*
G01X157580Y1047020D02*
X157681Y1046988D01*
G01X156910Y1046922D02*
X157011Y1046889D01*
G01X160630Y1058819D02*
X162992Y1058130D01*
G01X160630Y1055669D02*
X162992Y1054980D01*
G01X160630Y1052519D02*
X162992Y1051830D01*
G01X160630Y1049370D02*
X162992Y1048681D01*
G01X157647Y1046791D02*
X157513Y1046824D01*
G01X157011Y1046693D02*
X156876Y1046725D01*
G01X145669Y1006200D02*
X195669D01*
G01X166142Y1003248D02*
X177165D01*
G01X145669D02*
X166142D01*
G01X199606Y999035D02*
X166142D01*
G01X199606Y997854D02*
X145669D01*
G01X157480Y995885D02*
X177165D01*
G01X141732Y993917D02*
X153543D01*
G01X177165Y992795D02*
X157480D01*
G01Y991811D02*
X177165D01*
G01X176969Y991614D02*
X157677D01*
G01X176969Y990039D02*
X157677D01*
G01X177165Y989842D02*
X157480D01*
G01Y988858D02*
X177165D01*
G01X157480Y986870D02*
X177165D01*
G01X157480Y984901D02*
X177165D01*
G01X181102Y980964D02*
X153543D01*
G01X156876Y1046725D02*
X156709Y1046824D01*
G01X157647Y1048202D02*
X157513Y1048267D01*
G01X157848Y1047578D02*
X157781Y1047611D01*
G01X157111Y1047906D02*
X157245Y1047841D01*
G01X157748Y1049317D02*
X157915Y1049252D01*
G01X157078Y1049350D02*
X157245Y1049284D01*
G01X156977Y1048169D02*
X156809Y1048235D01*
G01X153543Y1042008D02*
X156693Y1040826D01*
G01X153543Y1037008D02*
X156693Y1035826D01*
G01X153543Y1032008D02*
X156693Y1030826D01*
G01X153543Y1027008D02*
X156693Y1025826D01*
G01X153543Y1022008D02*
X156693Y1020826D01*
G01X153543Y1017008D02*
X156693Y1015826D01*
G01X150498Y1015091D02*
X150598Y1015059D01*
G01X150297Y1014304D02*
X150397Y1014271D01*
G01X149626Y1014206D02*
X149727Y1014173D01*
G01X150364Y1014074D02*
X150230Y1014107D01*
G01X149727Y1013976D02*
X149593Y1014009D01*
G01X150464Y1014271D02*
X150565Y1014304D01*
G01X157915Y1049252D02*
X158016Y1049153D01*
G01X157513Y1048267D02*
X157413Y1048366D01*
G01X157915Y1047513D02*
X157848Y1047578D01*
G01X157245Y1047841D02*
X157379Y1047709D01*
G01X156809Y1048235D02*
X156709Y1048333D01*
G01X157513Y1046824D02*
X157379Y1046955D01*
G01X156809Y1047020D02*
X156910Y1046922D01*
G01X157078Y1049186D02*
X157211Y1049087D01*
G01X157882Y1047775D02*
X158016Y1047677D01*
G01X156977Y1048333D02*
X156843Y1048432D01*
G01X150598Y1015059D02*
X150732Y1014960D01*
G01X157748Y1049153D02*
X157848Y1049087D01*
G01X157681Y1048366D02*
X157580Y1048432D01*
G01X157178Y1047644D02*
X157078Y1047709D01*
G01X149895Y1014928D02*
X149794Y1014993D01*
G01X149593Y1014009D02*
X149426Y1014107D01*
G01X150565Y1014862D02*
X150498Y1014895D01*
G01X149828Y1015190D02*
X149961Y1015124D01*
G01X162992Y1047303D02*
X160630Y1046614D01*
G01X162992Y1050452D02*
X160630Y1049763D01*
G01X162992Y1053602D02*
X160630Y1052913D01*
G01X162992Y1056752D02*
X160630Y1056063D01*
G01X162992Y1059901D02*
X160630Y1059212D01*
G01X157748Y1046988D02*
X157848Y1047020D01*
G01X156693Y1014055D02*
X153543Y1012874D01*
G01X156693Y1019055D02*
X153543Y1017874D01*
G01X156693Y1024055D02*
X153543Y1022874D01*
G01X156693Y1029055D02*
X153543Y1027874D01*
G01X156693Y1034055D02*
X153543Y1032874D01*
G01X156693Y1039055D02*
X153543Y1037874D01*
G01X156693Y1044055D02*
X153543Y1042874D01*
G01X157915Y1048267D02*
X157748Y1048202D01*
G01X157245Y1048235D02*
X157078Y1048169D01*
G01X156809Y1049284D02*
X156977Y1049350D01*
G01X149526Y1015124D02*
X149660Y1015190D01*
G01X156809Y1047841D02*
X156944Y1047906D01*
G01X157513Y1049252D02*
X157647Y1049317D01*
G01X149694Y1014993D02*
X149593Y1014928D01*
G01X158016Y1049153D02*
X158116Y1048989D01*
G01X156709Y1048333D02*
X156608Y1048497D01*
G01X156709Y1046824D02*
X156608Y1046988D01*
G01X157245Y1047546D02*
X157178Y1047644D01*
G01X157513Y1047119D02*
X157580Y1047020D01*
G01X157848Y1049087D02*
X157949Y1048956D01*
G01X157245Y1049284D02*
X157346Y1049153D01*
G01X157580Y1048432D02*
X157480Y1048563D01*
G01X158016Y1047677D02*
X158116Y1047546D01*
G01X150732Y1014960D02*
X150833Y1014829D01*
G01X150632Y1014796D02*
X150565Y1014862D01*
G01X149961Y1015124D02*
X150096Y1014993D01*
G01X150230Y1014107D02*
X150183Y1014153D01*
G01D02*
X150096Y1014239D01*
G01X149526Y1014304D02*
X149626Y1014206D01*
G01X156977Y1047709D02*
X156876Y1047644D01*
G01X157848Y1048432D02*
X157748Y1048366D01*
G01X157580Y1049087D02*
X157681Y1049153D01*
G01X157211Y1048432D02*
X157078Y1048333D01*
G01X156843Y1049087D02*
X156977Y1049186D01*
G01X150632Y1015452D02*
X150866Y1015649D01*
G01X150598D02*
X150364Y1015452D01*
G01X150679Y1014153D02*
X150632Y1014107D01*
G01X150766Y1014239D02*
X150679Y1014153D01*
G01X149392Y1014993D02*
X149526Y1015124D01*
G01X158049Y1046955D02*
X157915Y1046824D01*
G01X158016Y1048366D02*
X157915Y1048267D01*
G01X156676Y1047709D02*
X156809Y1047841D01*
G01X157413Y1049153D02*
X157513Y1049252D01*
G01X156709Y1049186D02*
X156809Y1049284D01*
G01X158116Y1048989D02*
X158150Y1048825D01*
G01X158146Y1047401D02*
X158150Y1047382D01*
G01X158116Y1047546D02*
X158146Y1047401D01*
G01X157446Y1047578D02*
X157480Y1047414D01*
G01X156591Y1048582D02*
X156575Y1048661D01*
G01X156608Y1048497D02*
X156591Y1048582D01*
G01X156608Y1046988D02*
X156575Y1047152D01*
G01X150833Y1014829D02*
X150866Y1014665D01*
G01X150163Y1014862D02*
X150196Y1014698D01*
G01X149325Y1014271D02*
X149291Y1014435D01*
G01X157949Y1048956D02*
X157982Y1048825D01*
G01X157474Y1048582D02*
X157446Y1048694D01*
G01X157480Y1048563D02*
X157474Y1048582D01*
G01X157279Y1048956D02*
X157312Y1048825D01*
G01X157279Y1047414D02*
X157245Y1047546D01*
G01X157312Y1047086D02*
X157279Y1047217D01*
G01X156771Y1048582D02*
X156743Y1048694D01*
G01X156776Y1048563D02*
X156771Y1048582D01*
G01X156776Y1047152D02*
X156809Y1047020D01*
G01X149995Y1014698D02*
X149961Y1014829D01*
G01X150029Y1014370D02*
X149995Y1014501D01*
G01X149493Y1014435D02*
X149526Y1014304D01*
G01X157949Y1047414D02*
X157915Y1047513D01*
G01X157480Y1047217D02*
X157513Y1047119D01*
G01X150665Y1014698D02*
X150632Y1014796D01*
G01X150196Y1014501D02*
X150230Y1014402D01*
G01X157346Y1049153D02*
X157379Y1049087D01*
G01X157211D02*
X157279Y1048956D01*
G01X157413Y1048366D02*
X157379Y1048432D01*
G01Y1047709D02*
X157446Y1047578D01*
G01X156843Y1048432D02*
X156776Y1048563D01*
G01X157379Y1046955D02*
X157312Y1047086D01*
G01X150096Y1014993D02*
X150163Y1014862D01*
G01X150096Y1014239D02*
X150029Y1014370D01*
G01X149426Y1014107D02*
X149397Y1014153D01*
G01D02*
X149325Y1014271D01*
G01X149961Y1014829D02*
X149895Y1014928D01*
G01X150230Y1014402D02*
X150297Y1014304D01*
G01X157949Y1048563D02*
X157848Y1048432D01*
G01X157346Y1048366D02*
X157245Y1048235D01*
G01X157480Y1048956D02*
X157580Y1049087D01*
G01X150565Y1014304D02*
X150632Y1014402D01*
G01X149593Y1014928D02*
X149526Y1014829D01*
G01X157848Y1047020D02*
X157915Y1047119D01*
G01X156876Y1047644D02*
X156809Y1047546D01*
G01X158116Y1048530D02*
X158016Y1048366D01*
G01X156608Y1049022D02*
X156709Y1049186D01*
G01X150833Y1014370D02*
X150766Y1014239D01*
G01X149325Y1014862D02*
X149392Y1014993D01*
G01X158116Y1047086D02*
X158049Y1046955D01*
G01X157379Y1048432D02*
X157346Y1048366D01*
G01X157279Y1048563D02*
X157211Y1048432D01*
G01X157379Y1049087D02*
X157413Y1049153D01*
G01X156608Y1047578D02*
X156676Y1047709D01*
G01X156776Y1048956D02*
X156843Y1049087D01*
G01X150632Y1014402D02*
X150665Y1014501D01*
G01X157915Y1047119D02*
X157949Y1047217D01*
G01X150866Y1014501D02*
X150833Y1014370D01*
G01X158150Y1047217D02*
X158116Y1047086D01*
G01X149526Y1014829D02*
X149493Y1014698D01*
G01X157982Y1048694D02*
X157954Y1048582D01*
G01D02*
X157949Y1048563D01*
G01X157446Y1048825D02*
X157480Y1048956D01*
G01X157312Y1048694D02*
X157284Y1048582D01*
G01D02*
X157279Y1048563D01*
G01X156809Y1047546D02*
X156776Y1047414D01*
G01X156743Y1048825D02*
X156776Y1048956D01*
G01X158150Y1048694D02*
X158127Y1048582D01*
G01D02*
X158116Y1048530D01*
G01X156575Y1047414D02*
X156608Y1047578D01*
G01X156575Y1048858D02*
X156608Y1049022D01*
G01X149291Y1014698D02*
X149325Y1014862D01*
G01X177165Y997854D02*
Y1157027D01*
G01Y984901D02*
Y997854D01*
G01X176969Y990039D02*
Y991614D01*
G01X171614D02*
Y990039D01*
G01X170276Y991614D02*
Y991811D01*
G01Y989842D02*
Y990039D01*
G01Y991614D02*
Y990039D01*
G01X170079Y991614D02*
Y990039D01*
G01X169291Y1143759D02*
Y1011122D01*
G01X168504Y991614D02*
Y990039D01*
G01X168110Y1045236D02*
Y1069645D01*
G01X168012Y1011122D02*
Y1143759D01*
G01X166634D02*
Y1011122D01*
G01X166142Y997854D02*
Y1006200D01*
G01Y991614D02*
Y990039D01*
G01X165354Y1009350D02*
Y1047401D01*
G01Y1048582D02*
Y1047401D01*
G01Y1050551D02*
Y1048582D01*
G01Y1053700D02*
Y1051732D01*
G01D02*
Y1050551D01*
G01Y1056850D02*
Y1054882D01*
G01D02*
Y1053700D01*
G01Y1058031D02*
Y1056850D01*
G01Y1060000D02*
Y1058031D01*
G01Y1061181D02*
Y1060000D01*
G01X164567Y990039D02*
Y991614D01*
G01X164370D02*
Y991811D01*
G01Y990039D02*
Y991614D01*
G01Y990039D02*
Y989842D01*
G01X163465Y1060000D02*
Y1061181D01*
G01Y1056850D02*
Y1058031D01*
G01Y1053700D02*
Y1054882D01*
G01Y1050551D02*
Y1051732D01*
G01Y1047401D02*
Y1048582D01*
G01X163032Y990039D02*
Y991614D01*
G01X161890Y1060000D02*
Y1061181D01*
G01Y1056850D02*
Y1058031D01*
G01Y1053700D02*
Y1054882D01*
G01Y1050551D02*
Y1051732D01*
G01Y1047401D02*
Y1048582D01*
G01X161417Y1045728D02*
Y1045826D01*
G01Y1044153D02*
Y1045728D01*
G01Y1044055D02*
Y1044153D01*
G01Y1040728D02*
Y1040826D01*
G01Y1039153D02*
Y1040728D01*
G01Y1039055D02*
Y1039153D01*
G01Y1035728D02*
Y1035826D01*
G01Y1034055D02*
Y1034153D01*
G01D02*
Y1035728D01*
G01Y1030728D02*
Y1030826D01*
G01Y1029055D02*
Y1029153D01*
G01D02*
Y1030728D01*
G01Y1025728D02*
Y1025826D01*
G01Y1024055D02*
Y1024153D01*
G01D02*
Y1025728D01*
G01Y1020728D02*
Y1020826D01*
G01Y1019055D02*
Y1019153D01*
G01D02*
Y1020728D01*
G01Y1015728D02*
Y1015826D01*
G01Y1014055D02*
Y1014153D01*
G01D02*
Y1015728D01*
G01X161102Y1048582D02*
Y1047401D01*
G01Y1051732D02*
Y1050551D01*
G01Y1054882D02*
Y1053700D01*
G01Y1058031D02*
Y1056850D01*
G01Y1061181D02*
Y1060000D01*
G01X160709Y1048582D02*
Y1047401D01*
G01Y1051732D02*
Y1050551D01*
G01Y1058031D02*
Y1056850D01*
G01Y1054882D02*
Y1053700D01*
G01Y1061181D02*
Y1060000D01*
G01X160630Y1055669D02*
Y1056063D01*
G01Y1058819D02*
Y1059212D01*
G01Y1052519D02*
Y1052913D01*
G01Y1046417D02*
Y1046614D01*
G01Y1049370D02*
Y1049763D01*
G01X158465Y1038819D02*
Y1036063D01*
G01X158150Y1047382D02*
Y1047217D01*
G01Y1048825D02*
Y1048694D01*
G01X157982Y1048825D02*
Y1048694D01*
G01X157949Y1047217D02*
Y1047401D01*
G01D02*
Y1047414D01*
G01X157781Y1047611D02*
Y1047808D01*
G01X157677Y991614D02*
Y990039D01*
G01X157480Y984901D02*
Y997854D01*
G01Y1047401D02*
Y1047217D01*
G01Y1047414D02*
Y1047401D01*
G01X157446Y1048694D02*
Y1048825D01*
G01X157312D02*
Y1048694D01*
G01X157284Y1045826D02*
Y1046417D01*
G01X157279Y1047217D02*
Y1047401D01*
G01D02*
Y1047414D01*
G01X157011Y1046889D02*
Y1046693D01*
G01X156776Y1047401D02*
Y1047152D01*
G01Y1047414D02*
Y1047401D01*
G01X156743Y1048694D02*
Y1048825D01*
G01X156575Y1047152D02*
Y1047401D01*
G01Y1048661D02*
Y1048858D01*
G01Y1047401D02*
Y1047414D01*
G01X156102Y1060000D02*
Y1061181D01*
G01Y1053700D02*
Y1054882D01*
G01Y1056850D02*
Y1058031D01*
G01Y1050551D02*
Y1051732D01*
G01Y1047401D02*
Y1048582D01*
G01X155787Y1044153D02*
Y1045728D01*
G01Y1039153D02*
Y1040728D01*
G01Y1034153D02*
Y1035728D01*
G01Y1029153D02*
Y1030728D01*
G01Y1024153D02*
Y1025728D01*
G01Y1019153D02*
Y1020728D01*
G01Y1014153D02*
Y1015728D01*
G01X154213Y1044153D02*
Y1045728D01*
G01Y1039153D02*
Y1040728D01*
G01Y1034153D02*
Y1035728D01*
G01Y1029153D02*
Y1030728D01*
G01Y1024153D02*
Y1025728D01*
G01Y1019153D02*
Y1020728D01*
G01Y1014153D02*
Y1015728D01*
G01X153543Y1042008D02*
Y1042874D01*
G01Y1037008D02*
Y1037874D01*
G01Y1032008D02*
Y1032874D01*
G01Y1027008D02*
Y1027874D01*
G01Y1022008D02*
Y1022874D01*
G01Y1017008D02*
Y1017874D01*
G01Y1011122D02*
Y1012874D01*
G01Y980964D02*
Y993917D01*
G01X153425Y1015728D02*
Y1014153D01*
G01Y1020728D02*
Y1019153D01*
G01Y1025728D02*
Y1024153D01*
G01Y1030728D02*
Y1029153D01*
G01Y1035728D02*
Y1034153D01*
G01Y1040728D02*
Y1039153D01*
G01Y1045728D02*
Y1044153D01*
G01X153032Y1015728D02*
Y1014153D01*
G01Y1020728D02*
Y1019153D01*
G01Y1025728D02*
Y1024153D01*
G01Y1030728D02*
Y1029153D01*
G01Y1035728D02*
Y1034153D01*
G01Y1040728D02*
Y1039153D01*
G01Y1045728D02*
Y1044153D01*
G01X150866Y1015728D02*
Y1015846D01*
G01Y1015649D02*
Y1015728D01*
G01Y1014665D02*
Y1014501D01*
G01X150665D02*
Y1014698D01*
G01X150498Y1014895D02*
Y1015091D01*
G01X150196Y1014698D02*
Y1014501D01*
G01X149995D02*
Y1014698D01*
G01X149727Y1014153D02*
Y1013976D01*
G01Y1014173D02*
Y1014153D01*
G01X149493Y1014698D02*
Y1014435D01*
G01X149291D02*
Y1014698D01*
G01Y1015846D02*
Y1015728D01*
G01D02*
Y1015649D01*
G01X148110Y1044153D02*
Y1045728D01*
G01Y1039153D02*
Y1040728D01*
G01Y1034153D02*
Y1035728D01*
G01Y1029153D02*
Y1030728D01*
G01Y1024153D02*
Y1025728D01*
G01Y1019153D02*
Y1020728D01*
G01Y1014153D02*
Y1015728D01*
G01X145669Y997854D02*
Y1011122D01*
G01X141732Y1160964D02*
Y993917D01*
G01X158661Y1124055D02*
X153543Y1122874D01*
G01X158661Y1084055D02*
X153543Y1082874D01*
G01X161417Y1140826D02*
X156693D01*
G01X197638D02*
X165354D01*
G01Y1140728D02*
X195877D01*
G01X148110D02*
X165354D01*
G01Y1139153D02*
X195877D01*
G01X165354D02*
X148110D01*
G01X165354Y1139055D02*
X197638D01*
G01X156693D02*
X161417D01*
G01X165354Y1135826D02*
X197638D01*
G01X161417D02*
X156693D01*
G01X165354Y1135728D02*
X195877D01*
G01X148110D02*
X165354D01*
G01Y1134153D02*
X195877D01*
G01X165354D02*
X148110D01*
G01X165354Y1134055D02*
X197638D01*
G01X156693D02*
X161417D01*
G01X165354Y1130826D02*
X197638D01*
G01X161417D02*
X156693D01*
G01X165354Y1130728D02*
X195877D01*
G01X148110D02*
X165354D01*
G01Y1129153D02*
X195877D01*
G01X165354D02*
X148110D01*
G01X165354Y1129055D02*
X197638D01*
G01X156693D02*
X161417D01*
G01X166535Y1127303D02*
X165354D01*
G01X163386Y1125826D02*
X158661D01*
G01X197638D02*
X166535D01*
G01Y1125728D02*
X195877D01*
G01X146654D02*
X166535D01*
G01Y1124153D02*
X195877D01*
G01X146654D02*
X166535D01*
G01Y1124055D02*
X197638D01*
G01X158661D02*
X163386D01*
G01X158465Y1123819D02*
X165354D01*
G01Y1122578D02*
X166535D01*
G01X165354Y1121063D02*
X158465D01*
G01X165354Y1120826D02*
X197638D01*
G01X161417D02*
X156693D01*
G01X165354Y1120728D02*
X195877D01*
G01X148110D02*
X165354D01*
G01Y1119153D02*
X195877D01*
G01X165354D02*
X148110D01*
G01X165354Y1119055D02*
X197638D01*
G01X156693D02*
X161417D01*
G01X165354Y1115826D02*
X197638D01*
G01X161417D02*
X156693D01*
G01X165354Y1115728D02*
X195877D01*
G01X148110D02*
X165354D01*
G01Y1114153D02*
X195877D01*
G01X165354D02*
X148110D01*
G01X165354Y1114055D02*
X197638D01*
G01X156693D02*
X161417D01*
G01X165354Y1110826D02*
X197638D01*
G01X161417D02*
X156693D01*
G01X165354Y1110728D02*
X195877D01*
G01X148110D02*
X165354D01*
G01Y1109153D02*
X195877D01*
G01X165354D02*
X148110D01*
G01X165354Y1109055D02*
X197638D01*
G01X156693D02*
X161417D01*
G01X165354Y1105826D02*
X197638D01*
G01X161417D02*
X156693D01*
G01X165354Y1105728D02*
X195877D01*
G01X148110D02*
X165354D01*
G01Y1104153D02*
X195877D01*
G01X165354D02*
X148110D01*
G01X165354Y1104055D02*
X197638D01*
G01X156693D02*
X161417D01*
G01X165354Y1100826D02*
X197638D01*
G01X161417D02*
X156693D01*
G01X165354Y1100728D02*
X195877D01*
G01X148110D02*
X165354D01*
G01Y1099153D02*
X195877D01*
G01X165354D02*
X148110D01*
G01X165354Y1099055D02*
X197638D01*
G01X156693D02*
X161417D01*
G01X158465Y1098819D02*
X165354D01*
G01Y1096063D02*
X158465D01*
G01X165354Y1095826D02*
X197638D01*
G01X161417D02*
X156693D01*
G01X165354Y1095728D02*
X195877D01*
G01X148110D02*
X165354D01*
G01Y1094153D02*
X195877D01*
G01X165354D02*
X148110D01*
G01X165354Y1094055D02*
X197638D01*
G01X156693D02*
X161417D01*
G01X165354Y1090826D02*
X197638D01*
G01X161417D02*
X156693D01*
G01X165354Y1090728D02*
X195877D01*
G01X148110D02*
X165354D01*
G01Y1089153D02*
X195877D01*
G01X165354D02*
X148110D01*
G01X165354Y1089055D02*
X197638D01*
G01X156693D02*
X161417D01*
G01X166535Y1087303D02*
X165354D01*
G01X163386Y1085826D02*
X158661D01*
G01X197638D02*
X166535D01*
G01Y1085728D02*
X195877D01*
G01X146654D02*
X166535D01*
G01Y1084153D02*
X195877D01*
G01X146654D02*
X166535D01*
G01Y1084055D02*
X197638D01*
G01X158661D02*
X163386D01*
G01X165354Y1082578D02*
X166535D01*
G01X153543Y1127008D02*
X158661Y1125826D01*
G01X165354Y1080826D02*
X197638D01*
G01X161417D02*
X156693D01*
G01X165354Y1080728D02*
X195877D01*
G01X148110D02*
X165354D01*
G01Y1079153D02*
X195877D01*
G01X165354D02*
X148110D01*
G01X165354Y1079055D02*
X197638D01*
G01X156693D02*
X161417D01*
G01X165354Y1075826D02*
X197638D01*
G01X161417D02*
X156693D01*
G01X165354Y1075728D02*
X195877D01*
G01X148110D02*
X165354D01*
G01Y1074153D02*
X148110D01*
G01X195877D02*
X165354D01*
G01Y1074055D02*
X197638D01*
G01X156693D02*
X161417D01*
G01X158465Y1073819D02*
X165354D01*
G01Y1071063D02*
X158465D01*
G01X150906Y1070885D02*
X149331D01*
G01X165354Y1070826D02*
X194685D01*
G01X161417D02*
X156693D01*
G01X165354Y1070728D02*
X195756D01*
G01X146654D02*
X165354D01*
G01X149331Y1070689D02*
X150638D01*
G01X150403Y1070492D02*
X150671D01*
G01X150537Y1070229D02*
X150403D01*
G01X150437Y1070032D02*
X150537D01*
G01X165354Y1069645D02*
X197638D01*
G01X150738Y1069212D02*
X150235D01*
G01X150035D02*
X149331D01*
G01X165354Y1069153D02*
X195756D01*
G01X146654D02*
X165354D01*
G01Y1069055D02*
X194685D01*
G01X157284D02*
X161417D01*
G01X149331Y1069015D02*
X150906D01*
G01X160630Y1068464D02*
X157284D01*
G01X168110Y1067578D02*
X197441D01*
G01X162992D02*
X165354D01*
G01X168110Y1067480D02*
X194215D01*
G01X156102D02*
X168110D01*
G01X177165Y1067204D02*
X195669D01*
G01X156102Y1066299D02*
X168110D01*
G01X194215D02*
X168110D01*
G01Y1066200D02*
X197441D01*
G01X162992D02*
X165354D01*
G01X168110Y1064429D02*
X197441D01*
G01X162992D02*
X165354D01*
G01X168110Y1064330D02*
X194215D01*
G01X156102D02*
X168110D01*
G01X156102Y1063149D02*
X168110D01*
G01X194215D02*
X168110D01*
G01Y1063051D02*
X197441D01*
G01X162992D02*
X165354D01*
G01X168110Y1061279D02*
X197441D01*
G01X162992D02*
X165354D01*
G01X168110Y1061181D02*
X194215D01*
G01X156102D02*
X168110D01*
G01X153543Y1142008D02*
X156693Y1140826D01*
G01X153543Y1137008D02*
X156693Y1135826D01*
G01X153543Y1132008D02*
X156693Y1130826D01*
G01X153543Y1122008D02*
X156693Y1120826D01*
G01X153543Y1117008D02*
X156693Y1115826D01*
G01X153543Y1112008D02*
X156693Y1110826D01*
G01X153543Y1107008D02*
X156693Y1105826D01*
G01X153543Y1102008D02*
X156693Y1100826D01*
G01X153543Y1097008D02*
X156693Y1095826D01*
G01X153543Y1092008D02*
X156693Y1090826D01*
G01X153543Y1082008D02*
X156693Y1080826D01*
G01X153543Y1077008D02*
X156693Y1075826D01*
G01X153543Y1072008D02*
X156693Y1070826D01*
G01X150638Y1070196D02*
X150537Y1070229D01*
G01Y1070032D02*
X150638Y1070000D01*
G01X160630Y1068267D02*
X162992Y1067578D01*
G01X160630Y1065118D02*
X162992Y1064429D01*
G01X160630Y1061968D02*
X162992Y1061279D01*
G01X153543Y1087008D02*
X158661Y1085826D01*
G01X150638Y1070000D02*
X150705Y1069934D01*
G01X150772Y1070098D02*
X150638Y1070196D01*
G01X162992Y1063051D02*
X160630Y1062362D01*
G01X162992Y1066200D02*
X160630Y1065511D01*
G01X150336Y1070000D02*
X150437Y1070032D01*
G01X150403Y1070229D02*
X150302Y1070196D01*
G01X156693Y1074055D02*
X153543Y1072874D01*
G01X156693Y1079055D02*
X153543Y1077874D01*
G01X156693Y1089055D02*
X153543Y1087874D01*
G01X150872Y1069967D02*
X150772Y1070098D01*
G01X156693Y1094055D02*
X153543Y1092874D01*
G01X156693Y1099055D02*
X153543Y1097874D01*
G01X156693Y1104055D02*
X153543Y1102874D01*
G01X156693Y1109055D02*
X153543Y1107874D01*
G01X156693Y1114055D02*
X153543Y1112874D01*
G01X156693Y1119055D02*
X153543Y1117874D01*
G01X156693Y1129055D02*
X153543Y1127874D01*
G01X156693Y1134055D02*
X153543Y1132874D01*
G01X156693Y1139055D02*
X153543Y1137874D01*
G01X150302Y1070196D02*
X150169Y1070098D01*
G01X150671Y1070492D02*
X150906Y1070689D01*
G01Y1069803D02*
X150872Y1069967D01*
G01X150705Y1069934D02*
X150738Y1069835D01*
G01X150638Y1070689D02*
X150403Y1070492D01*
G01X150269Y1069934D02*
X150336Y1070000D01*
G01X150169Y1070098D02*
X150068Y1069967D01*
G01X166535Y1122578D02*
Y1127303D01*
G01Y1082578D02*
Y1087303D01*
G01X165354Y1125728D02*
Y1145531D01*
G01Y1085728D02*
Y1124153D01*
G01Y1067480D02*
Y1084153D01*
G01Y1063149D02*
Y1061181D01*
G01Y1066299D02*
Y1064330D01*
G01D02*
Y1063149D01*
G01Y1067480D02*
Y1066299D01*
G01Y1085728D02*
Y1084153D01*
G01Y1125728D02*
Y1124153D01*
G01X163465Y1066299D02*
Y1067480D01*
G01Y1063149D02*
Y1064330D01*
G01X163386Y1125728D02*
Y1125826D01*
G01Y1124153D02*
Y1125728D01*
G01Y1124055D02*
Y1124153D01*
G01Y1085728D02*
Y1085826D01*
G01Y1084055D02*
Y1084153D01*
G01D02*
Y1085728D01*
G01X161890Y1066299D02*
Y1067480D01*
G01Y1063149D02*
Y1064330D01*
G01X161417Y1140728D02*
Y1140826D01*
G01Y1139055D02*
Y1139153D01*
G01D02*
Y1140728D01*
G01Y1135728D02*
Y1135826D01*
G01Y1134153D02*
Y1135728D01*
G01Y1134055D02*
Y1134153D01*
G01Y1130728D02*
Y1130826D01*
G01Y1129153D02*
Y1130728D01*
G01Y1129055D02*
Y1129153D01*
G01Y1120728D02*
Y1120826D01*
G01Y1119153D02*
Y1120728D01*
G01Y1119055D02*
Y1119153D01*
G01Y1115728D02*
Y1115826D01*
G01Y1114153D02*
Y1115728D01*
G01Y1114055D02*
Y1114153D01*
G01Y1110728D02*
Y1110826D01*
G01Y1109055D02*
Y1109153D01*
G01D02*
Y1110728D01*
G01Y1105728D02*
Y1105826D01*
G01Y1104055D02*
Y1104153D01*
G01D02*
Y1105728D01*
G01Y1100728D02*
Y1100826D01*
G01Y1099055D02*
Y1099153D01*
G01D02*
Y1100728D01*
G01Y1095728D02*
Y1095826D01*
G01Y1094055D02*
Y1094153D01*
G01D02*
Y1095728D01*
G01Y1090728D02*
Y1090826D01*
G01Y1089055D02*
Y1089153D01*
G01D02*
Y1090728D01*
G01Y1080728D02*
Y1080826D01*
G01Y1079055D02*
Y1079153D01*
G01D02*
Y1080728D01*
G01Y1075728D02*
Y1075826D01*
G01Y1074055D02*
Y1074153D01*
G01D02*
Y1075728D01*
G01Y1070728D02*
Y1070826D01*
G01Y1069055D02*
Y1069153D01*
G01D02*
Y1070728D01*
G01X161102Y1067480D02*
Y1066299D01*
G01Y1064330D02*
Y1063149D01*
G01X160709Y1067480D02*
Y1066299D01*
G01Y1064330D02*
Y1063149D01*
G01X160630Y1068267D02*
Y1068464D01*
G01Y1065118D02*
Y1065511D01*
G01Y1061968D02*
Y1062362D01*
G01X158465Y1073819D02*
Y1071063D01*
G01Y1098819D02*
Y1096063D01*
G01Y1123819D02*
Y1121063D01*
G01X157284Y1068464D02*
Y1069055D01*
G01X156102Y1066299D02*
Y1067480D01*
G01Y1063149D02*
Y1064330D01*
G01X155787Y1139153D02*
Y1140728D01*
G01Y1134153D02*
Y1135728D01*
G01Y1129153D02*
Y1130728D01*
G01Y1124153D02*
Y1125728D01*
G01Y1119153D02*
Y1120728D01*
G01Y1114153D02*
Y1115728D01*
G01Y1109153D02*
Y1110728D01*
G01Y1104153D02*
Y1105728D01*
G01Y1099153D02*
Y1100728D01*
G01Y1094153D02*
Y1095728D01*
G01Y1089153D02*
Y1090728D01*
G01Y1084153D02*
Y1085728D01*
G01Y1079153D02*
Y1080728D01*
G01Y1074153D02*
Y1075728D01*
G01Y1069153D02*
Y1070728D01*
G01X154213Y1139153D02*
Y1140728D01*
G01Y1134153D02*
Y1135728D01*
G01Y1129153D02*
Y1130728D01*
G01Y1124153D02*
Y1125728D01*
G01Y1119153D02*
Y1120728D01*
G01Y1114153D02*
Y1115728D01*
G01Y1109153D02*
Y1110728D01*
G01Y1104153D02*
Y1105728D01*
G01Y1099153D02*
Y1100728D01*
G01Y1094153D02*
Y1095728D01*
G01Y1089153D02*
Y1090728D01*
G01Y1084153D02*
Y1085728D01*
G01Y1079153D02*
Y1080728D01*
G01Y1074153D02*
Y1075728D01*
G01Y1069153D02*
Y1070728D01*
G01X153543Y1142008D02*
Y1143759D01*
G01Y1137008D02*
Y1137874D01*
G01Y1132008D02*
Y1132874D01*
G01Y1127008D02*
Y1127874D01*
G01Y1122008D02*
Y1122874D01*
G01Y1117008D02*
Y1117874D01*
G01Y1112008D02*
Y1112874D01*
G01Y1107008D02*
Y1107874D01*
G01Y1102008D02*
Y1102874D01*
G01Y1097008D02*
Y1097874D01*
G01Y1092008D02*
Y1092874D01*
G01Y1087008D02*
Y1087874D01*
G01Y1082008D02*
Y1082874D01*
G01Y1077008D02*
Y1077874D01*
G01Y1072008D02*
Y1072874D01*
G01X153425Y1070728D02*
Y1069153D01*
G01Y1075728D02*
Y1074153D01*
G01Y1080728D02*
Y1079153D01*
G01Y1085728D02*
Y1084153D01*
G01Y1090728D02*
Y1089153D01*
G01Y1095728D02*
Y1094153D01*
G01Y1100728D02*
Y1099153D01*
G01Y1105728D02*
Y1104153D01*
G01Y1110728D02*
Y1109153D01*
G01Y1115728D02*
Y1114153D01*
G01Y1120728D02*
Y1119153D01*
G01Y1125728D02*
Y1124153D01*
G01Y1130728D02*
Y1129153D01*
G01Y1135728D02*
Y1134153D01*
G01Y1140728D02*
Y1139153D01*
G01X153032Y1070728D02*
Y1069153D01*
G01Y1075728D02*
Y1074153D01*
G01Y1080728D02*
Y1079153D01*
G01Y1085728D02*
Y1084153D01*
G01Y1090728D02*
Y1089153D01*
G01Y1095728D02*
Y1094153D01*
G01Y1100728D02*
Y1099153D01*
G01Y1105728D02*
Y1104153D01*
G01Y1110728D02*
Y1109153D01*
G01Y1115728D02*
Y1114153D01*
G01Y1120728D02*
Y1119153D01*
G01Y1125728D02*
Y1124153D01*
G01Y1130728D02*
Y1129153D01*
G01Y1135728D02*
Y1134153D01*
G01Y1140728D02*
Y1139153D01*
G01X150906Y1070728D02*
Y1070885D01*
G01Y1069015D02*
Y1069153D01*
G01Y1070689D02*
Y1070728D01*
G01Y1069153D02*
Y1069803D01*
G01X150738Y1069835D02*
Y1069212D01*
G01X150235D02*
Y1069835D01*
G01X150035Y1069803D02*
Y1069212D01*
G01X149331Y1070885D02*
Y1070728D01*
G01Y1069153D02*
Y1069015D01*
G01Y1070728D02*
Y1070689D01*
G01Y1069212D02*
Y1069153D01*
G01X150235Y1069835D02*
X150269Y1069934D01*
G01X150068Y1069967D02*
X150035Y1069803D01*
G01X148110Y1139153D02*
Y1140728D01*
G01Y1134153D02*
Y1135728D01*
G01Y1129153D02*
Y1130728D01*
G01Y1119153D02*
Y1120728D01*
G01Y1114153D02*
Y1115728D01*
G01Y1109153D02*
Y1110728D01*
G01Y1104153D02*
Y1105728D01*
G01Y1099153D02*
Y1100728D01*
G01Y1094153D02*
Y1095728D01*
G01Y1089153D02*
Y1090728D01*
G01Y1079153D02*
Y1080728D01*
G01Y1074153D02*
Y1075728D01*
G01X146654Y1124153D02*
Y1125728D01*
G01Y1084153D02*
Y1085728D01*
G01Y1069153D02*
Y1070728D01*
G01X171063Y1164055D02*
G03I-3740J0D01*
G01X156054Y1153819D02*
G03Y1150669I2017J-1575D01*
G01X160088D02*
G03Y1153819I-2017J1575D01*
G01X160441Y1149882D02*
G03Y1154606I-2370J2362D01*
G01X155701D02*
G03Y1149882I2370J-2362D01*
G01X161575Y1152244D02*
G03I-3504J0D01*
G01X160748Y1149094D02*
G03Y1155393I-2677J3149D01*
G01X155394D02*
G03Y1149094I2677J-3150D01*
G01X153543Y1173917D02*
X181102D01*
G01X177165Y1169980D02*
X157480D01*
G01X177165Y1168011D02*
X157480D01*
G01X177165Y1166023D02*
X157480D01*
G01Y1165039D02*
X177165D01*
G01X176969Y1164842D02*
X157677D01*
G01X176969Y1163267D02*
X157677D01*
G01X177165Y1163070D02*
X157480D01*
G01Y1162086D02*
X177165D01*
G01X153543Y1160964D02*
X141732D01*
G01X177165Y1158996D02*
X157480D01*
G01X199606Y1157027D02*
X145669D01*
G01X166142Y1155846D02*
X199606D01*
G01X155394Y1155393D02*
X160748D01*
G01X160441Y1154606D02*
X155701D01*
G01X156054Y1153819D02*
X160088D01*
G01X166142Y1151633D02*
X145669D01*
G01X177165D02*
X166142D01*
G01X156054Y1150669D02*
X160088D01*
G01X155701Y1149882D02*
X160441D01*
G01X160748Y1149094D02*
X155394D01*
G01X195669Y1148681D02*
X145669D01*
G01X165354Y1145531D02*
X145669D01*
G01Y1143759D02*
X165354D01*
G01D02*
X166634D01*
G01X196457D02*
X168012D01*
G01X177165Y1157027D02*
Y1169980D01*
G01X176969Y1163267D02*
Y1164842D01*
G01X171614D02*
Y1163267D01*
G01X170276Y1163070D02*
Y1163267D01*
G01Y1164842D02*
Y1165039D01*
G01Y1164842D02*
Y1163267D01*
G01X170079Y1164842D02*
Y1163267D01*
G01X168504Y1164842D02*
Y1163267D01*
G01X166142Y1148681D02*
Y1157027D01*
G01Y1164842D02*
Y1163267D01*
G01X164567D02*
Y1164842D01*
G01X164370D02*
Y1165039D01*
G01Y1163267D02*
Y1164842D01*
G01Y1163267D02*
Y1163070D01*
G01X163032Y1163267D02*
Y1164842D01*
G01X157677D02*
Y1163267D01*
G01X157480Y1157027D02*
Y1169980D01*
G01X153543Y1160964D02*
Y1173917D01*
G01X145669Y1143759D02*
Y1157027D01*
G01X162597Y1380846D02*
Y1378878D01*
G01Y1376319D02*
Y1378287D01*
G01X164172Y1381142D02*
Y1380551D01*
G01Y1379370D02*
Y1377795D01*
G01Y1376614D02*
Y1376024D01*
G01X165156Y1381142D02*
Y1376024D01*
G01X165353D02*
Y1381142D01*
G01X165747Y1378287D02*
Y1376319D01*
G01Y1378878D02*
Y1380846D01*
G01X168897Y1378287D02*
Y1376319D01*
G01Y1378878D02*
Y1380846D01*
G01X169290Y1376024D02*
Y1381142D01*
G01X169487D02*
Y1376024D01*
G01X164172D02*
X170471D01*
G01X165747Y1376319D02*
X164172D01*
G01D02*
X162597D01*
G01X168897D02*
X170471D01*
G01Y1378287D02*
X168897D01*
G01X164172D02*
X165747D01*
G01X162597D02*
X164172D01*
G01X170471Y1378878D02*
X168897D01*
G01X164172D02*
X165747D01*
G01X162597D02*
X164172D01*
G01X165747Y1380846D02*
X164172D01*
G01D02*
X162597D01*
G01X168897D02*
X170471D01*
G01X164172Y1381142D02*
X170471D01*
G01X164172Y1376614D02*
G03Y1377795I0J591D01*
G01Y1379370D02*
G03Y1380551I0J590D01*
G01X170461Y1379750D02*
X170554Y1379861D01*
G01Y1379733D02*
X170461Y1379622D01*
G01X170367D02*
Y1380370D01*
G01X170461D02*
Y1379750D01*
G01X170471Y1376024D02*
Y1376614D01*
G01Y1377795D02*
Y1379370D01*
G01Y1380551D02*
Y1381142D01*
G01X170554Y1379861D02*
Y1379733D01*
G01X172046Y1380846D02*
Y1378878D01*
G01Y1376319D02*
Y1378287D01*
G01X170471Y1376319D02*
X172046D01*
G01Y1378287D02*
X170471D01*
G01X172046Y1378878D02*
X170471D01*
G01X170461Y1379622D02*
X170367D01*
G01Y1380370D02*
X170461D01*
G01X170471Y1380846D02*
X172046D01*
G01X170471Y1377795D02*
G03Y1376614I1J-591D01*
G01Y1380551D02*
G03Y1379370I1J-591D01*
G01X157480Y1390413D02*
X177165D01*
G01X181102Y1386476D02*
X153543D01*
G01X177165Y1390413D02*
Y1403366D01*
G01X157480Y1390413D02*
Y1403366D01*
G01X153543Y1386476D02*
Y1399429D01*
G01X157996Y1412283D02*
X158071D01*
G01X158146Y1404016D02*
X158071Y1404015D01*
G01X160630Y1408149D02*
G03I-2559J0D01*
G01X161417D02*
G03I-3346J0D01*
G01X161575D02*
G03I-3504J0D01*
G01X171063Y1396338D02*
G03I-3740J0D01*
G01X158146Y1404016D02*
G03X158071Y1412283I-75J4133D01*
G01X157996Y1412282D02*
G03X158071Y1404015I74J-4133D01*
G01X168110Y1473090D02*
X197441D01*
G01X162992D02*
X165354D01*
G01X168110Y1472992D02*
X194215D01*
G01X156102D02*
X168110D01*
G01X177165Y1472716D02*
X195669D01*
G01X156102Y1471811D02*
X168110D01*
G01X194215D02*
X168110D01*
G01Y1471712D02*
X197441D01*
G01X162992D02*
X165354D01*
G01X168110Y1469941D02*
X197441D01*
G01X162992D02*
X165354D01*
G01X168110Y1469842D02*
X194215D01*
G01X156102D02*
X168110D01*
G01X156102Y1468661D02*
X168110D01*
G01X194215D02*
X168110D01*
G01Y1468563D02*
X197441D01*
G01X162992D02*
X165354D01*
G01X168110Y1466791D02*
X197441D01*
G01X162992D02*
X165354D01*
G01X168110Y1466693D02*
X194215D01*
G01X156102D02*
X168110D01*
G01X156102Y1465511D02*
X168110D01*
G01X194215D02*
X168110D01*
G01Y1465413D02*
X197441D01*
G01X162992D02*
X165354D01*
G01X168110Y1463641D02*
X197441D01*
G01X162992D02*
X165354D01*
G01X168110Y1463543D02*
X194215D01*
G01X156102D02*
X168110D01*
G01X157915Y1452335D02*
X157781Y1452303D01*
G01X150632Y1419619D02*
X150498Y1419586D01*
G01X156102Y1462362D02*
X168110D01*
G01X194215D02*
X168110D01*
G01Y1462263D02*
X197441D01*
G01X162992D02*
X165354D01*
G01X168110Y1460492D02*
X197441D01*
G01X162992D02*
X165354D01*
G01X168110Y1460393D02*
X194215D01*
G01X156102D02*
X168110D01*
G01X156102Y1459212D02*
X168110D01*
G01X194215D02*
X168110D01*
G01Y1459114D02*
X197441D01*
G01X162992D02*
X165354D01*
G01X168110Y1457342D02*
X197441D01*
G01X162992D02*
X165354D01*
G01X168110Y1457244D02*
X194215D01*
G01X156102D02*
X168110D01*
G01X156102Y1456063D02*
X168110D01*
G01X194215D02*
X168110D01*
G01Y1455964D02*
X197441D01*
G01X162992D02*
X165354D01*
G01X156977Y1454862D02*
X157078D01*
G01X157647Y1454829D02*
X157748D01*
G01X156977Y1454698D02*
X157078D01*
G01X157681Y1454665D02*
X157748D01*
G01X162992Y1454193D02*
X165354D01*
G01X197441D02*
X168110D01*
G01Y1454094D02*
X194215D01*
G01X156102D02*
X168110D01*
G01X157748Y1453878D02*
X157681D01*
G01X157078Y1453845D02*
X156977D01*
G01X157748Y1453713D02*
X157647D01*
G01X157078Y1453681D02*
X156977D01*
G01X156944Y1453418D02*
X157111D01*
G01X157078Y1453221D02*
X156977D01*
G01X195669Y1453189D02*
X177165D01*
G01X156102Y1452913D02*
X168110D01*
G01X194215D02*
X168110D01*
G01X162992Y1452815D02*
X165354D01*
G01X197441D02*
X168110D01*
G01X157681Y1452500D02*
X157748D01*
G01X157781Y1452303D02*
X157647D01*
G01X157284Y1451929D02*
X160630D01*
G01X161417Y1451338D02*
X157284D01*
G01X194685D02*
X165354D01*
G01Y1451240D02*
X195756D01*
G01X148110D02*
X165354D01*
G01Y1450748D02*
X197638D01*
G01X165354Y1449665D02*
X148110D01*
G01X195756D02*
X165354D01*
G01Y1449567D02*
X194685D01*
G01X156693D02*
X161417D01*
G01Y1446338D02*
X156693D01*
G01X197638D02*
X165354D01*
G01Y1446240D02*
X195877D01*
G01X148110D02*
X165354D01*
G01Y1444665D02*
X195877D01*
G01X165354D02*
X148110D01*
G01X165354Y1444567D02*
X197638D01*
G01X156693D02*
X161417D01*
G01X158465Y1444330D02*
X165354D01*
G01Y1441574D02*
X158465D01*
G01X165354Y1441338D02*
X197638D01*
G01X161417D02*
X156693D01*
G01X165354Y1441240D02*
X195877D01*
G01X148110D02*
X165354D01*
G01Y1439665D02*
X195877D01*
G01X165354D02*
X148110D01*
G01X165354Y1439567D02*
X197638D01*
G01X156693D02*
X161417D01*
G01X165354Y1436338D02*
X197638D01*
G01X161417D02*
X156693D01*
G01X165354Y1436240D02*
X195877D01*
G01X148110D02*
X165354D01*
G01Y1434665D02*
X195877D01*
G01X165354D02*
X148110D01*
G01X165354Y1434567D02*
X197638D01*
G01X156693D02*
X161417D01*
G01X165354Y1431338D02*
X197638D01*
G01X161417D02*
X156693D01*
G01X165354Y1431240D02*
X195877D01*
G01X148110D02*
X165354D01*
G01Y1429665D02*
X195877D01*
G01X165354D02*
X148110D01*
G01X165354Y1429567D02*
X197638D01*
G01X156693D02*
X161417D01*
G01X165354Y1426338D02*
X197638D01*
G01X161417D02*
X156693D01*
G01X165354Y1426240D02*
X195877D01*
G01X148110D02*
X165354D01*
G01Y1424665D02*
X195877D01*
G01X165354D02*
X148110D01*
G01X165354Y1424567D02*
X197638D01*
G01X156693D02*
X161417D01*
G01X150866Y1421358D02*
X149291D01*
G01X165354Y1421338D02*
X197638D01*
G01X161417D02*
X156693D01*
G01X165354Y1421240D02*
X195877D01*
G01X148110D02*
X165354D01*
G01X149291Y1421161D02*
X150598D01*
G01X150364Y1420964D02*
X150632D01*
G01X149660Y1420702D02*
X149828D01*
G01X149794Y1420505D02*
X149694D01*
G01X150397Y1419783D02*
X150464D01*
G01X165354Y1419665D02*
X195877D01*
G01X165354D02*
X148110D01*
G01X150498Y1419586D02*
X150364D01*
G01X165354Y1419567D02*
X197638D01*
G01X156693D02*
X161417D01*
G01X168012Y1416633D02*
X196457D01*
G01X165354D02*
X166634D01*
G01X165354D02*
X145669D01*
G01Y1414862D02*
X165354D01*
G01X145669Y1411712D02*
X195669D01*
G01X166142Y1408759D02*
X177165D01*
G01X145669D02*
X166142D01*
G01X199606Y1404547D02*
X166142D01*
G01X199606Y1403366D02*
X145669D01*
G01X157480Y1401397D02*
X177165D01*
G01X141732Y1399429D02*
X153543D01*
G01X177165Y1398307D02*
X157480D01*
G01Y1397322D02*
X177165D01*
G01X176969Y1397126D02*
X157677D01*
G01X176969Y1395551D02*
X157677D01*
G01X177165Y1395354D02*
X157480D01*
G01Y1394370D02*
X177165D01*
G01X157480Y1392382D02*
X177165D01*
G01X157781Y1453320D02*
X157882Y1453287D01*
G01X157580Y1452532D02*
X157681Y1452500D01*
G01X156910Y1452434D02*
X157011Y1452401D01*
G01X160630Y1473779D02*
X162992Y1473090D01*
G01X160630Y1470630D02*
X162992Y1469941D01*
G01X160630Y1467480D02*
X162992Y1466791D01*
G01X160630Y1464330D02*
X162992Y1463641D01*
G01X160630Y1461181D02*
X162992Y1460492D01*
G01X160630Y1458031D02*
X162992Y1457342D01*
G01X160630Y1454882D02*
X162992Y1454193D01*
G01X157647Y1452303D02*
X157513Y1452335D01*
G01X157011Y1452204D02*
X156876Y1452237D01*
G01X150364Y1419586D02*
X150230Y1419619D01*
G01X149727Y1419488D02*
X149593Y1419520D01*
G01X157647Y1453713D02*
X157513Y1453779D01*
G01X157848Y1453090D02*
X157781Y1453123D01*
G01X157111Y1453418D02*
X157245Y1453353D01*
G01X157748Y1454829D02*
X157915Y1454763D01*
G01X157078Y1454862D02*
X157245Y1454796D01*
G01X156977Y1453681D02*
X156809Y1453746D01*
G01X153543Y1447519D02*
X156693Y1446338D01*
G01X153543Y1442519D02*
X156693Y1441338D01*
G01X153543Y1437519D02*
X156693Y1436338D01*
G01X153543Y1432519D02*
X156693Y1431338D01*
G01X153543Y1427519D02*
X156693Y1426338D01*
G01X153543Y1422519D02*
X156693Y1421338D01*
G01X150498Y1420603D02*
X150598Y1420570D01*
G01X150297Y1419816D02*
X150397Y1419783D01*
G01X149626Y1419717D02*
X149727Y1419685D01*
G01X157748Y1454665D02*
X157848Y1454599D01*
G01X157681Y1453878D02*
X157580Y1453943D01*
G01X157178Y1453156D02*
X157078Y1453221D01*
G01X156876Y1452237D02*
X156709Y1452335D01*
G01X149593Y1419520D02*
X149426Y1419619D01*
G01X150565Y1420374D02*
X150498Y1420406D01*
G01X149828Y1420702D02*
X149961Y1420636D01*
G01X157078Y1454698D02*
X157211Y1454599D01*
G01X157882Y1453287D02*
X158016Y1453189D01*
G01X156977Y1453845D02*
X156843Y1453943D01*
G01X150598Y1420570D02*
X150732Y1420472D01*
G01X149895Y1420439D02*
X149794Y1420505D01*
G01X157915Y1454763D02*
X158016Y1454665D01*
G01X157513Y1453779D02*
X157413Y1453878D01*
G01X157915Y1453024D02*
X157848Y1453090D01*
G01X157245Y1453353D02*
X157379Y1453221D01*
G01X156809Y1453746D02*
X156709Y1453845D01*
G01X157513Y1452335D02*
X157379Y1452467D01*
G01X156809Y1452532D02*
X156910Y1452434D01*
G01X150632Y1420308D02*
X150565Y1420374D01*
G01X149961Y1420636D02*
X150096Y1420505D01*
G01X150183Y1419665D02*
X150096Y1419750D01*
G01X150230Y1419619D02*
X150183Y1419665D01*
G01X149526Y1419816D02*
X149626Y1419717D01*
G01X157245Y1453058D02*
X157178Y1453156D01*
G01X157513Y1452631D02*
X157580Y1452532D01*
G01X157848Y1454599D02*
X157949Y1454468D01*
G01X157245Y1454796D02*
X157346Y1454665D01*
G01X157580Y1453943D02*
X157480Y1454074D01*
G01X158016Y1453189D02*
X158116Y1453058D01*
G01X150732Y1420472D02*
X150833Y1420341D01*
G01X157346Y1454665D02*
X157379Y1454599D01*
G01X157211D02*
X157279Y1454468D01*
G01X157413Y1453878D02*
X157379Y1453943D01*
G01Y1453221D02*
X157446Y1453090D01*
G01X156843Y1453943D02*
X156776Y1454074D01*
G01X157379Y1452467D02*
X157312Y1452598D01*
G01X150096Y1420505D02*
X150163Y1420374D01*
G01X150096Y1419750D02*
X150029Y1419882D01*
G01X158016Y1454665D02*
X158116Y1454501D01*
G01X156709Y1453845D02*
X156608Y1454009D01*
G01X156709Y1452335D02*
X156608Y1452500D01*
G01X149426Y1419619D02*
X149397Y1419665D01*
G01D02*
X149325Y1419783D01*
G01X149961Y1420341D02*
X149895Y1420439D01*
G01X150230Y1419914D02*
X150297Y1419816D01*
G01X157949Y1452926D02*
X157915Y1453024D01*
G01X157480Y1452729D02*
X157513Y1452631D01*
G01X150665Y1420209D02*
X150632Y1420308D01*
G01X150196Y1420013D02*
X150230Y1419914D01*
G01X158116Y1454501D02*
X158150Y1454337D01*
G01X158146Y1452913D02*
X158150Y1452893D01*
G01X158116Y1453058D02*
X158146Y1452913D01*
G01X157446Y1453090D02*
X157480Y1452926D01*
G01X156591Y1454094D02*
X156575Y1454173D01*
G01X156608Y1454009D02*
X156591Y1454094D01*
G01X156608Y1452500D02*
X156575Y1452664D01*
G01X150833Y1420341D02*
X150866Y1420177D01*
G01X150163Y1420374D02*
X150196Y1420209D01*
G01X149325Y1419783D02*
X149291Y1419947D01*
G01X157949Y1454468D02*
X157982Y1454337D01*
G01X157474Y1454094D02*
X157446Y1454206D01*
G01X157480Y1454074D02*
X157474Y1454094D01*
G01X157279Y1454468D02*
X157312Y1454337D01*
G01X157279Y1452926D02*
X157245Y1453058D01*
G01X157312Y1452598D02*
X157279Y1452729D01*
G01X156771Y1454094D02*
X156743Y1454206D01*
G01X156776Y1454074D02*
X156771Y1454094D01*
G01X156776Y1452664D02*
X156809Y1452532D01*
G01X149995Y1420209D02*
X149961Y1420341D01*
G01X150029Y1419882D02*
X149995Y1420013D01*
G01X149493Y1419947D02*
X149526Y1419816D01*
G01X177165Y1403366D02*
Y1562539D01*
G01X176969Y1395551D02*
Y1397126D01*
G01X171614D02*
Y1395551D01*
G01X170276Y1397126D02*
Y1397322D01*
G01Y1395354D02*
Y1395551D01*
G01Y1397126D02*
Y1395551D01*
G01X170079Y1397126D02*
Y1395551D01*
G01X169291Y1549271D02*
Y1416633D01*
G01X168504Y1397126D02*
Y1395551D01*
G01X168110Y1450748D02*
Y1475157D01*
G01X168012Y1416633D02*
Y1549271D01*
G01X166634D02*
Y1416633D01*
G01X166142Y1403366D02*
Y1411712D01*
G01Y1397126D02*
Y1395551D01*
G01X165354Y1472992D02*
Y1489665D01*
G01Y1414862D02*
Y1452913D01*
G01Y1456063D02*
Y1454094D01*
G01D02*
Y1452913D01*
G01Y1459212D02*
Y1457244D01*
G01D02*
Y1456063D01*
G01Y1460393D02*
Y1459212D01*
G01Y1462362D02*
Y1460393D01*
G01Y1465511D02*
Y1463543D01*
G01D02*
Y1462362D01*
G01Y1468661D02*
Y1466693D01*
G01D02*
Y1465511D01*
G01Y1469842D02*
Y1468661D01*
G01Y1471811D02*
Y1469842D01*
G01Y1472992D02*
Y1471811D01*
G01X164567Y1395551D02*
Y1397126D01*
G01X164370D02*
Y1397322D01*
G01Y1395551D02*
Y1397126D01*
G01Y1395551D02*
Y1395354D01*
G01X163465Y1471811D02*
Y1472992D01*
G01Y1468661D02*
Y1469842D01*
G01Y1465511D02*
Y1466693D01*
G01Y1462362D02*
Y1463543D01*
G01Y1456063D02*
Y1457244D01*
G01Y1459212D02*
Y1460393D01*
G01Y1452913D02*
Y1454094D01*
G01X163032Y1395551D02*
Y1397126D01*
G01X161890Y1471811D02*
Y1472992D01*
G01Y1468661D02*
Y1469842D01*
G01Y1465511D02*
Y1466693D01*
G01Y1462362D02*
Y1463543D01*
G01Y1459212D02*
Y1460393D01*
G01Y1456063D02*
Y1457244D01*
G01Y1452913D02*
Y1454094D01*
G01X161417Y1451240D02*
Y1451338D01*
G01Y1449567D02*
Y1449665D01*
G01D02*
Y1451240D01*
G01Y1446240D02*
Y1446338D01*
G01Y1444567D02*
Y1444665D01*
G01D02*
Y1446240D01*
G01Y1441240D02*
Y1441338D01*
G01Y1439567D02*
Y1439665D01*
G01D02*
Y1441240D01*
G01Y1436240D02*
Y1436338D01*
G01Y1434567D02*
Y1434665D01*
G01D02*
Y1436240D01*
G01Y1431240D02*
Y1431338D01*
G01Y1429567D02*
Y1429665D01*
G01D02*
Y1431240D01*
G01Y1426240D02*
Y1426338D01*
G01Y1424567D02*
Y1424665D01*
G01D02*
Y1426240D01*
G01Y1421240D02*
Y1421338D01*
G01Y1419665D02*
Y1421240D01*
G01Y1419567D02*
Y1419665D01*
G01X161102Y1454094D02*
Y1452913D01*
G01Y1457244D02*
Y1456063D01*
G01Y1460393D02*
Y1459212D01*
G01Y1463543D02*
Y1462362D01*
G01Y1466693D02*
Y1465511D01*
G01Y1469842D02*
Y1468661D01*
G01Y1472992D02*
Y1471811D01*
G01X160709Y1454094D02*
Y1452913D01*
G01Y1457244D02*
Y1456063D01*
G01Y1460393D02*
Y1459212D01*
G01Y1463543D02*
Y1462362D01*
G01Y1469842D02*
Y1468661D01*
G01Y1466693D02*
Y1465511D01*
G01Y1472992D02*
Y1471811D01*
G01X160630Y1473779D02*
Y1473976D01*
G01Y1467480D02*
Y1467874D01*
G01Y1470630D02*
Y1471023D01*
G01Y1464330D02*
Y1464724D01*
G01Y1458031D02*
Y1458425D01*
G01Y1461181D02*
Y1461574D01*
G01Y1454882D02*
Y1455275D01*
G01Y1451929D02*
Y1452126D01*
G01X158465Y1444330D02*
Y1441574D01*
G01X158150Y1452893D02*
Y1452729D01*
G01Y1454337D02*
Y1454206D01*
G01X157982Y1454337D02*
Y1454206D01*
G01X157949Y1452729D02*
Y1452913D01*
G01D02*
Y1452926D01*
G01X157781Y1453123D02*
Y1453320D01*
G01X157677Y1397126D02*
Y1395551D01*
G01X157480Y1452913D02*
Y1452729D01*
G01Y1452926D02*
Y1452913D01*
G01X157446Y1454206D02*
Y1454337D01*
G01X157312D02*
Y1454206D01*
G01X157284Y1451338D02*
Y1451929D01*
G01X157279Y1452729D02*
Y1452913D01*
G01D02*
Y1452926D01*
G01X157011Y1452401D02*
Y1452204D01*
G01X156776Y1452913D02*
Y1452664D01*
G01Y1452926D02*
Y1452913D01*
G01X156743Y1454206D02*
Y1454337D01*
G01X156575Y1452664D02*
Y1452913D01*
G01Y1454173D02*
Y1454370D01*
G01Y1452913D02*
Y1452926D01*
G01X156102Y1471811D02*
Y1472992D01*
G01Y1465511D02*
Y1466693D01*
G01Y1468661D02*
Y1469842D01*
G01Y1462362D02*
Y1463543D01*
G01Y1456063D02*
Y1457244D01*
G01Y1459212D02*
Y1460393D01*
G01Y1452913D02*
Y1454094D01*
G01X155787Y1449665D02*
Y1451240D01*
G01Y1444665D02*
Y1446240D01*
G01Y1439665D02*
Y1441240D01*
G01Y1434665D02*
Y1436240D01*
G01Y1429665D02*
Y1431240D01*
G01Y1424665D02*
Y1426240D01*
G01Y1419665D02*
Y1421240D01*
G01X154213Y1449665D02*
Y1451240D01*
G01Y1444665D02*
Y1446240D01*
G01Y1439665D02*
Y1441240D01*
G01Y1434665D02*
Y1436240D01*
G01Y1429665D02*
Y1431240D01*
G01Y1424665D02*
Y1426240D01*
G01Y1419665D02*
Y1421240D01*
G01X153543Y1447519D02*
Y1448385D01*
G01Y1442519D02*
Y1443385D01*
G01Y1437519D02*
Y1438385D01*
G01Y1432519D02*
Y1433385D01*
G01Y1427519D02*
Y1428385D01*
G01Y1422519D02*
Y1423385D01*
G01Y1416633D02*
Y1418385D01*
G01X153425Y1421240D02*
Y1419665D01*
G01Y1426240D02*
Y1424665D01*
G01Y1431240D02*
Y1429665D01*
G01Y1436240D02*
Y1434665D01*
G01Y1441240D02*
Y1439665D01*
G01Y1446240D02*
Y1444665D01*
G01Y1451240D02*
Y1449665D01*
G01X153032Y1421240D02*
Y1419665D01*
G01Y1426240D02*
Y1424665D01*
G01Y1431240D02*
Y1429665D01*
G01Y1436240D02*
Y1434665D01*
G01Y1441240D02*
Y1439665D01*
G01Y1446240D02*
Y1444665D01*
G01Y1451240D02*
Y1449665D01*
G01X150866Y1421240D02*
Y1421358D01*
G01Y1421161D02*
Y1421240D01*
G01Y1420177D02*
Y1420013D01*
G01X150665D02*
Y1420209D01*
G01X150498Y1420406D02*
Y1420603D01*
G01X150196Y1420209D02*
Y1420013D01*
G01X149995D02*
Y1420209D01*
G01X149727Y1419665D02*
Y1419488D01*
G01Y1419685D02*
Y1419665D01*
G01X149493Y1420209D02*
Y1419947D01*
G01X149291D02*
Y1420209D01*
G01Y1421358D02*
Y1421240D01*
G01D02*
Y1421161D01*
G01X158150Y1454206D02*
X158127Y1454094D01*
G01D02*
X158116Y1454042D01*
G01X148110Y1449665D02*
Y1451240D01*
G01Y1444665D02*
Y1446240D01*
G01Y1439665D02*
Y1441240D01*
G01Y1434665D02*
Y1436240D01*
G01Y1429665D02*
Y1431240D01*
G01Y1424665D02*
Y1426240D01*
G01Y1419665D02*
Y1421240D01*
G01X145669Y1403366D02*
Y1416633D01*
G01X141732Y1566476D02*
Y1399429D01*
G01X150464Y1419783D02*
X150565Y1419816D01*
G01X150833Y1419882D02*
X150766Y1419750D01*
G01X150632Y1419914D02*
X150665Y1420013D01*
G01X157915Y1452631D02*
X157949Y1452729D01*
G01X150866Y1420013D02*
X150833Y1419882D01*
G01X158150Y1452729D02*
X158116Y1452598D01*
G01X149526Y1420341D02*
X149493Y1420209D01*
G01X157982Y1454206D02*
X157954Y1454094D01*
G01D02*
X157949Y1454074D01*
G01X157446Y1454337D02*
X157480Y1454468D01*
G01X157312Y1454206D02*
X157284Y1454094D01*
G01D02*
X157279Y1454074D01*
G01X156809Y1453058D02*
X156776Y1452926D01*
G01X156743Y1454337D02*
X156776Y1454468D01*
G01X156575Y1452926D02*
X156608Y1453090D01*
G01X156575Y1454370D02*
X156608Y1454534D01*
G01X149291Y1420209D02*
X149325Y1420374D01*
G01X162992Y1452815D02*
X160630Y1452126D01*
G01X162992Y1455964D02*
X160630Y1455275D01*
G01X162992Y1459114D02*
X160630Y1458425D01*
G01X162992Y1462263D02*
X160630Y1461574D01*
G01X162992Y1465413D02*
X160630Y1464724D01*
G01X162992Y1468563D02*
X160630Y1467874D01*
G01X162992Y1471712D02*
X160630Y1471023D01*
G01X157748Y1452500D02*
X157848Y1452532D01*
G01X156693Y1419567D02*
X153543Y1418385D01*
G01X156693Y1424567D02*
X153543Y1423385D01*
G01X156693Y1429567D02*
X153543Y1428385D01*
G01X156693Y1434567D02*
X153543Y1433385D01*
G01X156693Y1439567D02*
X153543Y1438385D01*
G01X156693Y1444567D02*
X153543Y1443385D01*
G01X156693Y1449567D02*
X153543Y1448385D01*
G01X157915Y1453779D02*
X157748Y1453713D01*
G01X157245Y1453746D02*
X157078Y1453681D01*
G01X156809Y1454796D02*
X156977Y1454862D01*
G01X149526Y1420636D02*
X149660Y1420702D01*
G01X156809Y1453353D02*
X156944Y1453418D01*
G01X157513Y1454763D02*
X157647Y1454829D01*
G01X149694Y1420505D02*
X149593Y1420439D01*
G01X156977Y1453221D02*
X156876Y1453156D01*
G01X157848Y1453943D02*
X157748Y1453878D01*
G01X157580Y1454599D02*
X157681Y1454665D01*
G01X157211Y1453943D02*
X157078Y1453845D01*
G01X156843Y1454599D02*
X156977Y1454698D01*
G01X150632Y1420964D02*
X150866Y1421161D01*
G01X150598D02*
X150364Y1420964D01*
G01X150679Y1419665D02*
X150632Y1419619D01*
G01X150766Y1419750D02*
X150679Y1419665D01*
G01X149392Y1420505D02*
X149526Y1420636D01*
G01X158049Y1452467D02*
X157915Y1452335D01*
G01X158016Y1453878D02*
X157915Y1453779D01*
G01X156676Y1453221D02*
X156809Y1453353D01*
G01X157413Y1454665D02*
X157513Y1454763D01*
G01X156709Y1454698D02*
X156809Y1454796D01*
G01X157949Y1454074D02*
X157848Y1453943D01*
G01X157346Y1453878D02*
X157245Y1453746D01*
G01X157480Y1454468D02*
X157580Y1454599D01*
G01X150565Y1419816D02*
X150632Y1419914D01*
G01X149593Y1420439D02*
X149526Y1420341D01*
G01X157848Y1452532D02*
X157915Y1452631D01*
G01X156876Y1453156D02*
X156809Y1453058D01*
G01X158116Y1454042D02*
X158016Y1453878D01*
G01X156608Y1454534D02*
X156709Y1454698D01*
G01X149325Y1420374D02*
X149392Y1420505D01*
G01X158116Y1452598D02*
X158049Y1452467D01*
G01X157379Y1453943D02*
X157346Y1453878D01*
G01X157279Y1454074D02*
X157211Y1453943D01*
G01X156608Y1453090D02*
X156676Y1453221D01*
G01X157379Y1454599D02*
X157413Y1454665D01*
G01X156776Y1454468D02*
X156843Y1454599D01*
G01X102164Y1506358D02*
Y1479783D01*
G01X106101Y1498780D02*
Y1487362D01*
G01X107873Y1483720D02*
Y1487362D01*
G01X108857Y1483720D02*
Y1487362D01*
G01X122243Y1479783D02*
X102164D01*
G01X108857Y1483720D02*
X107873D01*
G01X108857Y1485607D02*
X107873D01*
G01X108857Y1485689D02*
X107873D01*
G01X108857Y1487084D02*
X107873D01*
G01X108857Y1487165D02*
X107873D01*
G01X106101Y1487362D02*
X118306D01*
G01X107873Y1498780D02*
Y1502421D01*
G01X108857Y1498780D02*
Y1502421D01*
G01X118306Y1498780D02*
X106101D01*
G01X108857Y1498976D02*
X107873D01*
G01X108857Y1499058D02*
X107873D01*
G01X108857Y1500453D02*
X107873D01*
G01X108857Y1500534D02*
X107873D01*
G01X108857Y1502421D02*
X107873D01*
G01X122243Y1506358D02*
X102164D01*
G01X110432Y1483720D02*
Y1487362D01*
G01X111416Y1483720D02*
Y1487362D01*
G01X112991Y1483720D02*
Y1487362D01*
G01X113975Y1483720D02*
Y1487362D01*
G01X115550Y1483720D02*
Y1487362D01*
G01X116534Y1483720D02*
Y1487362D01*
G01X118306D02*
Y1498780D01*
G01X122243Y1479783D02*
Y1506358D01*
G01X116534Y1483720D02*
X115550D01*
G01X113975D02*
X112991D01*
G01X111416D02*
X110432D01*
G01X116534Y1485607D02*
X115550D01*
G01X113975D02*
X112991D01*
G01X111416D02*
X110432D01*
G01X116534Y1485689D02*
X115550D01*
G01X111416D02*
X110432D01*
G01X113975D02*
X112991D01*
G01X116534Y1487084D02*
X115550D01*
G01X113975D02*
X112991D01*
G01X111416D02*
X110432D01*
G01X116534Y1487165D02*
X115550D01*
G01X111416D02*
X110432D01*
G01X113975D02*
X112991D01*
G01X110432Y1498780D02*
Y1502421D01*
G01X111416Y1498780D02*
Y1502421D01*
G01X112991Y1498780D02*
Y1502421D01*
G01X113975Y1498780D02*
Y1502421D01*
G01X115550Y1498780D02*
Y1502421D01*
G01X116338Y1500059D02*
Y1500108D01*
G01X116534Y1498780D02*
Y1502421D01*
G01X116731Y1500108D02*
Y1500059D01*
G01X116664Y1500108D02*
X116606Y1500157D01*
G01X116673D02*
X116731Y1500108D01*
G01X116534Y1498976D02*
X115550D01*
G01X111416D02*
X110432D01*
G01X113975D02*
X112991D01*
G01X116534Y1499058D02*
X115550D01*
G01X111416D02*
X110432D01*
G01X113975D02*
X112991D01*
G01X116534Y1500059D02*
X116338D01*
G01X116731D02*
X116534D01*
G01X116338Y1500108D02*
X116534D01*
G01D02*
X116664D01*
G01X116606Y1500157D02*
X116673D01*
G01X116534Y1500453D02*
X115550D01*
G01X111416D02*
X110432D01*
G01X113975D02*
X112991D01*
G01X116534Y1500534D02*
X115550D01*
G01X111416D02*
X110432D01*
G01X113975D02*
X112991D01*
G01X116534Y1502421D02*
X115550D01*
G01X113975D02*
X112991D01*
G01X111416D02*
X110432D01*
G01X116731Y1497008D02*
G03I-590J0D01*
G01X156054Y1559330D02*
G03Y1556181I2017J-1574D01*
G01X160088D02*
G03Y1559330I-2017J1575D01*
G01X160441Y1555393D02*
G03Y1560118I-2370J2362D01*
G01X155701D02*
G03Y1555393I2370J-2363D01*
G01X161575Y1557756D02*
G03I-3504J0D01*
G01X160748Y1554606D02*
G03Y1560905I-2677J3149D01*
G01X155394D02*
G03Y1554606I2677J-3149D01*
G01X156054Y1556181D02*
X160088D01*
G01X155701Y1555393D02*
X160441D01*
G01X160748Y1554606D02*
X155394D01*
G01X195669Y1554193D02*
X145669D01*
G01X165354Y1551043D02*
X145669D01*
G01Y1549271D02*
X165354D01*
G01D02*
X166634D01*
G01X196457D02*
X168012D01*
G01X161417Y1546338D02*
X156693D01*
G01X197638D02*
X165354D01*
G01Y1546240D02*
X195877D01*
G01X148110D02*
X165354D01*
G01Y1544665D02*
X195877D01*
G01X165354D02*
X148110D01*
G01X165354Y1544567D02*
X197638D01*
G01X156693D02*
X161417D01*
G01X165354Y1541338D02*
X197638D01*
G01X161417D02*
X156693D01*
G01X165354Y1541240D02*
X195877D01*
G01X148110D02*
X165354D01*
G01Y1539665D02*
X195877D01*
G01X165354D02*
X148110D01*
G01X165354Y1539567D02*
X197638D01*
G01X156693D02*
X161417D01*
G01X158661Y1529567D02*
X153543Y1528385D01*
G01X158661Y1489567D02*
X153543Y1488385D01*
G01X165354Y1536338D02*
X197638D01*
G01X161417D02*
X156693D01*
G01X165354Y1536240D02*
X195877D01*
G01X148110D02*
X165354D01*
G01Y1534665D02*
X195877D01*
G01X165354D02*
X148110D01*
G01X165354Y1534567D02*
X197638D01*
G01X156693D02*
X161417D01*
G01X166535Y1532815D02*
X165354D01*
G01X163386Y1531338D02*
X158661D01*
G01X197638D02*
X166535D01*
G01Y1531240D02*
X195877D01*
G01X146654D02*
X166535D01*
G01Y1529665D02*
X195877D01*
G01X146654D02*
X166535D01*
G01Y1529567D02*
X197638D01*
G01X158661D02*
X163386D01*
G01X158465Y1529330D02*
X165354D01*
G01Y1528090D02*
X166535D01*
G01X165354Y1526574D02*
X158465D01*
G01X165354Y1526338D02*
X197638D01*
G01X161417D02*
X156693D01*
G01X165354Y1526240D02*
X195877D01*
G01X148110D02*
X165354D01*
G01Y1524665D02*
X195877D01*
G01X165354D02*
X148110D01*
G01X165354Y1524567D02*
X197638D01*
G01X156693D02*
X161417D01*
G01X165354Y1521338D02*
X197638D01*
G01X161417D02*
X156693D01*
G01X165354Y1521240D02*
X195877D01*
G01X148110D02*
X165354D01*
G01Y1519665D02*
X195877D01*
G01X165354D02*
X148110D01*
G01X165354Y1519567D02*
X197638D01*
G01X156693D02*
X161417D01*
G01X165354Y1516338D02*
X197638D01*
G01X161417D02*
X156693D01*
G01X165354Y1516240D02*
X195877D01*
G01X148110D02*
X165354D01*
G01Y1514665D02*
X195877D01*
G01X165354D02*
X148110D01*
G01X165354Y1514567D02*
X197638D01*
G01X156693D02*
X161417D01*
G01X165354Y1511338D02*
X197638D01*
G01X161417D02*
X156693D01*
G01X165354Y1511240D02*
X195877D01*
G01X148110D02*
X165354D01*
G01Y1509665D02*
X195877D01*
G01X165354D02*
X148110D01*
G01X165354Y1509567D02*
X197638D01*
G01X156693D02*
X161417D01*
G01X165354Y1506338D02*
X197638D01*
G01X161417D02*
X156693D01*
G01X165354Y1506240D02*
X195877D01*
G01X148110D02*
X165354D01*
G01Y1504665D02*
X195877D01*
G01X165354D02*
X148110D01*
G01X165354Y1504567D02*
X197638D01*
G01X156693D02*
X161417D01*
G01X158465Y1504330D02*
X165354D01*
G01Y1501574D02*
X158465D01*
G01X165354Y1501338D02*
X197638D01*
G01X161417D02*
X156693D01*
G01X165354Y1501240D02*
X195877D01*
G01X148110D02*
X165354D01*
G01Y1499665D02*
X195877D01*
G01X165354D02*
X148110D01*
G01X165354Y1499567D02*
X197638D01*
G01X156693D02*
X161417D01*
G01X165354Y1496338D02*
X197638D01*
G01X161417D02*
X156693D01*
G01X165354Y1496240D02*
X195877D01*
G01X148110D02*
X165354D01*
G01Y1494665D02*
X195877D01*
G01X165354D02*
X148110D01*
G01X165354Y1494567D02*
X197638D01*
G01X156693D02*
X161417D01*
G01X166535Y1492815D02*
X165354D01*
G01X163386Y1491338D02*
X158661D01*
G01X197638D02*
X166535D01*
G01Y1491240D02*
X195877D01*
G01X146654D02*
X166535D01*
G01Y1489665D02*
X195877D01*
G01X146654D02*
X166535D01*
G01Y1489567D02*
X197638D01*
G01X158661D02*
X163386D01*
G01X165354Y1488090D02*
X166535D01*
G01X165354Y1486338D02*
X197638D01*
G01X161417D02*
X156693D01*
G01X165354Y1486240D02*
X195877D01*
G01X148110D02*
X165354D01*
G01Y1484665D02*
X195877D01*
G01X165354D02*
X148110D01*
G01X165354Y1484567D02*
X197638D01*
G01X156693D02*
X161417D01*
G01X165354Y1481338D02*
X197638D01*
G01X161417D02*
X156693D01*
G01X165354Y1481240D02*
X195877D01*
G01X148110D02*
X165354D01*
G01Y1479665D02*
X148110D01*
G01X195877D02*
X165354D01*
G01Y1479567D02*
X197638D01*
G01X156693D02*
X161417D01*
G01X158465Y1479330D02*
X165354D01*
G01Y1476574D02*
X158465D01*
G01X150906Y1476397D02*
X149331D01*
G01X165354Y1476338D02*
X194685D01*
G01X161417D02*
X156693D01*
G01X165354Y1476240D02*
X195756D01*
G01X146654D02*
X165354D01*
G01X149331Y1476200D02*
X150638D01*
G01X150403Y1476004D02*
X150671D01*
G01X150537Y1475741D02*
X150403D01*
G01X150437Y1475544D02*
X150537D01*
G01X165354Y1475157D02*
X197638D01*
G01X150738Y1474724D02*
X150235D01*
G01X150035D02*
X149331D01*
G01X165354Y1474665D02*
X195756D01*
G01X146654D02*
X165354D01*
G01Y1474567D02*
X194685D01*
G01X157284D02*
X161417D01*
G01X149331Y1474527D02*
X150906D01*
G01X160630Y1473976D02*
X157284D01*
G01X153543Y1532519D02*
X158661Y1531338D01*
G01X153543Y1492519D02*
X158661Y1491338D01*
G01X153543Y1547519D02*
X156693Y1546338D01*
G01X153543Y1542519D02*
X156693Y1541338D01*
G01X153543Y1537519D02*
X156693Y1536338D01*
G01X153543Y1527519D02*
X156693Y1526338D01*
G01X153543Y1522519D02*
X156693Y1521338D01*
G01X153543Y1517519D02*
X156693Y1516338D01*
G01X153543Y1512519D02*
X156693Y1511338D01*
G01X153543Y1507519D02*
X156693Y1506338D01*
G01X153543Y1502519D02*
X156693Y1501338D01*
G01X153543Y1497519D02*
X156693Y1496338D01*
G01X153543Y1487519D02*
X156693Y1486338D01*
G01X153543Y1482519D02*
X156693Y1481338D01*
G01X153543Y1477519D02*
X156693Y1476338D01*
G01X150638Y1475708D02*
X150537Y1475741D01*
G01Y1475544D02*
X150638Y1475511D01*
G01X150772Y1475610D02*
X150638Y1475708D01*
G01Y1475511D02*
X150705Y1475446D01*
G01X150872Y1475479D02*
X150772Y1475610D01*
G01X150705Y1475446D02*
X150738Y1475347D01*
G01X150906Y1475315D02*
X150872Y1475479D01*
G01X166535Y1528090D02*
Y1532815D01*
G01Y1488090D02*
Y1492815D01*
G01X166142Y1554193D02*
Y1562539D01*
G01X165354Y1531240D02*
Y1551043D01*
G01Y1491240D02*
Y1529665D01*
G01Y1491240D02*
Y1489665D01*
G01Y1531240D02*
Y1529665D01*
G01X163386Y1531240D02*
Y1531338D01*
G01Y1529567D02*
Y1529665D01*
G01D02*
Y1531240D01*
G01Y1491240D02*
Y1491338D01*
G01Y1489665D02*
Y1491240D01*
G01Y1489567D02*
Y1489665D01*
G01X161417Y1546240D02*
Y1546338D01*
G01Y1544665D02*
Y1546240D01*
G01Y1544567D02*
Y1544665D01*
G01Y1541240D02*
Y1541338D01*
G01Y1539567D02*
Y1539665D01*
G01D02*
Y1541240D01*
G01Y1536240D02*
Y1536338D01*
G01Y1534567D02*
Y1534665D01*
G01D02*
Y1536240D01*
G01Y1526240D02*
Y1526338D01*
G01Y1524567D02*
Y1524665D01*
G01D02*
Y1526240D01*
G01Y1521240D02*
Y1521338D01*
G01Y1519567D02*
Y1519665D01*
G01D02*
Y1521240D01*
G01Y1516240D02*
Y1516338D01*
G01Y1514567D02*
Y1514665D01*
G01D02*
Y1516240D01*
G01Y1511240D02*
Y1511338D01*
G01Y1509567D02*
Y1509665D01*
G01D02*
Y1511240D01*
G01Y1506240D02*
Y1506338D01*
G01Y1504567D02*
Y1504665D01*
G01D02*
Y1506240D01*
G01Y1501240D02*
Y1501338D01*
G01Y1499567D02*
Y1499665D01*
G01D02*
Y1501240D01*
G01Y1496240D02*
Y1496338D01*
G01Y1494567D02*
Y1494665D01*
G01D02*
Y1496240D01*
G01Y1486240D02*
Y1486338D01*
G01Y1484665D02*
Y1486240D01*
G01Y1484567D02*
Y1484665D01*
G01Y1481240D02*
Y1481338D01*
G01Y1479665D02*
Y1481240D01*
G01Y1479567D02*
Y1479665D01*
G01Y1476240D02*
Y1476338D01*
G01Y1474665D02*
Y1476240D01*
G01Y1474567D02*
Y1474665D01*
G01X158465Y1479330D02*
Y1476574D01*
G01Y1504330D02*
Y1501574D01*
G01Y1529330D02*
Y1526574D01*
G01X157284Y1473976D02*
Y1474567D01*
G01X155787Y1544665D02*
Y1546240D01*
G01Y1539665D02*
Y1541240D01*
G01Y1534665D02*
Y1536240D01*
G01Y1529665D02*
Y1531240D01*
G01Y1524665D02*
Y1526240D01*
G01Y1519665D02*
Y1521240D01*
G01Y1514665D02*
Y1516240D01*
G01Y1509665D02*
Y1511240D01*
G01Y1504665D02*
Y1506240D01*
G01Y1499665D02*
Y1501240D01*
G01Y1494665D02*
Y1496240D01*
G01Y1489665D02*
Y1491240D01*
G01Y1484665D02*
Y1486240D01*
G01Y1479665D02*
Y1481240D01*
G01Y1474665D02*
Y1476240D01*
G01X154213Y1544665D02*
Y1546240D01*
G01Y1539665D02*
Y1541240D01*
G01Y1534665D02*
Y1536240D01*
G01Y1529665D02*
Y1531240D01*
G01Y1524665D02*
Y1526240D01*
G01Y1519665D02*
Y1521240D01*
G01Y1514665D02*
Y1516240D01*
G01Y1509665D02*
Y1511240D01*
G01Y1504665D02*
Y1506240D01*
G01Y1499665D02*
Y1501240D01*
G01Y1494665D02*
Y1496240D01*
G01Y1489665D02*
Y1491240D01*
G01Y1484665D02*
Y1486240D01*
G01Y1479665D02*
Y1481240D01*
G01Y1474665D02*
Y1476240D01*
G01X153543Y1547519D02*
Y1549271D01*
G01Y1542519D02*
Y1543385D01*
G01Y1537519D02*
Y1538385D01*
G01Y1532519D02*
Y1533385D01*
G01Y1527519D02*
Y1528385D01*
G01Y1522519D02*
Y1523385D01*
G01Y1517519D02*
Y1518385D01*
G01Y1512519D02*
Y1513385D01*
G01Y1507519D02*
Y1508385D01*
G01Y1502519D02*
Y1503385D01*
G01Y1497519D02*
Y1498385D01*
G01Y1492519D02*
Y1493385D01*
G01Y1487519D02*
Y1488385D01*
G01Y1482519D02*
Y1483385D01*
G01Y1477519D02*
Y1478385D01*
G01X153425Y1476240D02*
Y1474665D01*
G01Y1481240D02*
Y1479665D01*
G01Y1486240D02*
Y1484665D01*
G01Y1491240D02*
Y1489665D01*
G01Y1496240D02*
Y1494665D01*
G01Y1501240D02*
Y1499665D01*
G01Y1506240D02*
Y1504665D01*
G01Y1511240D02*
Y1509665D01*
G01Y1516240D02*
Y1514665D01*
G01Y1521240D02*
Y1519665D01*
G01Y1526240D02*
Y1524665D01*
G01Y1531240D02*
Y1529665D01*
G01Y1536240D02*
Y1534665D01*
G01Y1541240D02*
Y1539665D01*
G01Y1546240D02*
Y1544665D01*
G01X153032Y1476240D02*
Y1474665D01*
G01Y1481240D02*
Y1479665D01*
G01Y1486240D02*
Y1484665D01*
G01Y1491240D02*
Y1489665D01*
G01Y1496240D02*
Y1494665D01*
G01Y1501240D02*
Y1499665D01*
G01Y1506240D02*
Y1504665D01*
G01Y1511240D02*
Y1509665D01*
G01Y1516240D02*
Y1514665D01*
G01Y1521240D02*
Y1519665D01*
G01Y1526240D02*
Y1524665D01*
G01Y1531240D02*
Y1529665D01*
G01Y1536240D02*
Y1534665D01*
G01Y1541240D02*
Y1539665D01*
G01Y1546240D02*
Y1544665D01*
G01X150906Y1476240D02*
Y1476397D01*
G01Y1476200D02*
Y1476240D01*
G01Y1474527D02*
Y1474665D01*
G01D02*
Y1475315D01*
G01X150738Y1475347D02*
Y1474724D01*
G01X150235D02*
Y1475347D01*
G01X150035Y1475315D02*
Y1474724D01*
G01X149331Y1474665D02*
Y1474527D01*
G01Y1474724D02*
Y1474665D01*
G01Y1476397D02*
Y1476240D01*
G01D02*
Y1476200D01*
G01X148110Y1544665D02*
Y1546240D01*
G01Y1539665D02*
Y1541240D01*
G01Y1534665D02*
Y1536240D01*
G01Y1524665D02*
Y1526240D01*
G01Y1519665D02*
Y1521240D01*
G01Y1514665D02*
Y1516240D01*
G01Y1509665D02*
Y1511240D01*
G01Y1504665D02*
Y1506240D01*
G01Y1499665D02*
Y1501240D01*
G01Y1494665D02*
Y1496240D01*
G01Y1484665D02*
Y1486240D01*
G01Y1479665D02*
Y1481240D01*
G01X146654Y1529665D02*
Y1531240D01*
G01Y1489665D02*
Y1491240D01*
G01Y1474665D02*
Y1476240D01*
G01X145669Y1549271D02*
Y1562539D01*
G01X150235Y1475347D02*
X150269Y1475446D01*
G01X150068Y1475479D02*
X150035Y1475315D01*
G01X150336Y1475511D02*
X150437Y1475544D01*
G01X150403Y1475741D02*
X150302Y1475708D01*
G01X156693Y1479567D02*
X153543Y1478385D01*
G01X156693Y1484567D02*
X153543Y1483385D01*
G01X156693Y1494567D02*
X153543Y1493385D01*
G01X156693Y1499567D02*
X153543Y1498385D01*
G01X150169Y1475610D02*
X150068Y1475479D01*
G01X156693Y1504567D02*
X153543Y1503385D01*
G01X156693Y1509567D02*
X153543Y1508385D01*
G01X156693Y1514567D02*
X153543Y1513385D01*
G01X156693Y1519567D02*
X153543Y1518385D01*
G01X156693Y1524567D02*
X153543Y1523385D01*
G01X156693Y1534567D02*
X153543Y1533385D01*
G01X156693Y1539567D02*
X153543Y1538385D01*
G01X156693Y1544567D02*
X153543Y1543385D01*
G01X150302Y1475708D02*
X150169Y1475610D01*
G01X150671Y1476004D02*
X150906Y1476200D01*
G01X150638D02*
X150403Y1476004D01*
G01X150269Y1475446D02*
X150336Y1475511D01*
G01X171063Y1569567D02*
G03I-3740J0D01*
G01X153543Y1579429D02*
X181102D01*
G01X177165Y1575492D02*
X157480D01*
G01X177165Y1573523D02*
X157480D01*
G01X177165Y1571535D02*
X157480D01*
G01Y1570551D02*
X177165D01*
G01X176969Y1570354D02*
X157677D01*
G01X176969Y1568779D02*
X157677D01*
G01X177165Y1568582D02*
X157480D01*
G01Y1567598D02*
X177165D01*
G01X153543Y1566476D02*
X141732D01*
G01X177165Y1564508D02*
X157480D01*
G01X199606Y1562539D02*
X145669D01*
G01X166142Y1561358D02*
X199606D01*
G01X155394Y1560905D02*
X160748D01*
G01X160441Y1560118D02*
X155701D01*
G01X156054Y1559330D02*
X160088D01*
G01X166142Y1557145D02*
X145669D01*
G01X177165D02*
X166142D01*
G01X177165Y1562539D02*
Y1575492D01*
G01X176969Y1568779D02*
Y1570354D01*
G01X171614D02*
Y1568779D01*
G01X170276Y1570354D02*
Y1570551D01*
G01Y1568582D02*
Y1568779D01*
G01Y1570354D02*
Y1568779D01*
G01X170079Y1570354D02*
Y1568779D01*
G01X168504Y1570354D02*
Y1568779D01*
G01X166142Y1570354D02*
Y1568779D01*
G01X164567D02*
Y1570354D01*
G01X164370D02*
Y1570551D01*
G01Y1568779D02*
Y1570354D01*
G01Y1568779D02*
Y1568582D01*
G01X163032Y1568779D02*
Y1570354D01*
G01X157677D02*
Y1568779D01*
G01X157480Y1562539D02*
Y1575492D01*
G01X153543Y1566476D02*
Y1579429D01*
G01X110235Y1830039D02*
Y1760945D01*
G01X137794D02*
X110235D01*
G01X137794Y1980315D02*
Y1760945D01*
G01X162597Y1786358D02*
Y1784390D01*
G01Y1781831D02*
Y1783799D01*
G01X164172Y1786654D02*
Y1786063D01*
G01Y1784882D02*
Y1783307D01*
G01Y1782126D02*
Y1781535D01*
G01X165156Y1786654D02*
Y1781535D01*
G01X165353D02*
Y1786654D01*
G01X165747Y1783799D02*
Y1781831D01*
G01Y1784390D02*
Y1786358D01*
G01X168897Y1783799D02*
Y1781831D01*
G01Y1784390D02*
Y1786358D01*
G01X169290Y1781535D02*
Y1786654D01*
G01X169487D02*
Y1781535D01*
G01X164172D02*
X170471D01*
G01X165747Y1781831D02*
X164172D01*
G01D02*
X162597D01*
G01X168897D02*
X170471D01*
G01Y1783799D02*
X168897D01*
G01X164172D02*
X165747D01*
G01X162597D02*
X164172D01*
G01X170471Y1784390D02*
X168897D01*
G01X164172D02*
X165747D01*
G01X162597D02*
X164172D01*
G01X165747Y1786358D02*
X164172D01*
G01D02*
X162597D01*
G01X168897D02*
X170471D01*
G01X164172Y1786654D02*
X170471D01*
G01X164172Y1782126D02*
G03Y1783307I0J591D01*
G01Y1784882D02*
G03Y1786063I0J590D01*
G01X170461Y1785261D02*
X170554Y1785373D01*
G01Y1785245D02*
X170461Y1785134D01*
G01X170367D02*
Y1785882D01*
G01X170461D02*
Y1785261D01*
G01X170471Y1781535D02*
Y1782126D01*
G01Y1783307D02*
Y1784882D01*
G01Y1786063D02*
Y1786654D01*
G01X170554Y1785373D02*
Y1785245D01*
G01X172046Y1786358D02*
Y1784390D01*
G01Y1781831D02*
Y1783799D01*
G01X170471Y1781831D02*
X172046D01*
G01Y1783799D02*
X170471D01*
G01X172046Y1784390D02*
X170471D01*
G01X170461Y1785134D02*
X170367D01*
G01Y1785882D02*
X170461D01*
G01X170471Y1786358D02*
X172046D01*
G01X170471Y1783307D02*
G03Y1782126I1J-590D01*
G01Y1786063D02*
G03Y1784882I1J-591D01*
G01X171063Y1801850D02*
G03I-3740J0D01*
G01X141732Y1804941D02*
X153543D01*
G01X177165Y1803819D02*
X157480D01*
G01Y1802834D02*
X177165D01*
G01X176969Y1802637D02*
X157677D01*
G01X176969Y1801063D02*
X157677D01*
G01X177165Y1800866D02*
X157480D01*
G01Y1799882D02*
X177165D01*
G01X157480Y1797893D02*
X177165D01*
G01X157480Y1795925D02*
X177165D01*
G01X181102Y1791988D02*
X153543D01*
G01X177165Y1795925D02*
Y1808878D01*
G01X176969Y1801063D02*
Y1802637D01*
G01X171614D02*
Y1801063D01*
G01X170276Y1802637D02*
Y1802834D01*
G01Y1800866D02*
Y1801063D01*
G01Y1802637D02*
Y1801063D01*
G01X170079Y1802637D02*
Y1801063D01*
G01X168504Y1802637D02*
Y1801063D01*
G01X166142Y1802637D02*
Y1801063D01*
G01X164567D02*
Y1802637D01*
G01X164370D02*
Y1802834D01*
G01Y1801063D02*
Y1802637D01*
G01Y1801063D02*
Y1800866D01*
G01X163032Y1801063D02*
Y1802637D01*
G01X157677D02*
Y1801063D01*
G01X157480Y1795925D02*
Y1808878D01*
G01X153543Y1791988D02*
Y1804941D01*
G01X141732Y1971988D02*
Y1804941D01*
G01X99015Y1884144D02*
Y1882913D01*
G01X157996Y1817795D02*
X158071D01*
G01X158146Y1809528D02*
X158071Y1809527D01*
G01X160630Y1813661D02*
G03I-2559J0D01*
G01X161417D02*
G03I-3346J0D01*
G01X161575D02*
G03I-3504J0D01*
G01X158146Y1809528D02*
G03X158071Y1817795I-75J4133D01*
G01X157996Y1817794D02*
G03X158071Y1809527I74J-4133D01*
G01X165354Y1886850D02*
X197638D01*
G01X161417D02*
X156693D01*
G01X165354Y1886752D02*
X195877D01*
G01X148110D02*
X165354D01*
G01Y1885177D02*
X148110D01*
G01X195877D02*
X165354D01*
G01Y1885078D02*
X197638D01*
G01X156693D02*
X161417D01*
G01X158465Y1884842D02*
X165354D01*
G01Y1882086D02*
X158465D01*
G01X150906Y1881909D02*
X149331D01*
G01X165354Y1881850D02*
X194685D01*
G01X161417D02*
X156693D01*
G01X165354Y1881752D02*
X195756D01*
G01X146654D02*
X165354D01*
G01X149331Y1881712D02*
X150638D01*
G01X150403Y1881515D02*
X150671D01*
G01X150537Y1881253D02*
X150403D01*
G01X150437Y1881056D02*
X150537D01*
G01X165354Y1880669D02*
X197638D01*
G01X150738Y1880236D02*
X150235D01*
G01X150035D02*
X149331D01*
G01X165354Y1880177D02*
X195756D01*
G01X146654D02*
X165354D01*
G01Y1880078D02*
X194685D01*
G01X157284D02*
X161417D01*
G01X149331Y1880039D02*
X150906D01*
G01X160630Y1879488D02*
X157284D01*
G01X168110Y1878602D02*
X197441D01*
G01X162992D02*
X165354D01*
G01X168110Y1878504D02*
X194215D01*
G01X156102D02*
X168110D01*
G01X177165Y1878228D02*
X195669D01*
G01X156102Y1877322D02*
X168110D01*
G01X194215D02*
X168110D01*
G01Y1877224D02*
X197441D01*
G01X162992D02*
X165354D01*
G01X168110Y1875452D02*
X197441D01*
G01X162992D02*
X165354D01*
G01X168110Y1875354D02*
X194215D01*
G01X156102D02*
X168110D01*
G01X156102Y1874173D02*
X168110D01*
G01X194215D02*
X168110D01*
G01Y1874074D02*
X197441D01*
G01X162992D02*
X165354D01*
G01X168110Y1872303D02*
X197441D01*
G01X162992D02*
X165354D01*
G01X168110Y1872204D02*
X194215D01*
G01X156102D02*
X168110D01*
G01X156102Y1871023D02*
X168110D01*
G01X194215D02*
X168110D01*
G01Y1870925D02*
X197441D01*
G01X162992D02*
X165354D01*
G01X168110Y1869153D02*
X197441D01*
G01X162992D02*
X165354D01*
G01X168110Y1869055D02*
X194215D01*
G01X156102D02*
X168110D01*
G01X156102Y1867874D02*
X168110D01*
G01X194215D02*
X168110D01*
G01Y1867775D02*
X197441D01*
G01X162992D02*
X165354D01*
G01X168110Y1866004D02*
X197441D01*
G01X162992D02*
X165354D01*
G01X168110Y1865905D02*
X194215D01*
G01X156102D02*
X168110D01*
G01X156102Y1864724D02*
X168110D01*
G01X194215D02*
X168110D01*
G01Y1864626D02*
X197441D01*
G01X162992D02*
X165354D01*
G01X168110Y1862854D02*
X197441D01*
G01X162992D02*
X165354D01*
G01X168110Y1862756D02*
X194215D01*
G01X156102D02*
X168110D01*
G01X156102Y1861574D02*
X168110D01*
G01X194215D02*
X168110D01*
G01Y1861476D02*
X197441D01*
G01X162992D02*
X165354D01*
G01X156977Y1860374D02*
X157078D01*
G01X157647Y1860341D02*
X157748D01*
G01X156977Y1860209D02*
X157078D01*
G01X157681Y1860177D02*
X157748D01*
G01X162992Y1859704D02*
X165354D01*
G01X197441D02*
X168110D01*
G01Y1859606D02*
X194215D01*
G01X156102D02*
X168110D01*
G01X157748Y1859389D02*
X157681D01*
G01X157078Y1859357D02*
X156977D01*
G01X157748Y1859225D02*
X157647D01*
G01X157078Y1859193D02*
X156977D01*
G01X156944Y1858930D02*
X157111D01*
G01X157078Y1858733D02*
X156977D01*
G01X195669Y1858700D02*
X177165D01*
G01X156102Y1858425D02*
X168110D01*
G01X194215D02*
X168110D01*
G01X162992Y1858326D02*
X165354D01*
G01X197441D02*
X168110D01*
G01X157681Y1858011D02*
X157748D01*
G01X157781Y1857815D02*
X157647D01*
G01X157284Y1857441D02*
X160630D01*
G01X161417Y1856850D02*
X157284D01*
G01X194685D02*
X165354D01*
G01Y1856752D02*
X195756D01*
G01X148110D02*
X165354D01*
G01Y1856259D02*
X197638D01*
G01X165354Y1855177D02*
X148110D01*
G01X195756D02*
X165354D01*
G01Y1855078D02*
X194685D01*
G01X156693D02*
X161417D01*
G01Y1851850D02*
X156693D01*
G01X197638D02*
X165354D01*
G01Y1851752D02*
X195877D01*
G01X148110D02*
X165354D01*
G01Y1850177D02*
X195877D01*
G01X165354D02*
X148110D01*
G01X165354Y1850078D02*
X197638D01*
G01X156693D02*
X161417D01*
G01X158465Y1849842D02*
X165354D01*
G01Y1847086D02*
X158465D01*
G01X165354Y1846850D02*
X197638D01*
G01X161417D02*
X156693D01*
G01X165354Y1846752D02*
X195877D01*
G01X148110D02*
X165354D01*
G01Y1845177D02*
X195877D01*
G01X165354D02*
X148110D01*
G01X165354Y1845078D02*
X197638D01*
G01X156693D02*
X161417D01*
G01X157915Y1857847D02*
X157781Y1857815D01*
G01X150632Y1825131D02*
X150498Y1825098D01*
G01X165354Y1841850D02*
X197638D01*
G01X161417D02*
X156693D01*
G01X165354Y1841752D02*
X195877D01*
G01X148110D02*
X165354D01*
G01Y1840177D02*
X195877D01*
G01X165354D02*
X148110D01*
G01X165354Y1840078D02*
X197638D01*
G01X156693D02*
X161417D01*
G01X165354Y1836850D02*
X197638D01*
G01X161417D02*
X156693D01*
G01X165354Y1836752D02*
X195877D01*
G01X148110D02*
X165354D01*
G01Y1835177D02*
X195877D01*
G01X165354D02*
X148110D01*
G01X165354Y1835078D02*
X197638D01*
G01X156693D02*
X161417D01*
G01X165354Y1831850D02*
X197638D01*
G01X161417D02*
X156693D01*
G01X165354Y1831752D02*
X195877D01*
G01X148110D02*
X165354D01*
G01Y1830177D02*
X195877D01*
G01X165354D02*
X148110D01*
G01X165354Y1830078D02*
X197638D01*
G01X156693D02*
X161417D01*
G01X150866Y1826870D02*
X149291D01*
G01X165354Y1826850D02*
X197638D01*
G01X161417D02*
X156693D01*
G01X165354Y1826752D02*
X195877D01*
G01X148110D02*
X165354D01*
G01X149291Y1826673D02*
X150598D01*
G01X150364Y1826476D02*
X150632D01*
G01X149660Y1826213D02*
X149828D01*
G01X149794Y1826017D02*
X149694D01*
G01X150397Y1825295D02*
X150464D01*
G01X165354Y1825177D02*
X195877D01*
G01X165354D02*
X148110D01*
G01X150498Y1825098D02*
X150364D01*
G01X165354Y1825078D02*
X197638D01*
G01X156693D02*
X161417D01*
G01X168012Y1822145D02*
X196457D01*
G01X165354D02*
X166634D01*
G01X165354D02*
X145669D01*
G01Y1820374D02*
X165354D01*
G01X145669Y1817224D02*
X195669D01*
G01X166142Y1814271D02*
X177165D01*
G01X145669D02*
X166142D01*
G01X199606Y1810059D02*
X166142D01*
G01X199606Y1808878D02*
X145669D01*
G01X157480Y1806909D02*
X177165D01*
G01X153543Y1888031D02*
X156693Y1886850D01*
G01X153543Y1883031D02*
X156693Y1881850D01*
G01X150638Y1881220D02*
X150537Y1881253D01*
G01Y1881056D02*
X150638Y1881023D01*
G01X157781Y1858832D02*
X157882Y1858799D01*
G01X157580Y1858044D02*
X157681Y1858011D01*
G01X156910Y1857946D02*
X157011Y1857913D01*
G01X160630Y1879291D02*
X162992Y1878602D01*
G01X160630Y1876141D02*
X162992Y1875452D01*
G01X160630Y1872992D02*
X162992Y1872303D01*
G01X160630Y1869842D02*
X162992Y1869153D01*
G01X160630Y1866693D02*
X162992Y1866004D01*
G01X160630Y1863543D02*
X162992Y1862854D01*
G01X160630Y1860393D02*
X162992Y1859704D01*
G01X157647Y1857815D02*
X157513Y1857847D01*
G01X157011Y1857716D02*
X156876Y1857749D01*
G01X150364Y1825098D02*
X150230Y1825131D01*
G01X149727Y1825000D02*
X149593Y1825032D01*
G01X157748Y1860341D02*
X157915Y1860275D01*
G01X157078Y1860374D02*
X157245Y1860308D01*
G01X156977Y1859193D02*
X156809Y1859258D01*
G01X153543Y1853031D02*
X156693Y1851850D01*
G01X153543Y1848031D02*
X156693Y1846850D01*
G01X153543Y1843031D02*
X156693Y1841850D01*
G01X153543Y1838031D02*
X156693Y1836850D01*
G01X153543Y1833031D02*
X156693Y1831850D01*
G01X153543Y1828031D02*
X156693Y1826850D01*
G01X150498Y1826115D02*
X150598Y1826082D01*
G01X150297Y1825328D02*
X150397Y1825295D01*
G01X149626Y1825229D02*
X149727Y1825196D01*
G01X156876Y1857749D02*
X156709Y1857847D01*
G01X157647Y1859225D02*
X157513Y1859291D01*
G01X157848Y1858602D02*
X157781Y1858635D01*
G01X157111Y1858930D02*
X157245Y1858865D01*
G01X150565Y1825885D02*
X150498Y1825918D01*
G01X149828Y1826213D02*
X149961Y1826148D01*
G01X150772Y1881122D02*
X150638Y1881220D01*
G01X157078Y1860209D02*
X157211Y1860111D01*
G01X157882Y1858799D02*
X158016Y1858700D01*
G01X156977Y1859357D02*
X156843Y1859455D01*
G01X157748Y1860177D02*
X157848Y1860111D01*
G01X157681Y1859389D02*
X157580Y1859455D01*
G01X157178Y1858668D02*
X157078Y1858733D01*
G01X149895Y1825951D02*
X149794Y1826017D01*
G01X149593Y1825032D02*
X149426Y1825131D01*
G01X150598Y1826082D02*
X150732Y1825984D01*
G01X150638Y1881023D02*
X150705Y1880958D01*
G01X157915Y1860275D02*
X158016Y1860177D01*
G01X157513Y1859291D02*
X157413Y1859389D01*
G01X157915Y1858536D02*
X157848Y1858602D01*
G01X157245Y1858865D02*
X157379Y1858733D01*
G01X156809Y1859258D02*
X156709Y1859357D01*
G01X157513Y1857847D02*
X157379Y1857979D01*
G01X156809Y1858044D02*
X156910Y1857946D01*
G01X150632Y1825820D02*
X150565Y1825885D01*
G01X149961Y1826148D02*
X150096Y1826017D01*
G01X150230Y1825131D02*
X150183Y1825177D01*
G01D02*
X150096Y1825262D01*
G01X149526Y1825328D02*
X149626Y1825229D01*
G01X150872Y1880991D02*
X150772Y1881122D01*
G01X157245Y1858569D02*
X157178Y1858668D01*
G01X157513Y1858143D02*
X157580Y1858044D01*
G01X157848Y1860111D02*
X157949Y1859980D01*
G01X157245Y1860308D02*
X157346Y1860177D01*
G01X157580Y1859455D02*
X157480Y1859586D01*
G01X158016Y1858700D02*
X158116Y1858569D01*
G01X150732Y1825984D02*
X150833Y1825853D01*
G01X158016Y1860177D02*
X158116Y1860013D01*
G01X156709Y1859357D02*
X156608Y1859520D01*
G01X156709Y1857847D02*
X156608Y1858011D01*
G01X149397Y1825177D02*
X149325Y1825295D01*
G01X149426Y1825131D02*
X149397Y1825177D01*
G01X149961Y1825853D02*
X149895Y1825951D01*
G01X150230Y1825426D02*
X150297Y1825328D01*
G01X157346Y1860177D02*
X157379Y1860111D01*
G01X157211D02*
X157279Y1859980D01*
G01X157413Y1859389D02*
X157379Y1859455D01*
G01Y1858733D02*
X157446Y1858602D01*
G01X156843Y1859455D02*
X156776Y1859586D01*
G01X157379Y1857979D02*
X157312Y1858110D01*
G01X150096Y1826017D02*
X150163Y1825885D01*
G01X150096Y1825262D02*
X150029Y1825393D01*
G01X150705Y1880958D02*
X150738Y1880859D01*
G01X157949Y1858438D02*
X157915Y1858536D01*
G01X157480Y1858241D02*
X157513Y1858143D01*
G01X157949Y1859980D02*
X157982Y1859849D01*
G01X157474Y1859606D02*
X157446Y1859717D01*
G01X157480Y1859586D02*
X157474Y1859606D01*
G01X157279Y1859980D02*
X157312Y1859849D01*
G01X157279Y1858438D02*
X157245Y1858569D01*
G01X157312Y1858110D02*
X157279Y1858241D01*
G01X156771Y1859606D02*
X156743Y1859717D01*
G01X156776Y1859586D02*
X156771Y1859606D01*
G01X156776Y1858176D02*
X156809Y1858044D01*
G01X150665Y1825721D02*
X150632Y1825820D01*
G01X150196Y1825524D02*
X150230Y1825426D01*
G01X158116Y1860013D02*
X158150Y1859849D01*
G01X158146Y1858425D02*
X158150Y1858405D01*
G01X158116Y1858569D02*
X158146Y1858425D01*
G01X157446Y1858602D02*
X157480Y1858438D01*
G01X156591Y1859606D02*
X156575Y1859685D01*
G01X156608Y1859520D02*
X156591Y1859606D01*
G01X156608Y1858011D02*
X156575Y1858176D01*
G01X150906Y1880826D02*
X150872Y1880991D01*
G01X150833Y1825853D02*
X150866Y1825689D01*
G01X150163Y1825885D02*
X150196Y1825721D01*
G01X149325Y1825295D02*
X149291Y1825459D01*
G01X149995Y1825721D02*
X149961Y1825853D01*
G01X150029Y1825393D02*
X149995Y1825524D01*
G01X149493Y1825459D02*
X149526Y1825328D01*
G01X177165Y1808878D02*
Y1968051D01*
G01X169291Y1954783D02*
Y1822145D01*
G01X168110Y1856259D02*
Y1880669D01*
G01X168012Y1822145D02*
Y1954783D01*
G01X166634D02*
Y1822145D01*
G01X166142Y1808878D02*
Y1817224D01*
G01X165354Y1878504D02*
Y1895177D01*
G01Y1820374D02*
Y1858425D01*
G01Y1859606D02*
Y1858425D01*
G01Y1861574D02*
Y1859606D01*
G01Y1862756D02*
Y1861574D01*
G01Y1864724D02*
Y1862756D01*
G01Y1867874D02*
Y1865905D01*
G01D02*
Y1864724D01*
G01Y1869055D02*
Y1867874D01*
G01Y1871023D02*
Y1869055D01*
G01Y1872204D02*
Y1871023D01*
G01Y1874173D02*
Y1872204D01*
G01Y1877322D02*
Y1875354D01*
G01D02*
Y1874173D01*
G01Y1878504D02*
Y1877322D01*
G01X163465D02*
Y1878504D01*
G01Y1874173D02*
Y1875354D01*
G01Y1871023D02*
Y1872204D01*
G01Y1867874D02*
Y1869055D01*
G01Y1864724D02*
Y1865905D01*
G01Y1861574D02*
Y1862756D01*
G01Y1858425D02*
Y1859606D01*
G01X161890Y1877322D02*
Y1878504D01*
G01Y1874173D02*
Y1875354D01*
G01Y1871023D02*
Y1872204D01*
G01Y1867874D02*
Y1869055D01*
G01Y1864724D02*
Y1865905D01*
G01Y1861574D02*
Y1862756D01*
G01Y1858425D02*
Y1859606D01*
G01X161417Y1886752D02*
Y1886850D01*
G01Y1885078D02*
Y1885177D01*
G01D02*
Y1886752D01*
G01Y1881752D02*
Y1881850D01*
G01Y1880078D02*
Y1880177D01*
G01D02*
Y1881752D01*
G01Y1856752D02*
Y1856850D01*
G01Y1855078D02*
Y1855177D01*
G01D02*
Y1856752D01*
G01Y1851752D02*
Y1851850D01*
G01Y1850177D02*
Y1851752D01*
G01Y1850078D02*
Y1850177D01*
G01Y1846752D02*
Y1846850D01*
G01Y1845177D02*
Y1846752D01*
G01Y1845078D02*
Y1845177D01*
G01Y1841752D02*
Y1841850D01*
G01Y1840177D02*
Y1841752D01*
G01Y1840078D02*
Y1840177D01*
G01Y1836752D02*
Y1836850D01*
G01Y1835177D02*
Y1836752D01*
G01Y1835078D02*
Y1835177D01*
G01Y1831752D02*
Y1831850D01*
G01Y1830177D02*
Y1831752D01*
G01Y1830078D02*
Y1830177D01*
G01Y1826752D02*
Y1826850D01*
G01Y1825078D02*
Y1825177D01*
G01D02*
Y1826752D01*
G01X161102Y1859606D02*
Y1858425D01*
G01Y1862756D02*
Y1861574D01*
G01Y1865905D02*
Y1864724D01*
G01Y1869055D02*
Y1867874D01*
G01Y1872204D02*
Y1871023D01*
G01Y1875354D02*
Y1874173D01*
G01Y1878504D02*
Y1877322D01*
G01X160709Y1859606D02*
Y1858425D01*
G01Y1862756D02*
Y1861574D01*
G01Y1869055D02*
Y1867874D01*
G01Y1865905D02*
Y1864724D01*
G01Y1872204D02*
Y1871023D01*
G01Y1875354D02*
Y1874173D01*
G01Y1878504D02*
Y1877322D01*
G01X160630Y1879291D02*
Y1879488D01*
G01Y1876141D02*
Y1876535D01*
G01Y1869842D02*
Y1870236D01*
G01Y1872992D02*
Y1873385D01*
G01Y1866693D02*
Y1867086D01*
G01Y1860393D02*
Y1860787D01*
G01Y1863543D02*
Y1863937D01*
G01Y1857441D02*
Y1857637D01*
G01X158465Y1849842D02*
Y1847086D01*
G01Y1884842D02*
Y1882086D01*
G01X158150Y1858405D02*
Y1858241D01*
G01Y1859849D02*
Y1859717D01*
G01X157982Y1859849D02*
Y1859717D01*
G01X157949Y1858241D02*
Y1858425D01*
G01D02*
Y1858438D01*
G01X157781Y1858635D02*
Y1858832D01*
G01X157480Y1858425D02*
Y1858241D01*
G01Y1858438D02*
Y1858425D01*
G01X157446Y1859717D02*
Y1859849D01*
G01X157312D02*
Y1859717D01*
G01X157284Y1879488D02*
Y1880078D01*
G01Y1856850D02*
Y1857441D01*
G01X157279Y1858241D02*
Y1858425D01*
G01D02*
Y1858438D01*
G01X157011Y1857913D02*
Y1857716D01*
G01X156776Y1858425D02*
Y1858176D01*
G01Y1858438D02*
Y1858425D01*
G01X156743Y1859717D02*
Y1859849D01*
G01X156575Y1859685D02*
Y1859882D01*
G01Y1858176D02*
Y1858425D01*
G01D02*
Y1858438D01*
G01X156102Y1877322D02*
Y1878504D01*
G01Y1874173D02*
Y1875354D01*
G01Y1871023D02*
Y1872204D01*
G01Y1864724D02*
Y1865905D01*
G01Y1867874D02*
Y1869055D01*
G01Y1861574D02*
Y1862756D01*
G01Y1858425D02*
Y1859606D01*
G01X155787Y1885177D02*
Y1886752D01*
G01Y1880177D02*
Y1881752D01*
G01Y1855177D02*
Y1856752D01*
G01Y1850177D02*
Y1851752D01*
G01Y1845177D02*
Y1846752D01*
G01Y1840177D02*
Y1841752D01*
G01Y1835177D02*
Y1836752D01*
G01Y1830177D02*
Y1831752D01*
G01Y1825177D02*
Y1826752D01*
G01X154213Y1885177D02*
Y1886752D01*
G01Y1880177D02*
Y1881752D01*
G01Y1855177D02*
Y1856752D01*
G01Y1850177D02*
Y1851752D01*
G01Y1845177D02*
Y1846752D01*
G01Y1840177D02*
Y1841752D01*
G01Y1835177D02*
Y1836752D01*
G01Y1830177D02*
Y1831752D01*
G01Y1825177D02*
Y1826752D01*
G01X153543Y1883031D02*
Y1883897D01*
G01Y1853031D02*
Y1853897D01*
G01Y1848031D02*
Y1848897D01*
G01Y1843031D02*
Y1843897D01*
G01Y1838031D02*
Y1838897D01*
G01Y1833031D02*
Y1833897D01*
G01Y1828031D02*
Y1828897D01*
G01Y1822145D02*
Y1823897D01*
G01X153425Y1826752D02*
Y1825177D01*
G01Y1831752D02*
Y1830177D01*
G01Y1836752D02*
Y1835177D01*
G01Y1841752D02*
Y1840177D01*
G01Y1846752D02*
Y1845177D01*
G01Y1851752D02*
Y1850177D01*
G01Y1856752D02*
Y1855177D01*
G01Y1881752D02*
Y1880177D01*
G01Y1886752D02*
Y1885177D01*
G01X153032Y1826752D02*
Y1825177D01*
G01Y1831752D02*
Y1830177D01*
G01Y1836752D02*
Y1835177D01*
G01Y1841752D02*
Y1840177D01*
G01Y1846752D02*
Y1845177D01*
G01Y1851752D02*
Y1850177D01*
G01Y1856752D02*
Y1855177D01*
G01Y1881752D02*
Y1880177D01*
G01Y1886752D02*
Y1885177D01*
G01X150906Y1881752D02*
Y1881909D01*
G01Y1880039D02*
Y1880177D01*
G01Y1881712D02*
Y1881752D01*
G01Y1880177D02*
Y1880826D01*
G01X150866Y1826752D02*
Y1826870D01*
G01Y1826673D02*
Y1826752D01*
G01Y1825689D02*
Y1825524D01*
G01X150738Y1880859D02*
Y1880236D01*
G01X150665Y1825524D02*
Y1825721D01*
G01X150498Y1825918D02*
Y1826115D01*
G01X150235Y1880236D02*
Y1880859D01*
G01X150196Y1825721D02*
Y1825524D01*
G01X150035Y1880826D02*
Y1880236D01*
G01X149995Y1825524D02*
Y1825721D01*
G01X149727Y1825177D02*
Y1825000D01*
G01Y1825196D02*
Y1825177D01*
G01X149493Y1825721D02*
Y1825459D01*
G01X149331Y1881909D02*
Y1881752D01*
G01Y1880177D02*
Y1880039D01*
G01Y1881752D02*
Y1881712D01*
G01Y1880236D02*
Y1880177D01*
G01X149291Y1825459D02*
Y1825721D01*
G01Y1826870D02*
Y1826752D01*
G01D02*
Y1826673D01*
G01X148110Y1885177D02*
Y1886752D01*
G01Y1855177D02*
Y1856752D01*
G01Y1850177D02*
Y1851752D01*
G01Y1845177D02*
Y1846752D01*
G01Y1840177D02*
Y1841752D01*
G01Y1835177D02*
Y1836752D01*
G01Y1830177D02*
Y1831752D01*
G01Y1825177D02*
Y1826752D01*
G01X146654Y1880177D02*
Y1881752D01*
G01X145669Y1808878D02*
Y1822145D01*
G01X150866Y1825524D02*
X150833Y1825393D01*
G01X158150Y1858241D02*
X158116Y1858110D01*
G01X149526Y1825853D02*
X149493Y1825721D01*
G01X157982Y1859717D02*
X157954Y1859606D01*
G01D02*
X157949Y1859586D01*
G01X157446Y1859849D02*
X157480Y1859980D01*
G01X157312Y1859717D02*
X157284Y1859606D01*
G01D02*
X157279Y1859586D01*
G01X156809Y1858569D02*
X156776Y1858438D01*
G01X156743Y1859849D02*
X156776Y1859980D01*
G01X158150Y1859717D02*
X158127Y1859606D01*
G01D02*
X158116Y1859554D01*
G01X156575Y1858438D02*
X156608Y1858602D01*
G01X156575Y1859882D02*
X156608Y1860046D01*
G01X149291Y1825721D02*
X149325Y1825885D01*
G01X150068Y1880991D02*
X150035Y1880826D01*
G01X150632Y1825426D02*
X150665Y1825524D01*
G01X157915Y1858143D02*
X157949Y1858241D01*
G01X150235Y1880859D02*
X150269Y1880958D01*
G01X150833Y1825393D02*
X150766Y1825262D01*
G01X149325Y1825885D02*
X149392Y1826017D01*
G01X158116Y1858110D02*
X158049Y1857979D01*
G01X157379Y1859455D02*
X157346Y1859389D01*
G01X157279Y1859586D02*
X157211Y1859455D01*
G01X156608Y1858602D02*
X156676Y1858733D01*
G01X157379Y1860111D02*
X157413Y1860177D01*
G01X156776Y1859980D02*
X156843Y1860111D01*
G01X157949Y1859586D02*
X157848Y1859455D01*
G01X157346Y1859389D02*
X157245Y1859258D01*
G01X157480Y1859980D02*
X157580Y1860111D01*
G01X150565Y1825328D02*
X150632Y1825426D01*
G01X149593Y1825951D02*
X149526Y1825853D01*
G01X157848Y1858044D02*
X157915Y1858143D01*
G01X156876Y1858668D02*
X156809Y1858569D01*
G01X158116Y1859554D02*
X158016Y1859389D01*
G01X156608Y1860046D02*
X156709Y1860209D01*
G01X150464Y1825295D02*
X150565Y1825328D01*
G01X149694Y1826017D02*
X149593Y1825951D01*
G01X150632Y1826476D02*
X150866Y1826673D01*
G01X150598D02*
X150364Y1826476D01*
G01X150679Y1825177D02*
X150632Y1825131D01*
G01X150766Y1825262D02*
X150679Y1825177D01*
G01X149392Y1826017D02*
X149526Y1826148D01*
G01X158049Y1857979D02*
X157915Y1857847D01*
G01X158016Y1859389D02*
X157915Y1859291D01*
G01X156676Y1858733D02*
X156809Y1858865D01*
G01X157413Y1860177D02*
X157513Y1860275D01*
G01X156709Y1860209D02*
X156809Y1860308D01*
G01X150269Y1880958D02*
X150336Y1881023D01*
G01X150169Y1881122D02*
X150068Y1880991D01*
G01X162992Y1858326D02*
X160630Y1857637D01*
G01X162992Y1861476D02*
X160630Y1860787D01*
G01X162992Y1864626D02*
X160630Y1863937D01*
G01X162992Y1867775D02*
X160630Y1867086D01*
G01X162992Y1870925D02*
X160630Y1870236D01*
G01X162992Y1874074D02*
X160630Y1873385D01*
G01X162992Y1877224D02*
X160630Y1876535D01*
G01X157748Y1858011D02*
X157848Y1858044D01*
G01X150336Y1881023D02*
X150437Y1881056D01*
G01X150403Y1881253D02*
X150302Y1881220D01*
G01X156693Y1825078D02*
X153543Y1823897D01*
G01X156693Y1830078D02*
X153543Y1828897D01*
G01X156693Y1835078D02*
X153543Y1833897D01*
G01X156693Y1840078D02*
X153543Y1838897D01*
G01X156693Y1845078D02*
X153543Y1843897D01*
G01X156693Y1850078D02*
X153543Y1848897D01*
G01X156693Y1855078D02*
X153543Y1853897D01*
G01X156693Y1885078D02*
X153543Y1883897D01*
G01X157915Y1859291D02*
X157748Y1859225D01*
G01X157245Y1859258D02*
X157078Y1859193D01*
G01X156809Y1860308D02*
X156977Y1860374D01*
G01X149526Y1826148D02*
X149660Y1826213D01*
G01X156809Y1858865D02*
X156944Y1858930D01*
G01X157513Y1860275D02*
X157647Y1860341D01*
G01X156977Y1858733D02*
X156876Y1858668D01*
G01X157848Y1859455D02*
X157748Y1859389D01*
G01X157580Y1860111D02*
X157681Y1860177D01*
G01X157211Y1859455D02*
X157078Y1859357D01*
G01X156843Y1860111D02*
X156977Y1860209D01*
G01X150302Y1881220D02*
X150169Y1881122D01*
G01X150671Y1881515D02*
X150906Y1881712D01*
G01X150638D02*
X150403Y1881515D01*
G01X99015Y1891115D02*
Y1889885D01*
G01X97968Y1904444D02*
Y1910185D01*
G01X99015Y1912851D02*
Y1911826D01*
G01Y1910185D02*
Y1902804D01*
G01Y1901163D02*
Y1899933D01*
G01X95455Y1897062D02*
X96083Y1896652D01*
G01X99015Y1902804D02*
X97968D01*
G01Y1910185D02*
X99015D01*
G01Y1925359D02*
Y1924334D01*
G01Y1928640D02*
Y1927615D01*
G01Y1922078D02*
Y1921053D01*
G01Y1916132D02*
Y1915107D01*
G01Y1919413D02*
Y1918387D01*
G01X156054Y1964842D02*
G03Y1961693I2017J-1574D01*
G01X160088D02*
G03Y1964842I-2017J1574D01*
G01X160441Y1960905D02*
G03Y1965630I-2370J2362D01*
G01X155701D02*
G03Y1960905I2370J-2362D01*
G01X161575Y1963267D02*
G03I-3504J0D01*
G01X160748Y1960118D02*
G03Y1966417I-2677J3149D01*
G01X155394D02*
G03Y1960118I2677J-3149D01*
G01X177165Y1970019D02*
X157480D01*
G01X199606Y1968051D02*
X145669D01*
G01X166142Y1966870D02*
X199606D01*
G01X155394Y1966417D02*
X160748D01*
G01X160441Y1965630D02*
X155701D01*
G01X156054Y1964842D02*
X160088D01*
G01X166142Y1962657D02*
X145669D01*
G01X177165D02*
X166142D01*
G01X156054Y1961693D02*
X160088D01*
G01X155701Y1960905D02*
X160441D01*
G01X160748Y1960118D02*
X155394D01*
G01X195669Y1959704D02*
X145669D01*
G01X165354Y1956555D02*
X145669D01*
G01Y1954783D02*
X165354D01*
G01D02*
X166634D01*
G01X196457D02*
X168012D01*
G01X161417Y1951850D02*
X156693D01*
G01X197638D02*
X165354D01*
G01Y1951752D02*
X195877D01*
G01X148110D02*
X165354D01*
G01Y1950177D02*
X195877D01*
G01X165354D02*
X148110D01*
G01X165354Y1950078D02*
X197638D01*
G01X156693D02*
X161417D01*
G01X165354Y1946850D02*
X197638D01*
G01X161417D02*
X156693D01*
G01X165354Y1946752D02*
X195877D01*
G01X148110D02*
X165354D01*
G01Y1945177D02*
X195877D01*
G01X165354D02*
X148110D01*
G01X165354Y1945078D02*
X197638D01*
G01X156693D02*
X161417D01*
G01X165354Y1941850D02*
X197638D01*
G01X161417D02*
X156693D01*
G01X165354Y1941752D02*
X195877D01*
G01X148110D02*
X165354D01*
G01Y1940177D02*
X195877D01*
G01X165354D02*
X148110D01*
G01X165354Y1940078D02*
X197638D01*
G01X156693D02*
X161417D01*
G01X166535Y1938326D02*
X165354D01*
G01X163386Y1936850D02*
X158661D01*
G01X197638D02*
X166535D01*
G01Y1936752D02*
X195877D01*
G01X146654D02*
X166535D01*
G01Y1935177D02*
X195877D01*
G01X146654D02*
X166535D01*
G01Y1935078D02*
X197638D01*
G01X158661D02*
X163386D01*
G01X158465Y1934842D02*
X165354D01*
G01Y1933602D02*
X166535D01*
G01X165354Y1932086D02*
X158465D01*
G01X165354Y1931850D02*
X197638D01*
G01X161417D02*
X156693D01*
G01X165354Y1931752D02*
X195877D01*
G01X148110D02*
X165354D01*
G01Y1930177D02*
X195877D01*
G01X165354D02*
X148110D01*
G01X165354Y1930078D02*
X197638D01*
G01X156693D02*
X161417D01*
G01X165354Y1926850D02*
X197638D01*
G01X161417D02*
X156693D01*
G01X165354Y1926752D02*
X195877D01*
G01X148110D02*
X165354D01*
G01Y1925177D02*
X195877D01*
G01X165354D02*
X148110D01*
G01X165354Y1925078D02*
X197638D01*
G01X156693D02*
X161417D01*
G01X165354Y1921850D02*
X197638D01*
G01X161417D02*
X156693D01*
G01X165354Y1921752D02*
X195877D01*
G01X148110D02*
X165354D01*
G01X158661Y1935078D02*
X153543Y1933897D01*
G01X158661Y1895078D02*
X153543Y1893897D01*
G01X165354Y1920177D02*
X195877D01*
G01X165354D02*
X148110D01*
G01X165354Y1920078D02*
X197638D01*
G01X156693D02*
X161417D01*
G01X165354Y1916850D02*
X197638D01*
G01X161417D02*
X156693D01*
G01X165354Y1916752D02*
X195877D01*
G01X148110D02*
X165354D01*
G01Y1915177D02*
X195877D01*
G01X165354D02*
X148110D01*
G01X165354Y1915078D02*
X197638D01*
G01X156693D02*
X161417D01*
G01X165354Y1911850D02*
X197638D01*
G01X161417D02*
X156693D01*
G01X165354Y1911752D02*
X195877D01*
G01X148110D02*
X165354D01*
G01Y1910177D02*
X195877D01*
G01X165354D02*
X148110D01*
G01X165354Y1910078D02*
X197638D01*
G01X156693D02*
X161417D01*
G01X158465Y1909842D02*
X165354D01*
G01Y1907086D02*
X158465D01*
G01X165354Y1906850D02*
X197638D01*
G01X161417D02*
X156693D01*
G01X165354Y1906752D02*
X195877D01*
G01X148110D02*
X165354D01*
G01Y1905177D02*
X195877D01*
G01X165354D02*
X148110D01*
G01X165354Y1905078D02*
X197638D01*
G01X156693D02*
X161417D01*
G01X165354Y1901850D02*
X197638D01*
G01X161417D02*
X156693D01*
G01X165354Y1901752D02*
X195877D01*
G01X148110D02*
X165354D01*
G01Y1900177D02*
X195877D01*
G01X165354D02*
X148110D01*
G01X165354Y1900078D02*
X197638D01*
G01X156693D02*
X161417D01*
G01X166535Y1898326D02*
X165354D01*
G01X163386Y1896850D02*
X158661D01*
G01X197638D02*
X166535D01*
G01Y1896752D02*
X195877D01*
G01X146654D02*
X166535D01*
G01Y1895177D02*
X195877D01*
G01X146654D02*
X166535D01*
G01Y1895078D02*
X197638D01*
G01X158661D02*
X163386D01*
G01X165354Y1893602D02*
X166535D01*
G01X165354Y1891850D02*
X197638D01*
G01X161417D02*
X156693D01*
G01X165354Y1891752D02*
X195877D01*
G01X148110D02*
X165354D01*
G01Y1890177D02*
X195877D01*
G01X165354D02*
X148110D01*
G01X165354Y1890078D02*
X197638D01*
G01X156693D02*
X161417D01*
G01X153543Y1938031D02*
X158661Y1936850D01*
G01X153543Y1898031D02*
X158661Y1896850D01*
G01X153543Y1953031D02*
X156693Y1951850D01*
G01X153543Y1948031D02*
X156693Y1946850D01*
G01X153543Y1943031D02*
X156693Y1941850D01*
G01X153543Y1933031D02*
X156693Y1931850D01*
G01X153543Y1928031D02*
X156693Y1926850D01*
G01X153543Y1923031D02*
X156693Y1921850D01*
G01X153543Y1918031D02*
X156693Y1916850D01*
G01X153543Y1913031D02*
X156693Y1911850D01*
G01X153543Y1908031D02*
X156693Y1906850D01*
G01X153543Y1903031D02*
X156693Y1901850D01*
G01X153543Y1893031D02*
X156693Y1891850D01*
G01X177165Y1968051D02*
Y1981004D01*
G01X166535Y1933602D02*
Y1938326D01*
G01Y1893602D02*
Y1898326D01*
G01X166142Y1959704D02*
Y1968051D01*
G01X165354Y1936752D02*
Y1956555D01*
G01Y1896752D02*
Y1935177D01*
G01Y1896752D02*
Y1895177D01*
G01Y1936752D02*
Y1935177D01*
G01X163386Y1936752D02*
Y1936850D01*
G01Y1935078D02*
Y1935177D01*
G01D02*
Y1936752D01*
G01Y1896752D02*
Y1896850D01*
G01Y1895078D02*
Y1895177D01*
G01D02*
Y1896752D01*
G01X161417Y1951752D02*
Y1951850D01*
G01Y1950078D02*
Y1950177D01*
G01D02*
Y1951752D01*
G01Y1946752D02*
Y1946850D01*
G01Y1945078D02*
Y1945177D01*
G01D02*
Y1946752D01*
G01Y1941752D02*
Y1941850D01*
G01Y1940078D02*
Y1940177D01*
G01D02*
Y1941752D01*
G01Y1931752D02*
Y1931850D01*
G01Y1930078D02*
Y1930177D01*
G01D02*
Y1931752D01*
G01Y1926752D02*
Y1926850D01*
G01Y1925177D02*
Y1926752D01*
G01Y1925078D02*
Y1925177D01*
G01Y1921752D02*
Y1921850D01*
G01Y1920177D02*
Y1921752D01*
G01Y1920078D02*
Y1920177D01*
G01Y1916752D02*
Y1916850D01*
G01Y1915177D02*
Y1916752D01*
G01Y1915078D02*
Y1915177D01*
G01Y1911752D02*
Y1911850D01*
G01Y1910177D02*
Y1911752D01*
G01Y1910078D02*
Y1910177D01*
G01Y1906752D02*
Y1906850D01*
G01Y1905177D02*
Y1906752D01*
G01Y1905078D02*
Y1905177D01*
G01Y1901752D02*
Y1901850D01*
G01Y1900078D02*
Y1900177D01*
G01D02*
Y1901752D01*
G01Y1891752D02*
Y1891850D01*
G01Y1890078D02*
Y1890177D01*
G01D02*
Y1891752D01*
G01X158465Y1909842D02*
Y1907086D01*
G01Y1934842D02*
Y1932086D01*
G01X157480Y1968051D02*
Y1981004D01*
G01X155787Y1950177D02*
Y1951752D01*
G01Y1945177D02*
Y1946752D01*
G01Y1940177D02*
Y1941752D01*
G01Y1935177D02*
Y1936752D01*
G01Y1930177D02*
Y1931752D01*
G01Y1925177D02*
Y1926752D01*
G01Y1920177D02*
Y1921752D01*
G01Y1915177D02*
Y1916752D01*
G01Y1910177D02*
Y1911752D01*
G01Y1905177D02*
Y1906752D01*
G01Y1900177D02*
Y1901752D01*
G01Y1895177D02*
Y1896752D01*
G01Y1890177D02*
Y1891752D01*
G01X154213Y1950177D02*
Y1951752D01*
G01Y1945177D02*
Y1946752D01*
G01Y1940177D02*
Y1941752D01*
G01Y1935177D02*
Y1936752D01*
G01Y1930177D02*
Y1931752D01*
G01Y1925177D02*
Y1926752D01*
G01Y1920177D02*
Y1921752D01*
G01Y1915177D02*
Y1916752D01*
G01Y1910177D02*
Y1911752D01*
G01Y1905177D02*
Y1906752D01*
G01Y1900177D02*
Y1901752D01*
G01Y1895177D02*
Y1896752D01*
G01Y1890177D02*
Y1891752D01*
G01X153543Y1953031D02*
Y1954783D01*
G01Y1948031D02*
Y1948897D01*
G01Y1943031D02*
Y1943897D01*
G01Y1938031D02*
Y1938897D01*
G01Y1933031D02*
Y1933897D01*
G01Y1928031D02*
Y1928897D01*
G01Y1923031D02*
Y1923897D01*
G01Y1918031D02*
Y1918897D01*
G01Y1913031D02*
Y1913897D01*
G01Y1908031D02*
Y1908897D01*
G01Y1903031D02*
Y1903897D01*
G01Y1898031D02*
Y1898897D01*
G01Y1893031D02*
Y1893897D01*
G01Y1888031D02*
Y1888897D01*
G01X153425Y1891752D02*
Y1890177D01*
G01Y1896752D02*
Y1895177D01*
G01Y1901752D02*
Y1900177D01*
G01Y1906752D02*
Y1905177D01*
G01Y1911752D02*
Y1910177D01*
G01Y1916752D02*
Y1915177D01*
G01Y1921752D02*
Y1920177D01*
G01Y1926752D02*
Y1925177D01*
G01Y1931752D02*
Y1930177D01*
G01Y1936752D02*
Y1935177D01*
G01Y1941752D02*
Y1940177D01*
G01Y1946752D02*
Y1945177D01*
G01Y1951752D02*
Y1950177D01*
G01X153032Y1891752D02*
Y1890177D01*
G01Y1896752D02*
Y1895177D01*
G01Y1901752D02*
Y1900177D01*
G01Y1906752D02*
Y1905177D01*
G01Y1911752D02*
Y1910177D01*
G01Y1916752D02*
Y1915177D01*
G01Y1921752D02*
Y1920177D01*
G01Y1926752D02*
Y1925177D01*
G01Y1931752D02*
Y1930177D01*
G01Y1936752D02*
Y1935177D01*
G01Y1941752D02*
Y1940177D01*
G01Y1946752D02*
Y1945177D01*
G01Y1951752D02*
Y1950177D01*
G01X148110D02*
Y1951752D01*
G01Y1945177D02*
Y1946752D01*
G01Y1940177D02*
Y1941752D01*
G01Y1930177D02*
Y1931752D01*
G01Y1925177D02*
Y1926752D01*
G01Y1920177D02*
Y1921752D01*
G01Y1915177D02*
Y1916752D01*
G01Y1910177D02*
Y1911752D01*
G01Y1905177D02*
Y1906752D01*
G01Y1900177D02*
Y1901752D01*
G01Y1890177D02*
Y1891752D01*
G01X146654Y1935177D02*
Y1936752D01*
G01Y1895177D02*
Y1896752D01*
G01X145669Y1954783D02*
Y1968051D01*
G01X156693Y1890078D02*
X153543Y1888897D01*
G01X156693Y1900078D02*
X153543Y1898897D01*
G01X156693Y1905078D02*
X153543Y1903897D01*
G01X156693Y1910078D02*
X153543Y1908897D01*
G01X156693Y1915078D02*
X153543Y1913897D01*
G01X156693Y1920078D02*
X153543Y1918897D01*
G01X156693Y1925078D02*
X153543Y1923897D01*
G01X156693Y1930078D02*
X153543Y1928897D01*
G01X156693Y1940078D02*
X153543Y1938897D01*
G01X156693Y1945078D02*
X153543Y1943897D01*
G01X156693Y1950078D02*
X153543Y1948897D01*
G01X171063Y1975078D02*
G03I-3740J0D01*
G01X153543Y1984941D02*
X181102D01*
G01X177165Y1981004D02*
X157480D01*
G01X177165Y1979035D02*
X157480D01*
G01X177165Y1977047D02*
X157480D01*
G01Y1976063D02*
X177165D01*
G01X176969Y1975866D02*
X157677D01*
G01X176969Y1974291D02*
X157677D01*
G01X177165Y1974094D02*
X157480D01*
G01Y1973110D02*
X177165D01*
G01X153543Y1971988D02*
X141732D01*
G01X176969Y1974291D02*
Y1975866D01*
G01X171614D02*
Y1974291D01*
G01X170276Y1974094D02*
Y1974291D01*
G01Y1975866D02*
Y1976063D01*
G01Y1975866D02*
Y1974291D01*
G01X170079Y1975866D02*
Y1974291D01*
G01X168504Y1975866D02*
Y1974291D01*
G01X166142Y1975866D02*
Y1974291D01*
G01X164567D02*
Y1975866D01*
G01X164370D02*
Y1976063D01*
G01Y1974291D02*
Y1975866D01*
G01Y1974291D02*
Y1974094D01*
G01X163032Y1974291D02*
Y1975866D01*
G01X157677D02*
Y1974291D01*
G01X153543Y1971988D02*
Y1984941D01*
G01X108267Y2138820D02*
Y2119883D01*
G01X215456Y-52375D02*
X216311Y-53326D01*
X217309Y-53896D01*
X218593Y-54086D01*
X219877Y-53706D01*
X220875Y-52946D01*
X221588Y-51615D01*
X221730Y-50094D01*
X221445Y-48573D01*
X220732Y-47622D01*
X219734Y-46862D01*
X218736Y-46672D01*
X217737Y-46862D01*
X216454Y-47622D01*
X216882Y-42679D01*
X220732D01*
G01X204331Y191476D02*
X199606Y186830D01*
G01X199611Y187938D02*
X204331Y192580D01*
G01X195669Y195177D02*
X197638Y197145D01*
G01X208268Y182893D02*
Y349941D01*
G01X204331Y191476D02*
Y193208D01*
G01X199606Y195177D02*
Y188011D01*
G01X197638Y195177D02*
Y337657D01*
G01X196457Y200098D02*
Y332736D01*
G01X195877Y228130D02*
Y229704D01*
G01Y223130D02*
Y224704D01*
G01Y218130D02*
Y219704D01*
G01Y213130D02*
Y214704D01*
G01Y208130D02*
Y209704D01*
G01Y203130D02*
Y204704D01*
G01X195195D02*
Y203130D01*
G01Y209704D02*
Y208130D01*
G01Y214704D02*
Y213130D01*
G01Y219704D02*
Y218130D01*
G01Y224704D02*
Y223130D01*
G01Y229704D02*
Y228130D01*
G01X194685Y228031D02*
Y229803D01*
G01Y223031D02*
Y224803D01*
G01Y218031D02*
Y219803D01*
G01Y213031D02*
Y214803D01*
G01Y208031D02*
Y209803D01*
G01Y203031D02*
Y204803D01*
G01X191020Y228130D02*
Y229704D01*
G01Y223130D02*
Y224704D01*
G01Y218130D02*
Y219704D01*
G01Y213130D02*
Y214704D01*
G01Y208130D02*
Y209704D01*
G01Y203130D02*
Y204704D01*
G01X190774Y228130D02*
Y229704D01*
G01Y223130D02*
Y224704D01*
G01Y218130D02*
Y219704D01*
G01Y213130D02*
Y214704D01*
G01Y208130D02*
Y209704D01*
G01Y203130D02*
Y204704D01*
G01X189667D02*
Y203130D01*
G01Y209704D02*
Y208130D01*
G01Y214704D02*
Y213130D01*
G01Y219704D02*
Y218130D01*
G01Y224704D02*
Y223130D01*
G01Y229704D02*
Y228130D01*
G01X181102Y182893D02*
Y169941D01*
G01X196457Y200098D02*
X197638Y198917D01*
G01Y195177D02*
X200921D01*
G01X208268Y182893D02*
X181102D01*
G01X204331Y193208D02*
X200921Y195177D01*
G01X287401Y267717D02*
G03I-15748J0D01*
G01X195669Y256181D02*
X197638Y258149D01*
G01X197441Y255177D02*
Y256555D01*
G01Y237657D02*
Y236279D01*
G01Y243956D02*
Y242578D01*
G01Y240807D02*
Y239429D01*
G01Y247106D02*
Y245728D01*
G01Y253405D02*
Y252027D01*
G01Y250256D02*
Y248878D01*
G01X195877Y313130D02*
Y314704D01*
G01Y308130D02*
Y309704D01*
G01Y303130D02*
Y304704D01*
G01Y298130D02*
Y299704D01*
G01Y293130D02*
Y294704D01*
G01Y288130D02*
Y289704D01*
G01Y283130D02*
Y284704D01*
G01Y278130D02*
Y279704D01*
G01Y273130D02*
Y274704D01*
G01Y268130D02*
Y269704D01*
G01Y263130D02*
Y264704D01*
G01X195756Y258130D02*
Y259704D01*
G01Y233130D02*
Y234704D01*
G01X195669Y258622D02*
Y234212D01*
G01X195195Y264704D02*
Y263130D01*
G01Y269704D02*
Y268130D01*
G01Y274704D02*
Y273130D01*
G01Y279704D02*
Y278130D01*
G01Y284704D02*
Y283130D01*
G01Y289704D02*
Y288130D01*
G01Y294704D02*
Y293130D01*
G01Y299704D02*
Y298130D01*
G01Y304704D02*
Y303130D01*
G01Y309704D02*
Y308130D01*
G01Y314704D02*
Y313130D01*
G01X194767Y234704D02*
Y233130D01*
G01Y259704D02*
Y258130D01*
G01X194685Y313031D02*
Y314803D01*
G01Y308031D02*
Y309803D01*
G01Y303031D02*
Y304803D01*
G01Y298031D02*
Y299803D01*
G01Y293031D02*
Y294803D01*
G01Y288031D02*
Y289803D01*
G01Y283031D02*
Y284803D01*
G01Y278031D02*
Y279803D01*
G01Y273031D02*
Y274803D01*
G01Y268031D02*
Y269803D01*
G01Y263031D02*
Y264803D01*
G01Y258031D02*
Y259803D01*
G01Y233031D02*
Y234803D01*
G01X194215Y237559D02*
Y236378D01*
G01Y240708D02*
Y239527D01*
G01Y243858D02*
Y242677D01*
G01Y247008D02*
Y245826D01*
G01Y250157D02*
Y248976D01*
G01Y253307D02*
Y252126D01*
G01Y256456D02*
Y255275D01*
G01X193477D02*
Y256456D01*
G01Y248976D02*
Y250157D01*
G01Y252126D02*
Y253307D01*
G01Y245826D02*
Y247008D01*
G01Y239527D02*
Y240708D01*
G01Y242677D02*
Y243858D01*
G01Y236378D02*
Y237559D01*
G01X191020Y313130D02*
Y314704D01*
G01Y308130D02*
Y309704D01*
G01Y303130D02*
Y304704D01*
G01Y298130D02*
Y299704D01*
G01Y293130D02*
Y294704D01*
G01Y288130D02*
Y289704D01*
G01Y283130D02*
Y284704D01*
G01Y278130D02*
Y279704D01*
G01Y273130D02*
Y274704D01*
G01Y268130D02*
Y269704D01*
G01Y263130D02*
Y264704D01*
G01Y234704D02*
Y233130D01*
G01Y259704D02*
Y258130D01*
G01X190774Y313130D02*
Y314704D01*
G01Y308130D02*
Y309704D01*
G01Y303130D02*
Y304704D01*
G01Y298130D02*
Y299704D01*
G01Y293130D02*
Y294704D01*
G01Y288130D02*
Y289704D01*
G01Y283130D02*
Y284704D01*
G01Y278130D02*
Y279704D01*
G01Y273130D02*
Y274704D01*
G01Y268130D02*
Y269704D01*
G01Y263130D02*
Y264704D01*
G01Y258130D02*
Y259704D01*
G01Y233130D02*
Y234704D01*
G01X189667D02*
Y233130D01*
G01Y259704D02*
Y258130D01*
G01Y264704D02*
Y263130D01*
G01Y269704D02*
Y268130D01*
G01Y274704D02*
Y273130D01*
G01Y279704D02*
Y278130D01*
G01Y284704D02*
Y283130D01*
G01Y289704D02*
Y288130D01*
G01Y294704D02*
Y293130D01*
G01Y299704D02*
Y298130D01*
G01Y304704D02*
Y303130D01*
G01Y309704D02*
Y308130D01*
G01Y314704D02*
Y313130D01*
G01X188661Y248878D02*
Y250256D01*
G01Y252027D02*
Y253405D01*
G01Y245728D02*
Y247106D01*
G01Y239429D02*
Y240807D01*
G01Y242578D02*
Y243956D01*
G01Y237657D02*
Y236279D01*
G01Y256555D02*
Y255177D01*
G01X187919Y237559D02*
Y236378D01*
G01Y240708D02*
Y239527D01*
G01Y243858D02*
Y242677D01*
G01Y247008D02*
Y245826D01*
G01Y253307D02*
Y252126D01*
G01Y250157D02*
Y248976D01*
G01Y256456D02*
Y255275D01*
G01X187421D02*
Y256456D01*
G01Y252126D02*
Y253307D01*
G01Y248976D02*
Y250157D01*
G01Y245826D02*
Y247008D01*
G01Y242677D02*
Y243858D01*
G01Y239527D02*
Y240708D01*
G01Y236378D02*
Y237559D01*
G01X185182D02*
Y236378D01*
G01Y240708D02*
Y239527D01*
G01Y243858D02*
Y242677D01*
G01Y247008D02*
Y245826D01*
G01Y250157D02*
Y248976D01*
G01Y253307D02*
Y252126D01*
G01Y256456D02*
Y255275D01*
G01X197638Y256555D02*
X197441D01*
G01Y255177D02*
X197638D01*
G01Y253405D02*
X197441D01*
G01Y252027D02*
X197638D01*
G01Y250256D02*
X197441D01*
G01Y248878D02*
X197638D01*
G01Y247106D02*
X197441D01*
G01Y245728D02*
X197638D01*
G01Y234685D02*
X195669Y236653D01*
G01X197638Y243956D02*
X197441D01*
G01Y242578D02*
X197638D01*
G01Y240807D02*
X197441D01*
G01Y239429D02*
X197638D01*
G01Y237657D02*
X197441D01*
G01Y236279D02*
X197638D01*
G01X200921Y337657D02*
X204331Y339626D01*
G01X196457Y332736D02*
X197638Y333917D01*
G01X204331Y339626D02*
Y341358D01*
G01X199606Y344822D02*
Y337657D01*
G01X195877Y328130D02*
Y329704D01*
G01Y323130D02*
Y324704D01*
G01Y318130D02*
Y319704D01*
G01X195195D02*
Y318130D01*
G01Y324704D02*
Y323130D01*
G01Y329704D02*
Y328130D01*
G01X194685Y328031D02*
Y329803D01*
G01Y323031D02*
Y324803D01*
G01Y318031D02*
Y319803D01*
G01X191020Y328130D02*
Y329704D01*
G01Y323130D02*
Y324704D01*
G01Y318130D02*
Y319704D01*
G01X190774Y328130D02*
Y329704D01*
G01Y323130D02*
Y324704D01*
G01Y318130D02*
Y319704D01*
G01X189667D02*
Y318130D01*
G01Y324704D02*
Y323130D01*
G01Y329704D02*
Y328130D01*
G01X181102Y362893D02*
Y349941D01*
G01D02*
X208268D01*
G01X197638Y337657D02*
X200921D01*
G01X197638Y335689D02*
X195669Y337657D01*
G01X199606Y346004D02*
X204331Y341358D01*
G01Y340255D02*
X199611Y344896D01*
G01X177755Y528091D02*
Y554665D01*
G01X204331Y596988D02*
X199606Y592342D01*
G01X199611Y593450D02*
X204331Y598091D01*
G01X195669Y600689D02*
X197638Y602657D01*
G01X197441Y644941D02*
X197638D01*
G01Y643169D02*
X197441D01*
G01Y641791D02*
X197638D01*
G01X208268Y588405D02*
Y755452D01*
G01X204331Y596988D02*
Y598720D01*
G01X199606Y600689D02*
Y593523D01*
G01X197638Y600689D02*
Y743169D01*
G01X197441Y646319D02*
Y644941D01*
G01Y643169D02*
Y641791D01*
G01X196457Y605610D02*
Y738248D01*
G01X195877Y633641D02*
Y635216D01*
G01Y628641D02*
Y630216D01*
G01Y623641D02*
Y625216D01*
G01Y618641D02*
Y620216D01*
G01Y613641D02*
Y615216D01*
G01Y608641D02*
Y610216D01*
G01X195756Y638641D02*
Y640216D01*
G01X195669Y664133D02*
Y639724D01*
G01X195195Y610216D02*
Y608641D01*
G01Y615216D02*
Y613641D01*
G01Y620216D02*
Y618641D01*
G01Y625216D02*
Y623641D01*
G01Y630216D02*
Y628641D01*
G01Y635216D02*
Y633641D01*
G01X194767Y640216D02*
Y638641D01*
G01X194685Y638543D02*
Y640315D01*
G01Y633543D02*
Y635315D01*
G01Y628543D02*
Y630315D01*
G01Y623543D02*
Y625315D01*
G01Y618543D02*
Y620315D01*
G01Y613543D02*
Y615315D01*
G01Y608543D02*
Y610315D01*
G01X194215Y643070D02*
Y641889D01*
G01Y646220D02*
Y645039D01*
G01X193477Y641889D02*
Y643070D01*
G01Y645039D02*
Y646220D01*
G01X191020Y633641D02*
Y635216D01*
G01Y628641D02*
Y630216D01*
G01Y623641D02*
Y625216D01*
G01Y618641D02*
Y620216D01*
G01Y613641D02*
Y615216D01*
G01Y608641D02*
Y610216D01*
G01Y640216D02*
Y638641D01*
G01X190774D02*
Y640216D01*
G01Y633641D02*
Y635216D01*
G01Y628641D02*
Y630216D01*
G01Y623641D02*
Y625216D01*
G01Y618641D02*
Y620216D01*
G01Y613641D02*
Y615216D01*
G01Y608641D02*
Y610216D01*
G01X189667D02*
Y608641D01*
G01Y615216D02*
Y613641D01*
G01Y620216D02*
Y618641D01*
G01Y625216D02*
Y623641D01*
G01Y630216D02*
Y628641D01*
G01Y635216D02*
Y633641D01*
G01Y640216D02*
Y638641D01*
G01X188661Y644941D02*
Y646319D01*
G01Y643169D02*
Y641791D01*
G01X187919Y643070D02*
Y641889D01*
G01Y646220D02*
Y645039D01*
G01X187421Y641889D02*
Y643070D01*
G01Y645039D02*
Y646220D01*
G01X185182Y643070D02*
Y641889D01*
G01Y646220D02*
Y645039D01*
G01X181102Y588405D02*
Y575452D01*
G01X197638Y600689D02*
X200921D01*
G01X208268Y588405D02*
X181102D01*
G01X197638Y640196D02*
X195669Y642165D01*
G01X196457Y605610D02*
X197638Y604429D01*
G01X204331Y598720D02*
X200921Y600689D01*
G01X287401Y673228D02*
G03I-15748J0D01*
G01X195669Y661693D02*
X197638Y663661D01*
G01Y662067D02*
X197441D01*
G01Y660689D02*
X197638D01*
G01Y658917D02*
X197441D01*
G01Y657539D02*
X197638D01*
G01Y655767D02*
X197441D01*
G01Y654389D02*
X197638D01*
G01Y652618D02*
X197441D01*
G01Y651240D02*
X197638D01*
G01Y649468D02*
X197441D01*
G01Y648090D02*
X197638D01*
G01Y646319D02*
X197441D01*
G01Y660689D02*
Y662067D01*
G01Y649468D02*
Y648090D01*
G01Y655767D02*
Y654389D01*
G01Y652618D02*
Y651240D01*
G01Y658917D02*
Y657539D01*
G01X195877Y728641D02*
Y730216D01*
G01Y723641D02*
Y725216D01*
G01Y718641D02*
Y720216D01*
G01Y713641D02*
Y715216D01*
G01Y708641D02*
Y710216D01*
G01Y703641D02*
Y705216D01*
G01Y698641D02*
Y700216D01*
G01Y693641D02*
Y695216D01*
G01Y688641D02*
Y690216D01*
G01Y683641D02*
Y685216D01*
G01Y678641D02*
Y680216D01*
G01Y673641D02*
Y675216D01*
G01Y668641D02*
Y670216D01*
G01X195756Y663641D02*
Y665216D01*
G01X195195Y670216D02*
Y668641D01*
G01Y675216D02*
Y673641D01*
G01Y680216D02*
Y678641D01*
G01Y685216D02*
Y683641D01*
G01Y690216D02*
Y688641D01*
G01Y695216D02*
Y693641D01*
G01Y700216D02*
Y698641D01*
G01Y705216D02*
Y703641D01*
G01Y710216D02*
Y708641D01*
G01Y715216D02*
Y713641D01*
G01Y720216D02*
Y718641D01*
G01Y725216D02*
Y723641D01*
G01Y730216D02*
Y728641D01*
G01X194767Y665216D02*
Y663641D01*
G01X194685Y728543D02*
Y730315D01*
G01Y723543D02*
Y725315D01*
G01Y718543D02*
Y720315D01*
G01Y713543D02*
Y715315D01*
G01Y708543D02*
Y710315D01*
G01Y703543D02*
Y705315D01*
G01Y698543D02*
Y700315D01*
G01Y693543D02*
Y695315D01*
G01Y688543D02*
Y690315D01*
G01Y683543D02*
Y685315D01*
G01Y678543D02*
Y680315D01*
G01Y673543D02*
Y675315D01*
G01Y668543D02*
Y670315D01*
G01Y663543D02*
Y665315D01*
G01X194215Y649370D02*
Y648189D01*
G01Y652519D02*
Y651338D01*
G01Y655669D02*
Y654488D01*
G01Y658819D02*
Y657637D01*
G01Y661968D02*
Y660787D01*
G01X193477D02*
Y661968D01*
G01Y657637D02*
Y658819D01*
G01Y654488D02*
Y655669D01*
G01Y651338D02*
Y652519D01*
G01Y648189D02*
Y649370D01*
G01X191020Y728641D02*
Y730216D01*
G01Y723641D02*
Y725216D01*
G01Y718641D02*
Y720216D01*
G01Y713641D02*
Y715216D01*
G01Y708641D02*
Y710216D01*
G01Y703641D02*
Y705216D01*
G01Y698641D02*
Y700216D01*
G01Y693641D02*
Y695216D01*
G01Y688641D02*
Y690216D01*
G01Y683641D02*
Y685216D01*
G01Y678641D02*
Y680216D01*
G01Y673641D02*
Y675216D01*
G01Y668641D02*
Y670216D01*
G01Y665216D02*
Y663641D01*
G01X190774Y728641D02*
Y730216D01*
G01Y723641D02*
Y725216D01*
G01Y718641D02*
Y720216D01*
G01Y713641D02*
Y715216D01*
G01Y708641D02*
Y710216D01*
G01Y703641D02*
Y705216D01*
G01Y698641D02*
Y700216D01*
G01Y693641D02*
Y695216D01*
G01Y688641D02*
Y690216D01*
G01Y683641D02*
Y685216D01*
G01Y678641D02*
Y680216D01*
G01Y673641D02*
Y675216D01*
G01Y668641D02*
Y670216D01*
G01Y663641D02*
Y665216D01*
G01X189667D02*
Y663641D01*
G01Y670216D02*
Y668641D01*
G01Y675216D02*
Y673641D01*
G01Y680216D02*
Y678641D01*
G01Y685216D02*
Y683641D01*
G01Y690216D02*
Y688641D01*
G01Y695216D02*
Y693641D01*
G01Y700216D02*
Y698641D01*
G01Y705216D02*
Y703641D01*
G01Y710216D02*
Y708641D01*
G01Y715216D02*
Y713641D01*
G01Y720216D02*
Y718641D01*
G01Y725216D02*
Y723641D01*
G01Y730216D02*
Y728641D01*
G01X188661Y657539D02*
Y658917D01*
G01Y651240D02*
Y652618D01*
G01Y654389D02*
Y655767D01*
G01Y648090D02*
Y649468D01*
G01Y662067D02*
Y660689D01*
G01X187919Y649370D02*
Y648189D01*
G01Y655669D02*
Y654488D01*
G01Y652519D02*
Y651338D01*
G01Y658819D02*
Y657637D01*
G01Y661968D02*
Y660787D01*
G01X187421D02*
Y661968D01*
G01Y657637D02*
Y658819D01*
G01Y654488D02*
Y655669D01*
G01Y651338D02*
Y652519D01*
G01Y648189D02*
Y649370D01*
G01X185182D02*
Y648189D01*
G01Y652519D02*
Y651338D01*
G01Y655669D02*
Y654488D01*
G01Y658819D02*
Y657637D01*
G01Y661968D02*
Y660787D01*
G01X200921Y743169D02*
X204331Y745137D01*
G01X196457Y738248D02*
X197638Y739429D01*
G01X181102Y755452D02*
X208268D01*
G01X197638Y743169D02*
X200921D01*
G01X204331Y745137D02*
Y746870D01*
G01X199606Y750334D02*
Y743169D01*
G01X195877Y733641D02*
Y735216D01*
G01X195195D02*
Y733641D01*
G01X194685Y733543D02*
Y735315D01*
G01X191020Y733641D02*
Y735216D01*
G01X190774Y733641D02*
Y735216D01*
G01X189667D02*
Y733641D01*
G01X181102Y768405D02*
Y755452D01*
G01X197638Y741200D02*
X195669Y743169D01*
G01X199606Y751515D02*
X204331Y746870D01*
G01Y745767D02*
X199611Y750408D01*
G01X197441Y1059901D02*
X197638D01*
G01Y1058130D02*
X197441D01*
G01Y1056752D02*
X197638D01*
G01Y1054980D02*
X197441D01*
G01Y1053602D02*
X197638D01*
G01Y1051830D02*
X197441D01*
G01Y1050452D02*
X197638D01*
G01Y1048681D02*
X197441D01*
G01Y1047303D02*
X197638D01*
G01Y1006200D02*
X200921D01*
G01X208268Y993917D02*
X181102D01*
G01X197638Y1045708D02*
X195669Y1047677D01*
G01X196457Y1011122D02*
X197638Y1009941D01*
G01X204331Y1004232D02*
X200921Y1006200D01*
G01X204331Y1002500D02*
X199606Y997854D01*
G01X199611Y998961D02*
X204331Y1003603D01*
G01X195669Y1006200D02*
X197638Y1008169D01*
G01X208268Y993917D02*
Y1160964D01*
G01X204331Y1002500D02*
Y1004232D01*
G01X199606Y1006200D02*
Y999035D01*
G01X197638Y1006200D02*
Y1148681D01*
G01X197441Y1048681D02*
Y1047303D01*
G01Y1051830D02*
Y1050452D01*
G01Y1058130D02*
Y1056752D01*
G01Y1054980D02*
Y1053602D01*
G01Y1061279D02*
Y1059901D01*
G01X196457Y1011122D02*
Y1143759D01*
G01X195877Y1039153D02*
Y1040728D01*
G01Y1034153D02*
Y1035728D01*
G01Y1029153D02*
Y1030728D01*
G01Y1024153D02*
Y1025728D01*
G01Y1019153D02*
Y1020728D01*
G01Y1014153D02*
Y1015728D01*
G01X195756Y1044153D02*
Y1045728D01*
G01X195669Y1069645D02*
Y1045236D01*
G01X195195Y1015728D02*
Y1014153D01*
G01Y1020728D02*
Y1019153D01*
G01Y1025728D02*
Y1024153D01*
G01Y1030728D02*
Y1029153D01*
G01Y1035728D02*
Y1034153D01*
G01Y1040728D02*
Y1039153D01*
G01X194767Y1045728D02*
Y1044153D01*
G01X194685Y1044055D02*
Y1045826D01*
G01Y1039055D02*
Y1040826D01*
G01Y1034055D02*
Y1035826D01*
G01Y1029055D02*
Y1030826D01*
G01Y1024055D02*
Y1025826D01*
G01Y1019055D02*
Y1020826D01*
G01Y1014055D02*
Y1015826D01*
G01X194215Y1048582D02*
Y1047401D01*
G01Y1051732D02*
Y1050551D01*
G01Y1054882D02*
Y1053700D01*
G01Y1058031D02*
Y1056850D01*
G01Y1061181D02*
Y1060000D01*
G01X193477D02*
Y1061181D01*
G01Y1053700D02*
Y1054882D01*
G01Y1056850D02*
Y1058031D01*
G01Y1050551D02*
Y1051732D01*
G01Y1047401D02*
Y1048582D01*
G01X191020Y1039153D02*
Y1040728D01*
G01Y1034153D02*
Y1035728D01*
G01Y1029153D02*
Y1030728D01*
G01Y1024153D02*
Y1025728D01*
G01Y1019153D02*
Y1020728D01*
G01Y1014153D02*
Y1015728D01*
G01Y1045728D02*
Y1044153D01*
G01X190774D02*
Y1045728D01*
G01Y1039153D02*
Y1040728D01*
G01Y1034153D02*
Y1035728D01*
G01Y1029153D02*
Y1030728D01*
G01Y1024153D02*
Y1025728D01*
G01Y1019153D02*
Y1020728D01*
G01Y1014153D02*
Y1015728D01*
G01X189667D02*
Y1014153D01*
G01Y1020728D02*
Y1019153D01*
G01Y1025728D02*
Y1024153D01*
G01Y1030728D02*
Y1029153D01*
G01Y1035728D02*
Y1034153D01*
G01Y1040728D02*
Y1039153D01*
G01Y1045728D02*
Y1044153D01*
G01X188661Y1059901D02*
Y1061279D01*
G01Y1053602D02*
Y1054980D01*
G01Y1056752D02*
Y1058130D01*
G01Y1050452D02*
Y1051830D01*
G01Y1048681D02*
Y1047303D01*
G01X187919Y1048582D02*
Y1047401D01*
G01Y1051732D02*
Y1050551D01*
G01Y1054882D02*
Y1053700D01*
G01Y1058031D02*
Y1056850D01*
G01Y1061181D02*
Y1060000D01*
G01X187421D02*
Y1061181D01*
G01Y1056850D02*
Y1058031D01*
G01Y1053700D02*
Y1054882D01*
G01Y1050551D02*
Y1051732D01*
G01Y1047401D02*
Y1048582D01*
G01X185182D02*
Y1047401D01*
G01Y1051732D02*
Y1050551D01*
G01Y1054882D02*
Y1053700D01*
G01Y1058031D02*
Y1056850D01*
G01Y1061181D02*
Y1060000D01*
G01X181102Y993917D02*
Y980964D01*
G01X287401Y1078740D02*
G03I-15748J0D01*
G01X197638Y1067578D02*
X197441D01*
G01Y1066200D02*
X197638D01*
G01Y1064429D02*
X197441D01*
G01Y1063051D02*
X197638D01*
G01Y1061279D02*
X197441D01*
G01X195669Y1067204D02*
X197638Y1069173D01*
G01X197441Y1066200D02*
Y1067578D01*
G01Y1064429D02*
Y1063051D01*
G01X195877Y1139153D02*
Y1140728D01*
G01Y1134153D02*
Y1135728D01*
G01Y1129153D02*
Y1130728D01*
G01Y1124153D02*
Y1125728D01*
G01Y1119153D02*
Y1120728D01*
G01Y1114153D02*
Y1115728D01*
G01Y1109153D02*
Y1110728D01*
G01Y1104153D02*
Y1105728D01*
G01Y1099153D02*
Y1100728D01*
G01Y1094153D02*
Y1095728D01*
G01Y1089153D02*
Y1090728D01*
G01Y1084153D02*
Y1085728D01*
G01Y1079153D02*
Y1080728D01*
G01Y1074153D02*
Y1075728D01*
G01X195756Y1069153D02*
Y1070728D01*
G01X195195Y1075728D02*
Y1074153D01*
G01Y1080728D02*
Y1079153D01*
G01Y1085728D02*
Y1084153D01*
G01Y1090728D02*
Y1089153D01*
G01Y1095728D02*
Y1094153D01*
G01Y1100728D02*
Y1099153D01*
G01Y1105728D02*
Y1104153D01*
G01Y1110728D02*
Y1109153D01*
G01Y1115728D02*
Y1114153D01*
G01Y1120728D02*
Y1119153D01*
G01Y1125728D02*
Y1124153D01*
G01Y1130728D02*
Y1129153D01*
G01Y1135728D02*
Y1134153D01*
G01Y1140728D02*
Y1139153D01*
G01X194767Y1070728D02*
Y1069153D01*
G01X194685Y1139055D02*
Y1140826D01*
G01Y1134055D02*
Y1135826D01*
G01Y1129055D02*
Y1130826D01*
G01Y1124055D02*
Y1125826D01*
G01Y1119055D02*
Y1120826D01*
G01Y1114055D02*
Y1115826D01*
G01Y1109055D02*
Y1110826D01*
G01Y1104055D02*
Y1105826D01*
G01Y1099055D02*
Y1100826D01*
G01Y1094055D02*
Y1095826D01*
G01Y1089055D02*
Y1090826D01*
G01Y1084055D02*
Y1085826D01*
G01Y1079055D02*
Y1080826D01*
G01Y1074055D02*
Y1075826D01*
G01Y1069055D02*
Y1070826D01*
G01X194215Y1067480D02*
Y1066299D01*
G01Y1064330D02*
Y1063149D01*
G01X193477Y1066299D02*
Y1067480D01*
G01Y1063149D02*
Y1064330D01*
G01X191020Y1139153D02*
Y1140728D01*
G01Y1134153D02*
Y1135728D01*
G01Y1129153D02*
Y1130728D01*
G01Y1124153D02*
Y1125728D01*
G01Y1119153D02*
Y1120728D01*
G01Y1114153D02*
Y1115728D01*
G01Y1109153D02*
Y1110728D01*
G01Y1104153D02*
Y1105728D01*
G01Y1099153D02*
Y1100728D01*
G01Y1094153D02*
Y1095728D01*
G01Y1089153D02*
Y1090728D01*
G01Y1084153D02*
Y1085728D01*
G01Y1079153D02*
Y1080728D01*
G01Y1074153D02*
Y1075728D01*
G01Y1070728D02*
Y1069153D01*
G01X190774Y1139153D02*
Y1140728D01*
G01Y1134153D02*
Y1135728D01*
G01Y1129153D02*
Y1130728D01*
G01Y1124153D02*
Y1125728D01*
G01Y1119153D02*
Y1120728D01*
G01Y1114153D02*
Y1115728D01*
G01Y1109153D02*
Y1110728D01*
G01Y1104153D02*
Y1105728D01*
G01Y1099153D02*
Y1100728D01*
G01Y1094153D02*
Y1095728D01*
G01Y1089153D02*
Y1090728D01*
G01Y1084153D02*
Y1085728D01*
G01Y1079153D02*
Y1080728D01*
G01Y1074153D02*
Y1075728D01*
G01Y1069153D02*
Y1070728D01*
G01X189667D02*
Y1069153D01*
G01Y1075728D02*
Y1074153D01*
G01Y1080728D02*
Y1079153D01*
G01Y1085728D02*
Y1084153D01*
G01Y1090728D02*
Y1089153D01*
G01Y1095728D02*
Y1094153D01*
G01Y1100728D02*
Y1099153D01*
G01Y1105728D02*
Y1104153D01*
G01Y1110728D02*
Y1109153D01*
G01Y1115728D02*
Y1114153D01*
G01Y1120728D02*
Y1119153D01*
G01Y1125728D02*
Y1124153D01*
G01Y1130728D02*
Y1129153D01*
G01Y1135728D02*
Y1134153D01*
G01Y1140728D02*
Y1139153D01*
G01X188661Y1063051D02*
Y1064429D01*
G01Y1067578D02*
Y1066200D01*
G01X187919Y1067480D02*
Y1066299D01*
G01Y1064330D02*
Y1063149D01*
G01X187421Y1066299D02*
Y1067480D01*
G01Y1063149D02*
Y1064330D01*
G01X185182Y1067480D02*
Y1066299D01*
G01Y1064330D02*
Y1063149D01*
G01X181102Y1160964D02*
X208268D01*
G01X197638Y1148681D02*
X200921D01*
G01X197638Y1146712D02*
X195669Y1148681D01*
G01X199606Y1157027D02*
X204331Y1152382D01*
G01Y1151278D02*
X199611Y1155920D01*
G01X200921Y1148681D02*
X204331Y1150649D01*
G01X196457Y1143759D02*
X197638Y1144941D01*
G01X204331Y1150649D02*
Y1152382D01*
G01X199606Y1155846D02*
Y1148681D01*
G01X181102Y1173917D02*
Y1160964D01*
G01Y1399429D02*
Y1386476D01*
G01X287401Y1484252D02*
G03I-15748J0D01*
G01X197638Y1473090D02*
X197441D01*
G01Y1471712D02*
X197638D01*
G01Y1469941D02*
X197441D01*
G01Y1468563D02*
X197638D01*
G01Y1466791D02*
X197441D01*
G01Y1465413D02*
X197638D01*
G01Y1463641D02*
X197441D01*
G01Y1462263D02*
X197638D01*
G01Y1460492D02*
X197441D01*
G01Y1459114D02*
X197638D01*
G01Y1457342D02*
X197441D01*
G01Y1455964D02*
X197638D01*
G01Y1454193D02*
X197441D01*
G01Y1452815D02*
X197638D01*
G01Y1411712D02*
X200921D01*
G01X208268Y1399429D02*
X181102D01*
G01X204331Y1409744D02*
X200921Y1411712D01*
G01X197638Y1451220D02*
X195669Y1453189D01*
G01X196457Y1416633D02*
X197638Y1415452D01*
G01X208268Y1399429D02*
Y1566476D01*
G01X204331Y1408011D02*
Y1409744D01*
G01X199606Y1411712D02*
Y1404547D01*
G01X197638Y1411712D02*
Y1554193D01*
G01X197441Y1471712D02*
Y1473090D01*
G01Y1454193D02*
Y1452815D01*
G01Y1460492D02*
Y1459114D01*
G01Y1457342D02*
Y1455964D01*
G01Y1463641D02*
Y1462263D01*
G01Y1469941D02*
Y1468563D01*
G01Y1466791D02*
Y1465413D01*
G01X196457Y1416633D02*
Y1549271D01*
G01X195877Y1444665D02*
Y1446240D01*
G01Y1439665D02*
Y1441240D01*
G01Y1434665D02*
Y1436240D01*
G01Y1429665D02*
Y1431240D01*
G01Y1424665D02*
Y1426240D01*
G01Y1419665D02*
Y1421240D01*
G01X195756Y1449665D02*
Y1451240D01*
G01X195669Y1475157D02*
Y1450748D01*
G01X195195Y1421240D02*
Y1419665D01*
G01Y1426240D02*
Y1424665D01*
G01Y1431240D02*
Y1429665D01*
G01Y1436240D02*
Y1434665D01*
G01Y1441240D02*
Y1439665D01*
G01Y1446240D02*
Y1444665D01*
G01X194767Y1451240D02*
Y1449665D01*
G01X194685Y1449567D02*
Y1451338D01*
G01Y1444567D02*
Y1446338D01*
G01Y1439567D02*
Y1441338D01*
G01Y1434567D02*
Y1436338D01*
G01Y1429567D02*
Y1431338D01*
G01Y1424567D02*
Y1426338D01*
G01Y1419567D02*
Y1421338D01*
G01X194215Y1454094D02*
Y1452913D01*
G01Y1457244D02*
Y1456063D01*
G01Y1460393D02*
Y1459212D01*
G01Y1463543D02*
Y1462362D01*
G01Y1466693D02*
Y1465511D01*
G01Y1469842D02*
Y1468661D01*
G01Y1472992D02*
Y1471811D01*
G01X193477D02*
Y1472992D01*
G01Y1465511D02*
Y1466693D01*
G01Y1468661D02*
Y1469842D01*
G01Y1462362D02*
Y1463543D01*
G01Y1456063D02*
Y1457244D01*
G01Y1459212D02*
Y1460393D01*
G01Y1452913D02*
Y1454094D01*
G01X191020Y1444665D02*
Y1446240D01*
G01Y1439665D02*
Y1441240D01*
G01Y1434665D02*
Y1436240D01*
G01Y1429665D02*
Y1431240D01*
G01Y1424665D02*
Y1426240D01*
G01Y1419665D02*
Y1421240D01*
G01Y1451240D02*
Y1449665D01*
G01X190774D02*
Y1451240D01*
G01Y1444665D02*
Y1446240D01*
G01Y1439665D02*
Y1441240D01*
G01Y1434665D02*
Y1436240D01*
G01Y1429665D02*
Y1431240D01*
G01Y1424665D02*
Y1426240D01*
G01Y1419665D02*
Y1421240D01*
G01X189667D02*
Y1419665D01*
G01Y1426240D02*
Y1424665D01*
G01Y1431240D02*
Y1429665D01*
G01Y1436240D02*
Y1434665D01*
G01Y1441240D02*
Y1439665D01*
G01Y1446240D02*
Y1444665D01*
G01Y1451240D02*
Y1449665D01*
G01X188661Y1465413D02*
Y1466791D01*
G01Y1468563D02*
Y1469941D01*
G01Y1462263D02*
Y1463641D01*
G01Y1455964D02*
Y1457342D01*
G01Y1459114D02*
Y1460492D01*
G01Y1454193D02*
Y1452815D01*
G01Y1473090D02*
Y1471712D01*
G01X187919Y1454094D02*
Y1452913D01*
G01Y1457244D02*
Y1456063D01*
G01Y1460393D02*
Y1459212D01*
G01Y1463543D02*
Y1462362D01*
G01Y1469842D02*
Y1468661D01*
G01Y1466693D02*
Y1465511D01*
G01Y1472992D02*
Y1471811D01*
G01X187421D02*
Y1472992D01*
G01Y1468661D02*
Y1469842D01*
G01Y1465511D02*
Y1466693D01*
G01Y1462362D02*
Y1463543D01*
G01Y1459212D02*
Y1460393D01*
G01Y1456063D02*
Y1457244D01*
G01Y1452913D02*
Y1454094D01*
G01X185182D02*
Y1452913D01*
G01Y1457244D02*
Y1456063D01*
G01Y1460393D02*
Y1459212D01*
G01Y1463543D02*
Y1462362D01*
G01Y1466693D02*
Y1465511D01*
G01Y1469842D02*
Y1468661D01*
G01Y1472992D02*
Y1471811D01*
G01X204331Y1408011D02*
X199606Y1403366D01*
G01X199611Y1404473D02*
X204331Y1409115D01*
G01X195669Y1411712D02*
X197638Y1413681D01*
G01X195669Y1472716D02*
X197638Y1474685D01*
G01Y1554193D02*
X200921D01*
G01X197638Y1552224D02*
X195669Y1554193D01*
G01X204331Y1556161D02*
Y1557893D01*
G01X199606Y1561358D02*
Y1554193D01*
G01X195877Y1544665D02*
Y1546240D01*
G01Y1539665D02*
Y1541240D01*
G01Y1534665D02*
Y1536240D01*
G01Y1529665D02*
Y1531240D01*
G01Y1524665D02*
Y1526240D01*
G01Y1519665D02*
Y1521240D01*
G01Y1514665D02*
Y1516240D01*
G01Y1509665D02*
Y1511240D01*
G01Y1504665D02*
Y1506240D01*
G01Y1499665D02*
Y1501240D01*
G01Y1494665D02*
Y1496240D01*
G01Y1489665D02*
Y1491240D01*
G01Y1484665D02*
Y1486240D01*
G01Y1479665D02*
Y1481240D01*
G01X195756Y1474665D02*
Y1476240D01*
G01X195195Y1481240D02*
Y1479665D01*
G01Y1486240D02*
Y1484665D01*
G01Y1491240D02*
Y1489665D01*
G01Y1496240D02*
Y1494665D01*
G01Y1501240D02*
Y1499665D01*
G01Y1506240D02*
Y1504665D01*
G01Y1511240D02*
Y1509665D01*
G01Y1516240D02*
Y1514665D01*
G01Y1521240D02*
Y1519665D01*
G01Y1526240D02*
Y1524665D01*
G01Y1531240D02*
Y1529665D01*
G01Y1536240D02*
Y1534665D01*
G01Y1541240D02*
Y1539665D01*
G01Y1546240D02*
Y1544665D01*
G01X194767Y1476240D02*
Y1474665D01*
G01X194685Y1544567D02*
Y1546338D01*
G01Y1539567D02*
Y1541338D01*
G01Y1534567D02*
Y1536338D01*
G01Y1529567D02*
Y1531338D01*
G01Y1524567D02*
Y1526338D01*
G01Y1519567D02*
Y1521338D01*
G01Y1514567D02*
Y1516338D01*
G01Y1509567D02*
Y1511338D01*
G01Y1504567D02*
Y1506338D01*
G01Y1499567D02*
Y1501338D01*
G01Y1494567D02*
Y1496338D01*
G01Y1489567D02*
Y1491338D01*
G01Y1484567D02*
Y1486338D01*
G01Y1479567D02*
Y1481338D01*
G01Y1474567D02*
Y1476338D01*
G01X191020Y1544665D02*
Y1546240D01*
G01Y1539665D02*
Y1541240D01*
G01Y1534665D02*
Y1536240D01*
G01Y1529665D02*
Y1531240D01*
G01Y1524665D02*
Y1526240D01*
G01Y1519665D02*
Y1521240D01*
G01Y1514665D02*
Y1516240D01*
G01Y1509665D02*
Y1511240D01*
G01Y1504665D02*
Y1506240D01*
G01Y1499665D02*
Y1501240D01*
G01Y1494665D02*
Y1496240D01*
G01Y1489665D02*
Y1491240D01*
G01Y1484665D02*
Y1486240D01*
G01Y1479665D02*
Y1481240D01*
G01Y1476240D02*
Y1474665D01*
G01X190774Y1544665D02*
Y1546240D01*
G01Y1539665D02*
Y1541240D01*
G01Y1534665D02*
Y1536240D01*
G01Y1529665D02*
Y1531240D01*
G01Y1524665D02*
Y1526240D01*
G01Y1519665D02*
Y1521240D01*
G01Y1514665D02*
Y1516240D01*
G01Y1509665D02*
Y1511240D01*
G01Y1504665D02*
Y1506240D01*
G01Y1499665D02*
Y1501240D01*
G01Y1494665D02*
Y1496240D01*
G01Y1489665D02*
Y1491240D01*
G01Y1484665D02*
Y1486240D01*
G01Y1479665D02*
Y1481240D01*
G01Y1474665D02*
Y1476240D01*
G01X189667D02*
Y1474665D01*
G01Y1481240D02*
Y1479665D01*
G01Y1486240D02*
Y1484665D01*
G01Y1491240D02*
Y1489665D01*
G01Y1496240D02*
Y1494665D01*
G01Y1501240D02*
Y1499665D01*
G01Y1506240D02*
Y1504665D01*
G01Y1511240D02*
Y1509665D01*
G01Y1516240D02*
Y1514665D01*
G01Y1521240D02*
Y1519665D01*
G01Y1526240D02*
Y1524665D01*
G01Y1531240D02*
Y1529665D01*
G01Y1536240D02*
Y1534665D01*
G01Y1541240D02*
Y1539665D01*
G01Y1546240D02*
Y1544665D01*
G01X200921Y1554193D02*
X204331Y1556161D01*
G01X196457Y1549271D02*
X197638Y1550452D01*
G01X181102Y1566476D02*
X208268D01*
G01X199606Y1562539D02*
X204331Y1557893D01*
G01Y1556790D02*
X199611Y1561432D01*
G01X181102Y1579429D02*
Y1566476D01*
G01X208268Y1804941D02*
X181102D01*
G01X208268D02*
Y1971988D01*
G01X181102Y1804941D02*
Y1791988D01*
G01X287401Y1889764D02*
G03I-15748J0D01*
G01X197638Y1878602D02*
X197441D01*
G01Y1877224D02*
X197638D01*
G01Y1875452D02*
X197441D01*
G01Y1874074D02*
X197638D01*
G01Y1872303D02*
X197441D01*
G01Y1870925D02*
X197638D01*
G01Y1869153D02*
X197441D01*
G01Y1867775D02*
X197638D01*
G01Y1866004D02*
X197441D01*
G01Y1864626D02*
X197638D01*
G01Y1862854D02*
X197441D01*
G01Y1861476D02*
X197638D01*
G01Y1859704D02*
X197441D01*
G01Y1858326D02*
X197638D01*
G01Y1817224D02*
X200921D01*
G01X204331Y1815256D02*
X200921Y1817224D01*
G01X197638Y1856732D02*
X195669Y1858700D01*
G01X196457Y1822145D02*
X197638Y1820964D01*
G01X204331Y1813523D02*
Y1815256D01*
G01X199606Y1817224D02*
Y1810059D01*
G01X197638Y1817224D02*
Y1959704D01*
G01X197441Y1877224D02*
Y1878602D01*
G01Y1859704D02*
Y1858326D01*
G01Y1862854D02*
Y1861476D01*
G01Y1866004D02*
Y1864626D01*
G01Y1872303D02*
Y1870925D01*
G01Y1869153D02*
Y1867775D01*
G01Y1875452D02*
Y1874074D01*
G01X196457Y1822145D02*
Y1954783D01*
G01X195877Y1885177D02*
Y1886752D01*
G01Y1850177D02*
Y1851752D01*
G01Y1845177D02*
Y1846752D01*
G01Y1840177D02*
Y1841752D01*
G01Y1835177D02*
Y1836752D01*
G01Y1830177D02*
Y1831752D01*
G01Y1825177D02*
Y1826752D01*
G01X195756Y1880177D02*
Y1881752D01*
G01Y1855177D02*
Y1856752D01*
G01X195669Y1880669D02*
Y1856259D01*
G01X195195Y1826752D02*
Y1825177D01*
G01Y1831752D02*
Y1830177D01*
G01Y1836752D02*
Y1835177D01*
G01Y1841752D02*
Y1840177D01*
G01Y1846752D02*
Y1845177D01*
G01Y1851752D02*
Y1850177D01*
G01Y1886752D02*
Y1885177D01*
G01X194767Y1856752D02*
Y1855177D01*
G01Y1881752D02*
Y1880177D01*
G01X194685Y1885078D02*
Y1886850D01*
G01Y1880078D02*
Y1881850D01*
G01Y1855078D02*
Y1856850D01*
G01Y1850078D02*
Y1851850D01*
G01Y1845078D02*
Y1846850D01*
G01Y1840078D02*
Y1841850D01*
G01Y1835078D02*
Y1836850D01*
G01Y1830078D02*
Y1831850D01*
G01Y1825078D02*
Y1826850D01*
G01X194215Y1859606D02*
Y1858425D01*
G01Y1862756D02*
Y1861574D01*
G01Y1865905D02*
Y1864724D01*
G01Y1869055D02*
Y1867874D01*
G01Y1872204D02*
Y1871023D01*
G01Y1878504D02*
Y1877322D01*
G01Y1875354D02*
Y1874173D01*
G01X193477Y1877322D02*
Y1878504D01*
G01Y1874173D02*
Y1875354D01*
G01Y1871023D02*
Y1872204D01*
G01Y1864724D02*
Y1865905D01*
G01Y1867874D02*
Y1869055D01*
G01Y1861574D02*
Y1862756D01*
G01Y1858425D02*
Y1859606D01*
G01X191020Y1885177D02*
Y1886752D01*
G01Y1850177D02*
Y1851752D01*
G01Y1845177D02*
Y1846752D01*
G01Y1840177D02*
Y1841752D01*
G01Y1835177D02*
Y1836752D01*
G01Y1830177D02*
Y1831752D01*
G01Y1825177D02*
Y1826752D01*
G01Y1856752D02*
Y1855177D01*
G01Y1881752D02*
Y1880177D01*
G01X190774Y1885177D02*
Y1886752D01*
G01Y1880177D02*
Y1881752D01*
G01Y1855177D02*
Y1856752D01*
G01Y1850177D02*
Y1851752D01*
G01Y1845177D02*
Y1846752D01*
G01Y1840177D02*
Y1841752D01*
G01Y1835177D02*
Y1836752D01*
G01Y1830177D02*
Y1831752D01*
G01Y1825177D02*
Y1826752D01*
G01X189667D02*
Y1825177D01*
G01Y1831752D02*
Y1830177D01*
G01Y1836752D02*
Y1835177D01*
G01Y1841752D02*
Y1840177D01*
G01Y1846752D02*
Y1845177D01*
G01Y1851752D02*
Y1850177D01*
G01Y1856752D02*
Y1855177D01*
G01Y1881752D02*
Y1880177D01*
G01Y1886752D02*
Y1885177D01*
G01X188661Y1874074D02*
Y1875452D01*
G01Y1867775D02*
Y1869153D01*
G01Y1870925D02*
Y1872303D01*
G01Y1864626D02*
Y1866004D01*
G01Y1861476D02*
Y1862854D01*
G01Y1859704D02*
Y1858326D01*
G01Y1878602D02*
Y1877224D01*
G01X187919Y1859606D02*
Y1858425D01*
G01Y1862756D02*
Y1861574D01*
G01Y1865905D02*
Y1864724D01*
G01Y1869055D02*
Y1867874D01*
G01Y1872204D02*
Y1871023D01*
G01Y1875354D02*
Y1874173D01*
G01Y1878504D02*
Y1877322D01*
G01X187421D02*
Y1878504D01*
G01Y1874173D02*
Y1875354D01*
G01Y1871023D02*
Y1872204D01*
G01Y1867874D02*
Y1869055D01*
G01Y1864724D02*
Y1865905D01*
G01Y1861574D02*
Y1862756D01*
G01Y1858425D02*
Y1859606D01*
G01X185182D02*
Y1858425D01*
G01Y1862756D02*
Y1861574D01*
G01Y1865905D02*
Y1864724D01*
G01Y1869055D02*
Y1867874D01*
G01Y1872204D02*
Y1871023D01*
G01Y1878504D02*
Y1877322D01*
G01Y1875354D02*
Y1874173D01*
G01X204331Y1813523D02*
X199606Y1808878D01*
G01X199611Y1809985D02*
X204331Y1814627D01*
G01X195669Y1817224D02*
X197638Y1819193D01*
G01X195669Y1878228D02*
X197638Y1880196D01*
G01Y1959704D02*
X200921D01*
G01X199606Y1968051D02*
X204331Y1963405D01*
G01Y1962302D02*
X199611Y1966943D01*
G01X197638Y1957736D02*
X195669Y1959704D01*
G01X204331Y1961673D02*
Y1963405D01*
G01X199606Y1966870D02*
Y1959704D01*
G01X195877Y1950177D02*
Y1951752D01*
G01Y1945177D02*
Y1946752D01*
G01Y1940177D02*
Y1941752D01*
G01Y1935177D02*
Y1936752D01*
G01Y1930177D02*
Y1931752D01*
G01Y1925177D02*
Y1926752D01*
G01Y1920177D02*
Y1921752D01*
G01Y1915177D02*
Y1916752D01*
G01Y1910177D02*
Y1911752D01*
G01Y1905177D02*
Y1906752D01*
G01Y1900177D02*
Y1901752D01*
G01Y1895177D02*
Y1896752D01*
G01Y1890177D02*
Y1891752D01*
G01X195195D02*
Y1890177D01*
G01Y1896752D02*
Y1895177D01*
G01Y1901752D02*
Y1900177D01*
G01Y1906752D02*
Y1905177D01*
G01Y1911752D02*
Y1910177D01*
G01Y1916752D02*
Y1915177D01*
G01Y1921752D02*
Y1920177D01*
G01Y1926752D02*
Y1925177D01*
G01Y1931752D02*
Y1930177D01*
G01Y1936752D02*
Y1935177D01*
G01Y1941752D02*
Y1940177D01*
G01Y1946752D02*
Y1945177D01*
G01Y1951752D02*
Y1950177D01*
G01X194685Y1950078D02*
Y1951850D01*
G01Y1945078D02*
Y1946850D01*
G01Y1940078D02*
Y1941850D01*
G01Y1935078D02*
Y1936850D01*
G01Y1930078D02*
Y1931850D01*
G01Y1925078D02*
Y1926850D01*
G01Y1920078D02*
Y1921850D01*
G01Y1915078D02*
Y1916850D01*
G01Y1910078D02*
Y1911850D01*
G01Y1905078D02*
Y1906850D01*
G01Y1900078D02*
Y1901850D01*
G01Y1895078D02*
Y1896850D01*
G01Y1890078D02*
Y1891850D01*
G01X191020Y1950177D02*
Y1951752D01*
G01Y1945177D02*
Y1946752D01*
G01Y1940177D02*
Y1941752D01*
G01Y1935177D02*
Y1936752D01*
G01Y1930177D02*
Y1931752D01*
G01Y1925177D02*
Y1926752D01*
G01Y1920177D02*
Y1921752D01*
G01Y1915177D02*
Y1916752D01*
G01Y1910177D02*
Y1911752D01*
G01Y1905177D02*
Y1906752D01*
G01Y1900177D02*
Y1901752D01*
G01Y1895177D02*
Y1896752D01*
G01Y1890177D02*
Y1891752D01*
G01X190774Y1950177D02*
Y1951752D01*
G01Y1945177D02*
Y1946752D01*
G01Y1940177D02*
Y1941752D01*
G01Y1935177D02*
Y1936752D01*
G01Y1930177D02*
Y1931752D01*
G01Y1925177D02*
Y1926752D01*
G01Y1920177D02*
Y1921752D01*
G01Y1915177D02*
Y1916752D01*
G01Y1910177D02*
Y1911752D01*
G01Y1905177D02*
Y1906752D01*
G01Y1900177D02*
Y1901752D01*
G01Y1895177D02*
Y1896752D01*
G01Y1890177D02*
Y1891752D01*
G01X189667D02*
Y1890177D01*
G01Y1896752D02*
Y1895177D01*
G01Y1901752D02*
Y1900177D01*
G01Y1906752D02*
Y1905177D01*
G01Y1911752D02*
Y1910177D01*
G01Y1916752D02*
Y1915177D01*
G01Y1921752D02*
Y1920177D01*
G01Y1926752D02*
Y1925177D01*
G01Y1931752D02*
Y1930177D01*
G01Y1936752D02*
Y1935177D01*
G01Y1941752D02*
Y1940177D01*
G01Y1946752D02*
Y1945177D01*
G01Y1951752D02*
Y1950177D01*
G01X196457Y1954783D02*
X197638Y1955964D01*
G01X200921Y1959704D02*
X204331Y1961673D01*
G01X181102Y1971988D02*
X208268D01*
G01X181102Y1984941D02*
Y1971988D01*
G01X215456Y2125381D02*
X216311Y2124430D01*
X217309Y2123860D01*
X218593Y2123670D01*
X219877Y2124050D01*
X220875Y2124810D01*
X221588Y2126141D01*
X221730Y2127662D01*
X221445Y2129183D01*
X220732Y2130134D01*
X219734Y2130894D01*
X218736Y2131084D01*
X217737Y2130894D01*
X216454Y2130134D01*
X216882Y2135077D01*
X220732D01*
G01X327937Y-38936D02*
Y-57873D01*
G01X278641Y267717D02*
G03I-6988J0D01*
G01Y673228D02*
G03I-6988J0D01*
G01Y1078740D02*
G03I-6988J0D01*
G01Y1484252D02*
G03I-6988J0D01*
G01Y1889764D02*
G03I-6988J0D01*
G01X327937Y2138820D02*
Y2119883D01*
G01X435553Y-49333D02*
X436551Y-48002D01*
X437406Y-47242D01*
X438547Y-46862D01*
X439546Y-47242D01*
X440258Y-48002D01*
X440829Y-49143D01*
X440971Y-50474D01*
X440829Y-51615D01*
X440258Y-52755D01*
X439403Y-53706D01*
X438405Y-54086D01*
X437264Y-53706D01*
X436266Y-52565D01*
X435695Y-50854D01*
X435553Y-48953D01*
X435838Y-46482D01*
X436266Y-45150D01*
X436978Y-43820D01*
X437977Y-42869D01*
X438975Y-42679D01*
X439973Y-43059D01*
X440686Y-44010D01*
G01X499158Y2031979D02*
X499756Y2031047D01*
X500555Y2030515D01*
X501453Y2030382D01*
X502252Y2030515D01*
X503050Y2031180D01*
X503549Y2031979D01*
X503649Y2032777D01*
X503450Y2033709D01*
X502751Y2034374D01*
X502052Y2034641D01*
X501154D01*
G01X502052D02*
X502651Y2035040D01*
X503150Y2035705D01*
X503350Y2036504D01*
X503150Y2037302D01*
X502651Y2037968D01*
X501753Y2038367D01*
X500854Y2038234D01*
X499956Y2037701D01*
G01X509338Y2038367D02*
X508540Y2038101D01*
X507941Y2037435D01*
X507542Y2036637D01*
X507242Y2035572D01*
X507143Y2034374D01*
X507242Y2033177D01*
X507542Y2032112D01*
X507941Y2031313D01*
X508540Y2030648D01*
X509338Y2030382D01*
X510137Y2030648D01*
X510736Y2031313D01*
X511135Y2032112D01*
X511435Y2033177D01*
X511534Y2034374D01*
X511435Y2035572D01*
X511135Y2036637D01*
X510736Y2037435D01*
X510137Y2038101D01*
X509338Y2038367D01*
G01X515427Y2037036D02*
X516026Y2037835D01*
X516725Y2038234D01*
X517523Y2038367D01*
X518521Y2038101D01*
X519220Y2037435D01*
X519420Y2036637D01*
X519320Y2035838D01*
X518920Y2035173D01*
X516924Y2033842D01*
X516026Y2032911D01*
X515427Y2031579D01*
X515227Y2030382D01*
X519420D01*
G01X525308Y2030116D02*
X525109Y2030249D01*
Y2030515D01*
X525308Y2030648D01*
X525508Y2030515D01*
Y2030249D01*
X525308Y2030116D01*
G01X531098Y2031579D02*
X531696Y2030914D01*
X532395Y2030515D01*
X533293Y2030382D01*
X534192Y2030648D01*
X534890Y2031180D01*
X535390Y2032112D01*
X535489Y2033177D01*
X535290Y2034241D01*
X534791Y2034907D01*
X534092Y2035439D01*
X533393Y2035572D01*
X532695Y2035439D01*
X531796Y2034907D01*
X532096Y2038367D01*
X534791D01*
G01X541278D02*
X540480Y2038101D01*
X539881Y2037435D01*
X539482Y2036637D01*
X539182Y2035572D01*
X539083Y2034374D01*
X539182Y2033177D01*
X539482Y2032112D01*
X539881Y2031313D01*
X540480Y2030648D01*
X541278Y2030382D01*
X542077Y2030648D01*
X542676Y2031313D01*
X543075Y2032112D01*
X543375Y2033177D01*
X543474Y2034374D01*
X543375Y2035572D01*
X543075Y2036637D01*
X542676Y2037435D01*
X542077Y2038101D01*
X541278Y2038367D01*
G01X435553Y2128423D02*
X436551Y2129754D01*
X437406Y2130514D01*
X438547Y2130894D01*
X439546Y2130514D01*
X440258Y2129754D01*
X440829Y2128613D01*
X440971Y2127282D01*
X440829Y2126141D01*
X440258Y2125001D01*
X439403Y2124050D01*
X438405Y2123670D01*
X437264Y2124050D01*
X436266Y2125191D01*
X435695Y2126902D01*
X435553Y2128803D01*
X435838Y2131274D01*
X436266Y2132606D01*
X436978Y2133936D01*
X437977Y2134887D01*
X438975Y2135077D01*
X439973Y2134697D01*
X440686Y2133746D01*
G01X547606Y-38936D02*
Y-57873D01*
G01X535458Y2034319D02*
X1111495D01*
G01X547606Y2138820D02*
Y2119883D01*
G01X657647Y-54086D02*
X657932Y-51615D01*
X658360Y-49523D01*
X658930Y-47622D01*
X659643Y-45531D01*
X660784Y-42679D01*
X655080D01*
G01X657647Y2123670D02*
X657932Y2126141D01*
X658360Y2128233D01*
X658930Y2130134D01*
X659643Y2132225D01*
X660784Y2135077D01*
X655080D01*
G01X767275Y-38936D02*
Y-57873D01*
G01X806692Y3937D02*
X866180D01*
G01X806692D02*
Y267087D01*
G01X839408Y42520D02*
X829566D01*
G01D02*
Y43750D01*
G01D02*
X833545D01*
G01Y49491D02*
X829566D01*
G01Y50722D02*
X839408D01*
G01X832707Y58309D02*
X831032D01*
G01X839408Y59539D02*
X831242D01*
G01X829566Y60769D02*
X839408D01*
G01X831869Y62615D02*
X831032Y62820D01*
G01Y58309D02*
X829566Y59539D01*
G01X831242D02*
X832707Y58309D01*
G01X831032Y62820D02*
X830194Y63640D01*
G01X834382Y52362D02*
X832288Y56258D01*
G01X829566Y49491D02*
Y50722D01*
G01Y59539D02*
Y60769D01*
G01X831869Y63640D02*
Y62615D01*
G01X832288Y56258D02*
X832917Y56669D01*
G01X831242Y64050D02*
X831869Y63640D01*
G01X830823Y64665D02*
X831242Y64050D01*
G01X830194Y63640D02*
X829775Y64460D01*
G01X830613Y65691D02*
X830823Y64665D01*
G01X829775Y64460D02*
X829566Y65896D01*
G01D02*
Y66716D01*
G01X830613Y66511D02*
Y65691D01*
G01X830823Y67536D02*
X830613Y66511D01*
G01X839408Y43750D02*
Y42520D01*
G01X834801Y43750D02*
X839408D01*
G01Y49491D02*
X834801D01*
G01X839408Y62410D02*
X838362D01*
G01X835849Y56669D02*
X836477Y56258D01*
G01X838362Y62410D02*
X833126Y68151D01*
G01X832917Y56669D02*
X834382Y53798D01*
G01X833545Y43750D02*
Y49491D01*
G01X834801D02*
Y43750D01*
G01X839408Y69792D02*
Y62410D01*
G01Y60769D02*
Y59539D01*
G01Y50722D02*
Y49491D01*
G01X834382Y53798D02*
X835849Y56669D01*
G01X836477Y56258D02*
X834382Y52362D01*
G01X833755Y69176D02*
X838362Y64050D01*
G01D02*
Y69792D01*
G01X831032Y69587D02*
X831869Y69792D01*
G01X832288Y68561D02*
X831869D01*
G01Y69792D02*
X832288D01*
G01D02*
X833126Y69587D01*
G01Y68151D02*
X832288Y68561D01*
G01X829566Y66716D02*
X829775Y67946D01*
G01D02*
X830194Y68767D01*
G01X831242Y68151D02*
X830823Y67536D01*
G01X830194Y68767D02*
X831032Y69587D01*
G01X831869Y68561D02*
X831242Y68151D01*
G01X838362Y69792D02*
X839408D01*
G01Y71432D02*
X832707D01*
G01X834173Y72457D02*
X839408D01*
G01X832707D02*
X833336D01*
G01X839408Y74713D02*
X834382D01*
G01Y75738D02*
X839408D01*
G01Y77994D02*
X834382D01*
G01Y79019D02*
X839408D01*
G01Y80659D02*
X832707D01*
G01X834173Y81685D02*
X839408D01*
G01X832707D02*
X833336D01*
G01X833964Y75943D02*
X834382Y75738D01*
G01X833126Y69587D02*
X833755Y69176D01*
G01X833336Y72457D02*
X832917Y72867D01*
G01X833755D02*
X834173Y72457D01*
G01X833545Y75533D02*
X832917Y76148D01*
G01X833755D02*
X833964Y75943D01*
G01X833336Y81685D02*
X832917Y82095D01*
G01X833755D02*
X834173Y81685D01*
G01X833545Y76558D02*
X833755Y76148D01*
G01X832917Y72867D02*
X832707Y73483D01*
G01X833545D02*
X833755Y72867D01*
G01X832917Y76148D02*
X832707Y76763D01*
G01X832917Y82095D02*
X832707Y82710D01*
G01X833545D02*
X833755Y82095D01*
G01X832707Y73483D02*
Y74303D01*
G01Y71432D02*
Y72457D01*
G01Y76763D02*
Y77584D01*
G01Y82710D02*
Y83530D01*
G01Y80659D02*
Y81685D01*
G01X833545Y83120D02*
Y82710D01*
G01Y77174D02*
Y76558D01*
G01Y73893D02*
Y73483D01*
G01X839408Y81685D02*
Y80659D01*
G01Y79019D02*
Y77994D01*
G01Y75738D02*
Y74713D01*
G01Y72457D02*
Y71432D01*
G01X832707Y83530D02*
X832917Y84145D01*
G01X832707Y77584D02*
X832917Y78199D01*
G01X832707Y74303D02*
X832917Y74918D01*
G01X833755Y83530D02*
X833545Y83120D01*
G01X833755Y77584D02*
X833545Y77174D01*
G01X833755Y74303D02*
X833545Y73893D01*
G01X833964Y83735D02*
X833755Y83530D01*
G01X832917Y78199D02*
X833336Y78609D01*
G01X833964Y77789D02*
X833755Y77584D01*
G01X832917Y74918D02*
X833545Y75533D01*
G01X833964Y74508D02*
X833755Y74303D01*
G01X834382Y77994D02*
X833964Y77789D01*
G01X834382Y74713D02*
X833964Y74508D01*
G01X833336Y78609D02*
X834382Y79019D01*
G01X839408Y83940D02*
X834382D01*
G01Y84966D02*
X839408D01*
G01Y87221D02*
X834382D01*
G01Y88246D02*
X839408D01*
G01X833964Y85170D02*
X834382Y84966D01*
G01X833545Y84761D02*
X832917Y85376D01*
G01X833755D02*
X833964Y85170D01*
G01X833545Y85786D02*
X833755Y85376D01*
G01X832917D02*
X832707Y85991D01*
G01D02*
Y86811D01*
G01X833545Y86401D02*
Y85786D01*
G01X839408Y88246D02*
Y87221D01*
G01Y84966D02*
Y83940D01*
G01X832707Y86811D02*
X832917Y87426D01*
G01X833755Y86811D02*
X833545Y86401D01*
G01X832917Y87426D02*
X833336Y87836D01*
G01X833964Y87016D02*
X833755Y86811D01*
G01X832917Y84145D02*
X833545Y84761D01*
G01X834382Y87221D02*
X833964Y87016D01*
G01X834382Y83940D02*
X833964Y83735D01*
G01X833336Y87836D02*
X834382Y88246D01*
G01X839212Y171752D02*
X819133D01*
G01X833503Y175689D02*
X832519D01*
G01X830944D02*
X829960D01*
G01X828385D02*
X827401D01*
G01X825826D02*
X824842D01*
G01X833503Y177576D02*
X832519D01*
G01X830944D02*
X829960D01*
G01X828385D02*
X827401D01*
G01X825826D02*
X824842D01*
G01X833503Y177657D02*
X832519D01*
G01X828385D02*
X827401D01*
G01X830944D02*
X829960D01*
G01X825826D02*
X824842D01*
G01X833503Y179052D02*
X832519D01*
G01X830944D02*
X829960D01*
G01X828385D02*
X827401D01*
G01X825826D02*
X824842D01*
G01X833503Y179134D02*
X832519D01*
G01X828385D02*
X827401D01*
G01X830944D02*
X829960D01*
G01X825826D02*
X824842D01*
G01X823070Y179331D02*
X835275D01*
G01X819133Y198327D02*
Y171752D01*
G01X823070Y190748D02*
Y179331D01*
G01X824842Y175689D02*
Y179331D01*
G01X825826Y175689D02*
Y179331D01*
G01X827401Y175689D02*
Y179331D01*
G01X828385Y175689D02*
Y179331D01*
G01X829960Y175689D02*
Y179331D01*
G01X830944Y175689D02*
Y179331D01*
G01X832519Y175689D02*
Y179331D01*
G01X835275Y190748D02*
X823070D01*
G01X833503Y190945D02*
X832519D01*
G01X828385D02*
X827401D01*
G01X830944D02*
X829960D01*
G01X825826D02*
X824842D01*
G01X833503Y191026D02*
X832519D01*
G01X828385D02*
X827401D01*
G01X830944D02*
X829960D01*
G01X825826D02*
X824842D01*
G01X833503Y192421D02*
X832519D01*
G01X828385D02*
X827401D01*
G01X830944D02*
X829960D01*
G01X825826D02*
X824842D01*
G01X833503Y192503D02*
X832519D01*
G01X828385D02*
X827401D01*
G01X830944D02*
X829960D01*
G01X825826D02*
X824842D01*
G01X833503Y194390D02*
X832519D01*
G01X830944D02*
X829960D01*
G01X828385D02*
X827401D01*
G01X825826D02*
X824842D01*
G01X839212Y198327D02*
X819133D01*
G01X824842Y190748D02*
Y194390D01*
G01X825826Y190748D02*
Y194390D01*
G01X827401Y190748D02*
Y194390D01*
G01X828385Y190748D02*
Y194390D01*
G01X829960Y190748D02*
Y194390D01*
G01X830944Y190748D02*
Y194390D01*
G01X832519Y190748D02*
Y194390D01*
G01X833700Y188976D02*
G03I-591J0D01*
G01X833503Y175689D02*
Y179331D01*
G01X835275D02*
Y190748D01*
G01X839212Y171752D02*
Y198327D01*
G01X833503Y192028D02*
X833306D01*
G01X833700D02*
X833503D01*
G01X833306Y192077D02*
X833503D01*
G01D02*
X833633D01*
G01X833574Y192126D02*
X833641D01*
G01X833633Y192077D02*
X833574Y192126D01*
G01X833641D02*
X833700Y192077D01*
G01X833306Y192028D02*
Y192077D01*
G01X833503Y190748D02*
Y194390D01*
G01X833700Y192077D02*
Y192028D01*
G01X866180Y267087D02*
X806692D01*
G01X838542Y1736850D02*
Y1705354D01*
G01D02*
X870038D01*
G01X819133Y1820374D02*
Y1793799D01*
G01X823070Y1812795D02*
Y1801378D01*
G01X824842Y1797736D02*
Y1801378D01*
G01X825826Y1797736D02*
Y1801378D01*
G01X827401Y1797736D02*
Y1801378D01*
G01X828385Y1797736D02*
Y1801378D01*
G01X829960Y1797736D02*
Y1801378D01*
G01X830944Y1797736D02*
Y1801378D01*
G01X832519Y1797736D02*
Y1801378D01*
G01X839212Y1793799D02*
X819133D01*
G01X833503Y1797736D02*
X832519D01*
G01X830944D02*
X829960D01*
G01X828385D02*
X827401D01*
G01X825826D02*
X824842D01*
G01X833503Y1799623D02*
X832519D01*
G01X830944D02*
X829960D01*
G01X828385D02*
X827401D01*
G01X825826D02*
X824842D01*
G01X833503Y1799705D02*
X832519D01*
G01X828385D02*
X827401D01*
G01X830944D02*
X829960D01*
G01X825826D02*
X824842D01*
G01X833503Y1801100D02*
X832519D01*
G01X830944D02*
X829960D01*
G01X828385D02*
X827401D01*
G01X825826D02*
X824842D01*
G01X833503Y1801181D02*
X832519D01*
G01X828385D02*
X827401D01*
G01X830944D02*
X829960D01*
G01X825826D02*
X824842D01*
G01X823070Y1801378D02*
X835275D01*
G01X870038Y1736850D02*
X838542D01*
G01X833503Y1797736D02*
Y1801378D01*
G01X835275D02*
Y1812795D01*
G01X839212Y1793799D02*
Y1820374D01*
G01X833700Y1811024D02*
G03I-591J0D01*
G01X824842Y1812795D02*
Y1816437D01*
G01X825826Y1812795D02*
Y1816437D01*
G01X827401Y1812795D02*
Y1816437D01*
G01X828385Y1812795D02*
Y1816437D01*
G01X829960Y1812795D02*
Y1816437D01*
G01X830944Y1812795D02*
Y1816437D01*
G01X832519Y1812795D02*
Y1816437D01*
G01X835275Y1812795D02*
X823070D01*
G01X833503Y1812992D02*
X832519D01*
G01X828385D02*
X827401D01*
G01X830944D02*
X829960D01*
G01X825826D02*
X824842D01*
G01X833503Y1813074D02*
X832519D01*
G01X828385D02*
X827401D01*
G01X830944D02*
X829960D01*
G01X825826D02*
X824842D01*
G01X833503Y1814469D02*
X832519D01*
G01X828385D02*
X827401D01*
G01X830944D02*
X829960D01*
G01X825826D02*
X824842D01*
G01X833503Y1814550D02*
X832519D01*
G01X828385D02*
X827401D01*
G01X830944D02*
X829960D01*
G01X825826D02*
X824842D01*
G01X833503Y1816437D02*
X832519D01*
G01X830944D02*
X829960D01*
G01X828385D02*
X827401D01*
G01X825826D02*
X824842D01*
G01X839212Y1820374D02*
X819133D01*
G01X833306Y1814075D02*
Y1814124D01*
G01X833503Y1812795D02*
Y1816437D01*
G01X833700Y1814124D02*
Y1814075D01*
G01X833503D02*
X833306D01*
G01X833700D02*
X833503D01*
G01X833306Y1814124D02*
X833503D01*
G01D02*
X833633D01*
G01X833574Y1814173D02*
X833641D01*
G01X833633Y1814124D02*
X833574Y1814173D01*
G01X833641D02*
X833700Y1814124D01*
G01X767275Y2138820D02*
Y2119883D01*
G01X877601Y-54086D02*
X878599Y-53896D01*
X879740Y-53326D01*
X880453Y-52375D01*
X880738Y-51044D01*
X880453Y-49714D01*
X879597Y-48573D01*
X878314Y-48002D01*
X876888D01*
X876032Y-47622D01*
X875319Y-46672D01*
X875034Y-45341D01*
X875462Y-44010D01*
X876460Y-43059D01*
X877601Y-42679D01*
X878742Y-43059D01*
X879740Y-44010D01*
X880168Y-45341D01*
X879883Y-46672D01*
X879170Y-47622D01*
X878314Y-48002D01*
X876888D01*
X875605Y-48573D01*
X874749Y-49714D01*
X874464Y-51044D01*
X874749Y-52375D01*
X875462Y-53326D01*
X876603Y-53896D01*
X877601Y-54086D01*
G01X866180Y35433D02*
Y3937D01*
G01X909920Y35433D02*
X866180D01*
G01X909920Y162087D02*
Y35433D01*
G01X866180Y162087D02*
X892519D01*
G01X866180D02*
Y267087D01*
G01X892519Y159488D02*
X898818D01*
G01X894093Y159783D02*
X892519D01*
G01D02*
X890944D01*
G01Y161752D02*
X892519D01*
G01D02*
X894093D01*
G01X892519Y162087D02*
X898818D01*
G01X890944Y162343D02*
X892519D01*
G01D02*
X894093D01*
G01X890944Y164311D02*
Y162343D01*
G01Y159783D02*
Y161752D01*
G01X892519Y162835D02*
Y161260D01*
G01Y160079D02*
Y159488D01*
G01Y160079D02*
G03Y161260I0J591D01*
G01Y162835D02*
G03Y164016I0J591D01*
G01X894093Y164311D02*
X892519D01*
G01D02*
X890944D01*
G01X892519Y164606D02*
X898818D01*
G01X892519D02*
Y164016D01*
G01X897243Y159783D02*
X898818D01*
G01D02*
X900393D01*
G01X898818Y161752D02*
X897243D01*
G01X900393D02*
X898818D01*
G01Y162087D02*
X909920D01*
G01X898818Y162343D02*
X897243D01*
G01X900393D02*
X898818D01*
G01X898807Y163087D02*
X898714D01*
G01Y163835D02*
X898807D01*
G01X893503Y164606D02*
Y159488D01*
G01X893700D02*
Y164606D01*
G01X894093Y161752D02*
Y159783D01*
G01Y162343D02*
Y164311D01*
G01X897243Y161752D02*
Y159783D01*
G01Y162343D02*
Y164311D01*
G01X897637Y159488D02*
Y164606D01*
G01X897834D02*
Y159488D01*
G01X898714Y163087D02*
Y163835D01*
G01X898807D02*
Y163214D01*
G01X898818Y159488D02*
Y160079D01*
G01Y161260D02*
Y162835D01*
G01X898901Y163326D02*
Y163198D01*
G01X900393Y164311D02*
Y162343D01*
G01Y159783D02*
Y161752D01*
G01X898807Y163214D02*
X898901Y163326D01*
G01Y163198D02*
X898807Y163087D01*
G01X898818Y161260D02*
G03Y160079I0J-591D01*
G01Y164016D02*
G03Y162835I0J-590D01*
G01X897243Y164311D02*
X898818D01*
G01D02*
X900393D01*
G01X898818Y164016D02*
Y164606D01*
G01X886343Y195747D02*
X886417Y195748D01*
G01X886492Y187480D02*
X886417D01*
G01X888976Y191614D02*
G03I-2558J0D01*
G01X889764D02*
G03I-3346J0D01*
G01X889921D02*
G03I-3503J0D01*
G01X899409Y179803D02*
G03I-3740J0D01*
G01X886492Y187481D02*
G03X886417Y195748I-73J4133D01*
G01X886343Y195747D02*
G03X886417Y187480I73J-4133D01*
G01X878811Y203248D02*
X878911Y203280D01*
G01X885039Y203031D02*
X881890Y201850D01*
G01X885039Y208031D02*
X881890Y206850D01*
G01X885039Y213031D02*
X881890Y211850D01*
G01X885039Y218031D02*
X881890Y216850D01*
G01X885039Y223031D02*
X881890Y221850D01*
G01X877872Y204101D02*
X878007Y204166D01*
G01X878040Y203969D02*
X877939Y203904D01*
G01X885039Y228031D02*
X881890Y226850D01*
G01X885039Y233031D02*
X881890Y231850D01*
G01X878978Y204429D02*
X879213Y204626D01*
G01X878945D02*
X878710Y204429D01*
G01X879025Y203130D02*
X878978Y203083D01*
G01X879112Y203215D02*
X879025Y203130D01*
G01X877739Y203969D02*
X877872Y204101D01*
G01X878911Y203280D02*
X878978Y203379D01*
G01X877939Y203904D02*
X877872Y203806D01*
G01X879179Y203346D02*
X879112Y203215D01*
G01X877671Y203838D02*
X877739Y203969D01*
G01X878978Y203379D02*
X879012Y203477D01*
G01X879213D02*
X879179Y203346D01*
G01X877872Y203806D02*
X877839Y203674D01*
G01X877638D02*
X877671Y203838D01*
G01X919366Y228130D02*
Y229704D01*
G01Y223130D02*
Y224704D01*
G01Y218130D02*
Y219704D01*
G01Y213130D02*
Y214704D01*
G01Y208130D02*
Y209704D01*
G01Y203130D02*
Y204704D01*
G01X919121Y228130D02*
Y229704D01*
G01Y223130D02*
Y224704D01*
G01Y218130D02*
Y219704D01*
G01Y213130D02*
Y214704D01*
G01Y208130D02*
Y209704D01*
G01Y203130D02*
Y204704D01*
G01X918014D02*
Y203130D01*
G01Y209704D02*
Y208130D01*
G01Y214704D02*
Y213130D01*
G01Y219704D02*
Y218130D01*
G01Y224704D02*
Y223130D01*
G01Y229704D02*
Y228130D01*
G01X909449Y182893D02*
Y169941D01*
G01X905512Y186830D02*
Y346004D01*
G01Y173878D02*
Y186830D01*
G01X905315Y179015D02*
Y180590D01*
G01X899961D02*
Y179015D01*
G01X898622Y180590D02*
Y180787D01*
G01Y178819D02*
Y179015D01*
G01Y180590D02*
Y179015D01*
G01X898425Y180590D02*
Y179015D01*
G01X897638Y332736D02*
Y200098D01*
G01X896850Y180590D02*
Y179015D01*
G01X896358Y200098D02*
Y332736D01*
G01X894980D02*
Y200098D01*
G01X894488Y186830D02*
Y195177D01*
G01Y180590D02*
Y179015D01*
G01X893701Y198326D02*
Y236378D01*
G01X892913Y179015D02*
Y180590D01*
G01X892717D02*
Y180787D01*
G01Y179015D02*
Y180590D01*
G01Y179015D02*
Y178819D01*
G01X891378Y179015D02*
Y180590D01*
G01X889764Y229704D02*
Y229803D01*
G01Y228031D02*
Y228130D01*
G01D02*
Y229704D01*
G01Y224704D02*
Y224803D01*
G01Y223031D02*
Y223130D01*
G01D02*
Y224704D01*
G01Y219704D02*
Y219803D01*
G01Y218031D02*
Y218130D01*
G01D02*
Y219704D01*
G01Y214704D02*
Y214803D01*
G01Y213031D02*
Y213130D01*
G01D02*
Y214704D01*
G01Y209704D02*
Y209803D01*
G01Y208031D02*
Y208130D01*
G01D02*
Y209704D01*
G01Y204704D02*
Y204803D01*
G01Y203031D02*
Y203130D01*
G01D02*
Y204704D01*
G01X886811Y227795D02*
Y225039D01*
G01X886024Y180590D02*
Y179015D01*
G01X885827Y173878D02*
Y186830D01*
G01X884134Y228130D02*
Y229704D01*
G01Y223130D02*
Y224704D01*
G01Y218130D02*
Y219704D01*
G01Y213130D02*
Y214704D01*
G01Y208130D02*
Y209704D01*
G01Y203130D02*
Y204704D01*
G01X882559Y228130D02*
Y229704D01*
G01Y223130D02*
Y224704D01*
G01Y218130D02*
Y219704D01*
G01Y213130D02*
Y214704D01*
G01Y208130D02*
Y209704D01*
G01Y203130D02*
Y204704D01*
G01X881890Y230984D02*
Y231850D01*
G01Y225984D02*
Y226850D01*
G01Y220984D02*
Y221850D01*
G01Y215984D02*
Y216850D01*
G01Y210984D02*
Y211850D01*
G01Y205984D02*
Y206850D01*
G01Y200098D02*
Y201850D01*
G01Y169941D02*
Y182893D01*
G01X881772Y204704D02*
Y203130D01*
G01Y209704D02*
Y208130D01*
G01Y214704D02*
Y213130D01*
G01Y219704D02*
Y218130D01*
G01Y224704D02*
Y223130D01*
G01Y229704D02*
Y228130D01*
G01X881378Y204704D02*
Y203130D01*
G01Y209704D02*
Y208130D01*
G01Y214704D02*
Y213130D01*
G01Y219704D02*
Y218130D01*
G01Y224704D02*
Y223130D01*
G01Y229704D02*
Y228130D01*
G01X879213Y204704D02*
Y204822D01*
G01Y204626D02*
Y204704D01*
G01Y203641D02*
Y203477D01*
G01X879012D02*
Y203674D01*
G01X878844Y203871D02*
Y204068D01*
G01X878543Y203674D02*
Y203477D01*
G01X878342D02*
Y203674D01*
G01X878074Y203130D02*
Y202952D01*
G01Y203149D02*
Y203130D01*
G01X877839Y203674D02*
Y203412D01*
G01X877638D02*
Y203674D01*
G01Y204822D02*
Y204704D01*
G01D02*
Y204626D01*
G01X876457Y228130D02*
Y229704D01*
G01Y223130D02*
Y224704D01*
G01Y218130D02*
Y219704D01*
G01Y213130D02*
Y214704D01*
G01Y208130D02*
Y209704D01*
G01Y203130D02*
Y204704D01*
G01X874016Y186830D02*
Y200098D01*
G01X870079Y349941D02*
Y182893D01*
G01X879179Y203806D02*
X879213Y203641D01*
G01X878509Y203838D02*
X878543Y203674D01*
G01X877671Y203248D02*
X877638Y203412D01*
G01X878342Y203674D02*
X878308Y203806D01*
G01X878375Y203346D02*
X878342Y203477D01*
G01X877839Y203412D02*
X877872Y203280D01*
G01X879012Y203674D02*
X878978Y203772D01*
G01X878543Y203477D02*
X878576Y203379D01*
G01X878442Y203969D02*
X878509Y203838D01*
G01X878442Y203215D02*
X878375Y203346D01*
G01X877772Y203083D02*
X877744Y203130D01*
G01D02*
X877671Y203248D01*
G01X878308Y203806D02*
X878241Y203904D01*
G01X878576Y203379D02*
X878643Y203280D01*
G01X879079Y203937D02*
X879179Y203806D01*
G01X878978Y203772D02*
X878911Y203838D01*
G01X878308Y204101D02*
X878442Y203969D01*
G01X878529Y203130D02*
X878442Y203215D01*
G01X878576Y203083D02*
X878529Y203130D01*
G01X877872Y203280D02*
X877973Y203182D01*
G01X878945Y204035D02*
X879079Y203937D01*
G01X878241Y203904D02*
X878141Y203969D01*
G01X877939Y202985D02*
X877772Y203083D01*
G01X878911Y203838D02*
X878844Y203871D01*
G01X878174Y204166D02*
X878308Y204101D01*
G01X881890Y230984D02*
X885039Y229803D01*
G01X881890Y225984D02*
X885039Y224803D01*
G01X881890Y220984D02*
X885039Y219803D01*
G01X881890Y215984D02*
X885039Y214803D01*
G01X881890Y210984D02*
X885039Y209803D01*
G01X881890Y205984D02*
X885039Y204803D01*
G01X878844Y204068D02*
X878945Y204035D01*
G01X878643Y203280D02*
X878744Y203248D01*
G01X877973Y203182D02*
X878074Y203149D01*
G01X878710Y203051D02*
X878576Y203083D01*
G01X878074Y202952D02*
X877939Y202985D01*
G01X889764Y229803D02*
X885039D01*
G01X925984D02*
X893701D01*
G01Y229704D02*
X924223D01*
G01X876457D02*
X893701D01*
G01Y228130D02*
X924223D01*
G01X893701D02*
X876457D01*
G01X893701Y228031D02*
X925984D01*
G01X885039D02*
X889764D01*
G01X886811Y227795D02*
X893701D01*
G01Y225039D02*
X886811D01*
G01X893701Y224803D02*
X925984D01*
G01X889764D02*
X885039D01*
G01X893701Y224704D02*
X924223D01*
G01X876457D02*
X893701D01*
G01Y223130D02*
X924223D01*
G01X893701D02*
X876457D01*
G01X893701Y223031D02*
X925984D01*
G01X885039D02*
X889764D01*
G01X893701Y219803D02*
X925984D01*
G01X889764D02*
X885039D01*
G01X893701Y219704D02*
X924223D01*
G01X876457D02*
X893701D01*
G01Y218130D02*
X924223D01*
G01X893701D02*
X876457D01*
G01X893701Y218031D02*
X925984D01*
G01X885039D02*
X889764D01*
G01X893701Y214803D02*
X925984D01*
G01X889764D02*
X885039D01*
G01X893701Y214704D02*
X924223D01*
G01X876457D02*
X893701D01*
G01Y213130D02*
X924223D01*
G01X893701D02*
X876457D01*
G01X893701Y213031D02*
X925984D01*
G01X885039D02*
X889764D01*
G01X893701Y209803D02*
X925984D01*
G01X889764D02*
X885039D01*
G01X893701Y209704D02*
X924223D01*
G01X876457D02*
X893701D01*
G01Y208130D02*
X924223D01*
G01X893701D02*
X876457D01*
G01X893701Y208031D02*
X925984D01*
G01X885039D02*
X889764D01*
G01X879213Y204822D02*
X877638D01*
G01X893701Y204803D02*
X925984D01*
G01X889764D02*
X885039D01*
G01X893701Y204704D02*
X924223D01*
G01X876457D02*
X893701D01*
G01X877638Y204626D02*
X878945D01*
G01X878710Y204429D02*
X878978D01*
G01X878007Y204166D02*
X878174D01*
G01X878141Y203969D02*
X878040D01*
G01X878744Y203248D02*
X878811D01*
G01X893701Y203130D02*
X924223D01*
G01X893701D02*
X876457D01*
G01X878844Y203051D02*
X878710D01*
G01X893701Y203031D02*
X925984D01*
G01X885039D02*
X889764D01*
G01X896358Y200098D02*
X924803D01*
G01X893701D02*
X894980D01*
G01X893701D02*
X874016D01*
G01Y198326D02*
X893701D01*
G01X874016Y195177D02*
X924016D01*
G01X894488Y192224D02*
X905512D01*
G01X874016D02*
X894488D01*
G01X927953Y188011D02*
X894488D01*
G01X927953Y186830D02*
X874016D01*
G01X885827Y184862D02*
X905512D01*
G01X870079Y182893D02*
X881890D01*
G01X936614D02*
X909449D01*
G01X905512Y181771D02*
X885827D01*
G01Y180787D02*
X905512D01*
G01X905315Y180590D02*
X886024D01*
G01X905315Y179015D02*
X886024D01*
G01X905512Y178819D02*
X885827D01*
G01Y177834D02*
X905512D01*
G01X885827Y175846D02*
X905512D01*
G01X885827Y173878D02*
X905512D01*
G01X909449Y169941D02*
X881890D01*
G01X878978Y203083D02*
X878844Y203051D01*
G01X891339Y236279D02*
X888976Y235590D01*
G01X891339Y239429D02*
X888976Y238740D01*
G01X891339Y242578D02*
X888976Y241889D01*
G01X891339Y245728D02*
X888976Y245039D01*
G01X891339Y248878D02*
X888976Y248189D01*
G01X891339Y252027D02*
X888976Y251338D01*
G01X891339Y255177D02*
X888976Y254488D01*
G01X886094Y235964D02*
X886195Y235997D01*
G01X878683Y258976D02*
X878783Y259009D01*
G01X878750Y259206D02*
X878649Y259173D01*
G01X885039Y263031D02*
X881890Y261850D01*
G01X885039Y268031D02*
X881890Y266850D01*
G01X885039Y278031D02*
X881890Y276850D01*
G01X885039Y283031D02*
X881890Y281850D01*
G01X885039Y288031D02*
X881890Y286850D01*
G01X885039Y293031D02*
X881890Y291850D01*
G01X885039Y298031D02*
X881890Y296850D01*
G01X885039Y303031D02*
X881890Y301850D01*
G01X885039Y308031D02*
X881890Y306850D01*
G01X886262Y237244D02*
X886094Y237178D01*
G01X885591Y237211D02*
X885424Y237145D01*
G01X885156Y238261D02*
X885324Y238326D01*
G01X885156Y236817D02*
X885290Y236883D01*
G01X885859Y238228D02*
X885994Y238294D01*
G01X885324Y236686D02*
X885223Y236620D01*
G01X886195Y237408D02*
X886094Y237342D01*
G01X885927Y238064D02*
X886027Y238130D01*
G01X885558Y237408D02*
X885424Y237309D01*
G01X885189Y238064D02*
X885324Y238162D01*
G01X878649Y259173D02*
X878515Y259074D01*
G01X879018Y259468D02*
X879252Y259665D01*
G01X878984D02*
X878750Y259468D01*
G01X886396Y235932D02*
X886262Y235800D01*
G01X886362Y237342D02*
X886262Y237244D01*
G01X885022Y236686D02*
X885156Y236817D01*
G01X885759Y238130D02*
X885859Y238228D01*
G01X885056Y238162D02*
X885156Y238261D01*
G01X878615Y258910D02*
X878683Y258976D01*
G01X886295Y237539D02*
X886195Y237408D01*
G01X885692Y237342D02*
X885591Y237211D01*
G01X885826Y237933D02*
X885927Y238064D01*
G01X878515Y259074D02*
X878415Y258943D01*
G01X886195Y235997D02*
X886262Y236095D01*
G01X885223Y236620D02*
X885156Y236522D01*
G01X886463Y237506D02*
X886362Y237342D01*
G01X884955Y237998D02*
X885056Y238162D01*
G01X886463Y236063D02*
X886396Y235932D01*
G01X885726Y237408D02*
X885692Y237342D01*
G01X885625Y237539D02*
X885558Y237408D01*
G01X885726Y238064D02*
X885759Y238130D01*
G01X884955Y236555D02*
X885022Y236686D01*
G01X885122Y237933D02*
X885189Y238064D01*
G01X886262Y236095D02*
X886295Y236194D01*
G01X878582Y258812D02*
X878615Y258910D01*
G01X886496Y236194D02*
X886463Y236063D01*
G01X886329Y237670D02*
X886300Y237559D01*
G01D02*
X886295Y237539D01*
G01X885793Y237802D02*
X885826Y237933D01*
G01X885659Y237670D02*
X885630Y237559D01*
G01D02*
X885625Y237539D01*
G01X885156Y236522D02*
X885122Y236391D01*
G01X885089Y237802D02*
X885122Y237933D01*
G01X886496Y237670D02*
X886473Y237559D01*
G01D02*
X886463Y237506D01*
G01X884921Y236391D02*
X884955Y236555D01*
G01X884921Y237834D02*
X884955Y237998D01*
G01X878415Y258943D02*
X878381Y258779D01*
G01X922561Y237559D02*
Y236378D01*
G01Y240708D02*
Y239527D01*
G01Y243858D02*
Y242677D01*
G01Y247008D02*
Y245826D01*
G01Y250157D02*
Y248976D01*
G01Y253307D02*
Y252126D01*
G01Y256456D02*
Y255275D01*
G01X921823D02*
Y256456D01*
G01Y248976D02*
Y250157D01*
G01Y252126D02*
Y253307D01*
G01Y245826D02*
Y247008D01*
G01Y239527D02*
Y240708D01*
G01Y242677D02*
Y243858D01*
G01Y236378D02*
Y237559D01*
G01X919366Y313130D02*
Y314704D01*
G01Y308130D02*
Y309704D01*
G01Y303130D02*
Y304704D01*
G01Y298130D02*
Y299704D01*
G01Y293130D02*
Y294704D01*
G01Y288130D02*
Y289704D01*
G01Y283130D02*
Y284704D01*
G01Y278130D02*
Y279704D01*
G01Y273130D02*
Y274704D01*
G01Y268130D02*
Y269704D01*
G01Y263130D02*
Y264704D01*
G01Y234704D02*
Y233130D01*
G01Y259704D02*
Y258130D01*
G01X919121Y313130D02*
Y314704D01*
G01Y308130D02*
Y309704D01*
G01Y303130D02*
Y304704D01*
G01Y298130D02*
Y299704D01*
G01Y293130D02*
Y294704D01*
G01Y288130D02*
Y289704D01*
G01Y283130D02*
Y284704D01*
G01Y278130D02*
Y279704D01*
G01Y273130D02*
Y274704D01*
G01Y268130D02*
Y269704D01*
G01Y263130D02*
Y264704D01*
G01Y258130D02*
Y259704D01*
G01Y233130D02*
Y234704D01*
G01X918014D02*
Y233130D01*
G01Y259704D02*
Y258130D01*
G01Y264704D02*
Y263130D01*
G01Y269704D02*
Y268130D01*
G01Y274704D02*
Y273130D01*
G01Y279704D02*
Y278130D01*
G01Y284704D02*
Y283130D01*
G01Y289704D02*
Y288130D01*
G01Y294704D02*
Y293130D01*
G01Y299704D02*
Y298130D01*
G01Y304704D02*
Y303130D01*
G01Y309704D02*
Y308130D01*
G01Y314704D02*
Y313130D01*
G01X917008Y248878D02*
Y250256D01*
G01Y252027D02*
Y253405D01*
G01Y245728D02*
Y247106D01*
G01Y239429D02*
Y240807D01*
G01Y242578D02*
Y243956D01*
G01Y237657D02*
Y236279D01*
G01Y256555D02*
Y255177D01*
G01X916265Y237559D02*
Y236378D01*
G01Y240708D02*
Y239527D01*
G01Y243858D02*
Y242677D01*
G01Y247008D02*
Y245826D01*
G01Y253307D02*
Y252126D01*
G01Y250157D02*
Y248976D01*
G01Y256456D02*
Y255275D01*
G01X915767D02*
Y256456D01*
G01Y252126D02*
Y253307D01*
G01Y248976D02*
Y250157D01*
G01Y245826D02*
Y247008D01*
G01Y242677D02*
Y243858D01*
G01Y239527D02*
Y240708D01*
G01Y236378D02*
Y237559D01*
G01X913528D02*
Y236378D01*
G01Y240708D02*
Y239527D01*
G01Y243858D02*
Y242677D01*
G01Y247008D02*
Y245826D01*
G01Y250157D02*
Y248976D01*
G01Y253307D02*
Y252126D01*
G01Y256456D02*
Y255275D01*
G01X896457Y234212D02*
Y258622D01*
G01X894882Y311555D02*
Y316279D01*
G01Y271555D02*
Y276279D01*
G01X893701Y314704D02*
Y334508D01*
G01Y274704D02*
Y313130D01*
G01Y256456D02*
Y273130D01*
G01Y239527D02*
Y237559D01*
G01D02*
Y236378D01*
G01Y242677D02*
Y240708D01*
G01D02*
Y239527D01*
G01Y243858D02*
Y242677D01*
G01Y245826D02*
Y243858D01*
G01Y248976D02*
Y247008D01*
G01D02*
Y245826D01*
G01Y252126D02*
Y250157D01*
G01D02*
Y248976D01*
G01Y253307D02*
Y252126D01*
G01Y255275D02*
Y253307D01*
G01Y256456D02*
Y255275D01*
G01Y274704D02*
Y273130D01*
G01Y314704D02*
Y313130D01*
G01X891811Y255275D02*
Y256456D01*
G01Y252126D02*
Y253307D01*
G01Y248976D02*
Y250157D01*
G01Y245826D02*
Y247008D01*
G01Y239527D02*
Y240708D01*
G01Y242677D02*
Y243858D01*
G01Y236378D02*
Y237559D01*
G01X891732Y314704D02*
Y314803D01*
G01Y313031D02*
Y313130D01*
G01D02*
Y314704D01*
G01Y274704D02*
Y274803D01*
G01Y273031D02*
Y273130D01*
G01D02*
Y274704D01*
G01X890236Y255275D02*
Y256456D01*
G01Y252126D02*
Y253307D01*
G01Y248976D02*
Y250157D01*
G01Y245826D02*
Y247008D01*
G01Y242677D02*
Y243858D01*
G01Y239527D02*
Y240708D01*
G01Y236378D02*
Y237559D01*
G01X889764Y309704D02*
Y309803D01*
G01Y308031D02*
Y308130D01*
G01D02*
Y309704D01*
G01Y304704D02*
Y304803D01*
G01Y303031D02*
Y303130D01*
G01D02*
Y304704D01*
G01Y299704D02*
Y299803D01*
G01Y298031D02*
Y298130D01*
G01D02*
Y299704D01*
G01Y294704D02*
Y294803D01*
G01Y293031D02*
Y293130D01*
G01D02*
Y294704D01*
G01Y289704D02*
Y289803D01*
G01Y288031D02*
Y288130D01*
G01D02*
Y289704D01*
G01Y284704D02*
Y284803D01*
G01Y283031D02*
Y283130D01*
G01D02*
Y284704D01*
G01Y279704D02*
Y279803D01*
G01Y278031D02*
Y278130D01*
G01D02*
Y279704D01*
G01Y269704D02*
Y269803D01*
G01Y268130D02*
Y269704D01*
G01Y268031D02*
Y268130D01*
G01Y264704D02*
Y264803D01*
G01Y263130D02*
Y264704D01*
G01Y263031D02*
Y263130D01*
G01Y259704D02*
Y259803D01*
G01Y258130D02*
Y259704D01*
G01Y258031D02*
Y258130D01*
G01Y234704D02*
Y234803D01*
G01Y233031D02*
Y233130D01*
G01D02*
Y234704D01*
G01X889449Y237559D02*
Y236378D01*
G01Y240708D02*
Y239527D01*
G01Y243858D02*
Y242677D01*
G01Y247008D02*
Y245826D01*
G01Y250157D02*
Y248976D01*
G01Y253307D02*
Y252126D01*
G01Y256456D02*
Y255275D01*
G01X889055Y237559D02*
Y236378D01*
G01Y240708D02*
Y239527D01*
G01Y243858D02*
Y242677D01*
G01Y247008D02*
Y245826D01*
G01Y253307D02*
Y252126D01*
G01Y250157D02*
Y248976D01*
G01Y256456D02*
Y255275D01*
G01X888976Y257244D02*
Y257441D01*
G01Y254094D02*
Y254488D01*
G01Y250945D02*
Y251338D01*
G01Y244645D02*
Y245039D01*
G01Y247795D02*
Y248189D01*
G01Y241496D02*
Y241889D01*
G01Y235393D02*
Y235590D01*
G01Y238346D02*
Y238740D01*
G01X886811Y262795D02*
Y260039D01*
G01Y287795D02*
Y285039D01*
G01Y312795D02*
Y310039D01*
G01X886496Y236358D02*
Y236194D01*
G01Y237802D02*
Y237670D01*
G01X886329Y237802D02*
Y237670D01*
G01X886295Y236194D02*
Y236378D01*
G01D02*
Y236391D01*
G01X886128Y236587D02*
Y236784D01*
G01X885826Y236378D02*
Y236194D01*
G01Y236391D02*
Y236378D01*
G01X885793Y237670D02*
Y237802D01*
G01X885659D02*
Y237670D01*
G01X885630Y257441D02*
Y258031D01*
G01Y234803D02*
Y235393D01*
G01X885625Y236194D02*
Y236378D01*
G01D02*
Y236391D01*
G01X885357Y235866D02*
Y235669D01*
G01X885122Y236378D02*
Y236128D01*
G01Y236391D02*
Y236378D01*
G01X885089Y237670D02*
Y237802D01*
G01X884921Y236128D02*
Y236378D01*
G01Y237637D02*
Y237834D01*
G01Y236378D02*
Y236391D01*
G01X884449Y255275D02*
Y256456D01*
G01Y248976D02*
Y250157D01*
G01Y252126D02*
Y253307D01*
G01Y245826D02*
Y247008D01*
G01Y239527D02*
Y240708D01*
G01Y242677D02*
Y243858D01*
G01Y236378D02*
Y237559D01*
G01X884134Y313130D02*
Y314704D01*
G01Y308130D02*
Y309704D01*
G01Y303130D02*
Y304704D01*
G01Y298130D02*
Y299704D01*
G01Y293130D02*
Y294704D01*
G01Y288130D02*
Y289704D01*
G01Y283130D02*
Y284704D01*
G01Y278130D02*
Y279704D01*
G01Y273130D02*
Y274704D01*
G01Y268130D02*
Y269704D01*
G01Y263130D02*
Y264704D01*
G01Y258130D02*
Y259704D01*
G01Y233130D02*
Y234704D01*
G01X882559Y313130D02*
Y314704D01*
G01Y308130D02*
Y309704D01*
G01Y303130D02*
Y304704D01*
G01Y298130D02*
Y299704D01*
G01Y293130D02*
Y294704D01*
G01Y288130D02*
Y289704D01*
G01Y283130D02*
Y284704D01*
G01Y278130D02*
Y279704D01*
G01Y273130D02*
Y274704D01*
G01Y268130D02*
Y269704D01*
G01Y263130D02*
Y264704D01*
G01Y258130D02*
Y259704D01*
G01Y233130D02*
Y234704D01*
G01X881890Y310984D02*
Y311850D01*
G01Y305984D02*
Y306850D01*
G01Y300984D02*
Y301850D01*
G01Y295984D02*
Y296850D01*
G01Y290984D02*
Y291850D01*
G01Y285984D02*
Y286850D01*
G01Y280984D02*
Y281850D01*
G01Y275984D02*
Y276850D01*
G01Y270984D02*
Y271850D01*
G01Y265984D02*
Y266850D01*
G01Y260984D02*
Y261850D01*
G01X881772Y234704D02*
Y233130D01*
G01Y259704D02*
Y258130D01*
G01Y264704D02*
Y263130D01*
G01Y269704D02*
Y268130D01*
G01Y274704D02*
Y273130D01*
G01Y279704D02*
Y278130D01*
G01Y284704D02*
Y283130D01*
G01Y289704D02*
Y288130D01*
G01Y294704D02*
Y293130D01*
G01Y299704D02*
Y298130D01*
G01Y304704D02*
Y303130D01*
G01Y309704D02*
Y308130D01*
G01Y314704D02*
Y313130D01*
G01X881378Y234704D02*
Y233130D01*
G01Y259704D02*
Y258130D01*
G01Y264704D02*
Y263130D01*
G01Y269704D02*
Y268130D01*
G01Y274704D02*
Y273130D01*
G01Y279704D02*
Y278130D01*
G01Y284704D02*
Y283130D01*
G01Y289704D02*
Y288130D01*
G01Y294704D02*
Y293130D01*
G01Y299704D02*
Y298130D01*
G01Y304704D02*
Y303130D01*
G01Y309704D02*
Y308130D01*
G01Y314704D02*
Y313130D01*
G01X879252Y259704D02*
Y259862D01*
G01Y259665D02*
Y259704D01*
G01Y257992D02*
Y258130D01*
G01D02*
Y258779D01*
G01X879085Y258812D02*
Y258189D01*
G01X878582D02*
Y258812D01*
G01X878381Y258779D02*
Y258189D01*
G01X877677Y258130D02*
Y257992D01*
G01Y258189D02*
Y258130D01*
G01Y259862D02*
Y259704D01*
G01D02*
Y259665D01*
G01X876457Y308130D02*
Y309704D01*
G01Y303130D02*
Y304704D01*
G01Y298130D02*
Y299704D01*
G01Y293130D02*
Y294704D01*
G01Y288130D02*
Y289704D01*
G01Y283130D02*
Y284704D01*
G01Y278130D02*
Y279704D01*
G01Y268130D02*
Y269704D01*
G01Y263130D02*
Y264704D01*
G01Y233130D02*
Y234704D01*
G01X875000Y313130D02*
Y314704D01*
G01Y273130D02*
Y274704D01*
G01Y258130D02*
Y259704D01*
G01X886463Y237965D02*
X886496Y237802D01*
G01X886492Y236378D02*
X886496Y236358D01*
G01X886463Y236522D02*
X886492Y236378D01*
G01X885793Y236555D02*
X885826Y236391D01*
G01X884937Y237559D02*
X884921Y237637D01*
G01X884955Y237473D02*
X884937Y237559D01*
G01X884955Y235964D02*
X884921Y236128D01*
G01X879252Y258779D02*
X879219Y258943D01*
G01X886295Y237933D02*
X886329Y237802D01*
G01X885821Y237559D02*
X885793Y237670D01*
G01X885826Y237539D02*
X885821Y237559D01*
G01X885625Y237933D02*
X885659Y237802D01*
G01X885625Y236391D02*
X885591Y236522D01*
G01X885659Y236063D02*
X885625Y236194D01*
G01X885117Y237559D02*
X885089Y237670D01*
G01X885122Y237539D02*
X885117Y237559D01*
G01X885122Y236128D02*
X885156Y235997D01*
G01X879051Y258910D02*
X879085Y258812D01*
G01X886295Y236391D02*
X886262Y236489D01*
G01X885826Y236194D02*
X885859Y236095D01*
G01X885692Y238130D02*
X885726Y238064D01*
G01X885558D02*
X885625Y237933D01*
G01X885759Y237342D02*
X885726Y237408D01*
G01Y236686D02*
X885793Y236555D01*
G01X885189Y237408D02*
X885122Y237539D01*
G01X885726Y235932D02*
X885659Y236063D01*
G01X886362Y238130D02*
X886463Y237965D01*
G01X885056Y237309D02*
X884955Y237473D01*
G01X885056Y235800D02*
X884955Y235964D01*
G01X885591Y236522D02*
X885524Y236620D01*
G01X885859Y236095D02*
X885927Y235997D01*
G01X879219Y258943D02*
X879118Y259074D01*
G01X886195Y238064D02*
X886295Y237933D01*
G01X885591Y238261D02*
X885692Y238130D01*
G01X885927Y237408D02*
X885826Y237539D01*
G01X886362Y236653D02*
X886463Y236522D01*
G01X878984Y258976D02*
X879051Y258910D01*
G01X886262Y238228D02*
X886362Y238130D01*
G01X885859Y237244D02*
X885759Y237342D01*
G01X886262Y236489D02*
X886195Y236555D01*
G01X885591Y236817D02*
X885726Y236686D01*
G01X885156Y237211D02*
X885056Y237309D01*
G01X885859Y235800D02*
X885726Y235932D01*
G01X885156Y235997D02*
X885256Y235898D01*
G01X879118Y259074D02*
X878984Y259173D01*
G01X885424Y238162D02*
X885558Y238064D01*
G01X886228Y236752D02*
X886362Y236653D01*
G01X885324Y237309D02*
X885189Y237408D01*
G01X886094Y238130D02*
X886195Y238064D01*
G01X886027Y237342D02*
X885927Y237408D01*
G01X885524Y236620D02*
X885424Y236686D01*
G01X885223Y235702D02*
X885056Y235800D01*
G01X885994Y237178D02*
X885859Y237244D01*
G01X886195Y236555D02*
X886128Y236587D01*
G01X885458Y236883D02*
X885591Y236817D01*
G01X881890Y310984D02*
X885039Y309803D01*
G01X881890Y305984D02*
X885039Y304803D01*
G01X886094Y238294D02*
X886262Y238228D01*
G01X885424Y238326D02*
X885591Y238261D01*
G01X885324Y237145D02*
X885156Y237211D01*
G01X881890Y300984D02*
X885039Y299803D01*
G01X881890Y295984D02*
X885039Y294803D01*
G01X881890Y290984D02*
X885039Y289803D01*
G01X881890Y285984D02*
X885039Y284803D01*
G01X881890Y280984D02*
X885039Y279803D01*
G01X881890Y270984D02*
X885039Y269803D01*
G01X881890Y265984D02*
X885039Y264803D01*
G01X881890Y260984D02*
X885039Y259803D01*
G01X878984Y259173D02*
X878884Y259206D01*
G01Y259009D02*
X878984Y258976D01*
G01X881890Y315984D02*
X887008Y314803D01*
G01X886128Y236784D02*
X886228Y236752D01*
G01X885927Y235997D02*
X886027Y235964D01*
G01X885256Y235898D02*
X885357Y235866D01*
G01X888976Y257244D02*
X891339Y256555D01*
G01X888976Y254094D02*
X891339Y253405D01*
G01X888976Y250945D02*
X891339Y250256D01*
G01X888976Y247795D02*
X891339Y247106D01*
G01X888976Y244645D02*
X891339Y243956D01*
G01X888976Y241496D02*
X891339Y240807D01*
G01X888976Y238346D02*
X891339Y237657D01*
G01X885994Y235767D02*
X885859Y235800D01*
G01X885357Y235669D02*
X885223Y235702D01*
G01X881890Y275984D02*
X887008Y274803D01*
G01X891732Y314803D02*
X887008D01*
G01X925984D02*
X894882D01*
G01Y314704D02*
X924223D01*
G01X875000D02*
X894882D01*
G01Y313130D02*
X924223D01*
G01X875000D02*
X894882D01*
G01Y313031D02*
X925984D01*
G01X887008D02*
X891732D01*
G01X886811Y312795D02*
X893701D01*
G01Y311555D02*
X894882D01*
G01X893701Y310039D02*
X886811D01*
G01X893701Y309803D02*
X925984D01*
G01X889764D02*
X885039D01*
G01X893701Y309704D02*
X924223D01*
G01X876457D02*
X893701D01*
G01Y308130D02*
X924223D01*
G01X893701D02*
X876457D01*
G01X893701Y308031D02*
X925984D01*
G01X885039D02*
X889764D01*
G01X893701Y304803D02*
X925984D01*
G01X889764D02*
X885039D01*
G01X893701Y304704D02*
X924223D01*
G01X876457D02*
X893701D01*
G01Y303130D02*
X924223D01*
G01X893701D02*
X876457D01*
G01X893701Y303031D02*
X925984D01*
G01X885039D02*
X889764D01*
G01X893701Y299803D02*
X925984D01*
G01X889764D02*
X885039D01*
G01X893701Y299704D02*
X924223D01*
G01X876457D02*
X893701D01*
G01Y298130D02*
X924223D01*
G01X893701D02*
X876457D01*
G01X893701Y298031D02*
X925984D01*
G01X885039D02*
X889764D01*
G01X893701Y294803D02*
X925984D01*
G01X889764D02*
X885039D01*
G01X893701Y294704D02*
X924223D01*
G01X876457D02*
X893701D01*
G01Y293130D02*
X924223D01*
G01X893701D02*
X876457D01*
G01X893701Y293031D02*
X925984D01*
G01X885039D02*
X889764D01*
G01X893701Y289803D02*
X925984D01*
G01X889764D02*
X885039D01*
G01X893701Y289704D02*
X924223D01*
G01X876457D02*
X893701D01*
G01Y288130D02*
X924223D01*
G01X893701D02*
X876457D01*
G01X893701Y288031D02*
X925984D01*
G01X885039D02*
X889764D01*
G01X886811Y287795D02*
X893701D01*
G01Y285039D02*
X886811D01*
G01X893701Y284803D02*
X925984D01*
G01X889764D02*
X885039D01*
G01X893701Y284704D02*
X924223D01*
G01X876457D02*
X893701D01*
G01Y283130D02*
X924223D01*
G01X893701D02*
X876457D01*
G01X893701Y283031D02*
X925984D01*
G01X885039D02*
X889764D01*
G01X893701Y279803D02*
X925984D01*
G01X889764D02*
X885039D01*
G01X893701Y279704D02*
X924223D01*
G01X876457D02*
X893701D01*
G01Y278130D02*
X924223D01*
G01X893701D02*
X876457D01*
G01X893701Y278031D02*
X925984D01*
G01X885039D02*
X889764D01*
G01X894882Y276279D02*
X893701D01*
G01X891732Y274803D02*
X887008D01*
G01X925984D02*
X894882D01*
G01Y274704D02*
X924223D01*
G01X875000D02*
X894882D01*
G01Y273130D02*
X924223D01*
G01X875000D02*
X894882D01*
G01Y273031D02*
X925984D01*
G01X887008D02*
X891732D01*
G01X893701Y271555D02*
X894882D01*
G01X893701Y269803D02*
X925984D01*
G01X889764D02*
X885039D01*
G01X893701Y269704D02*
X924223D01*
G01X876457D02*
X893701D01*
G01Y268130D02*
X924223D01*
G01X893701D02*
X876457D01*
G01X893701Y268031D02*
X925984D01*
G01X885039D02*
X889764D01*
G01X893701Y264803D02*
X925984D01*
G01X889764D02*
X885039D01*
G01X893701Y264704D02*
X924223D01*
G01X876457D02*
X893701D01*
G01Y263130D02*
X876457D01*
G01X924223D02*
X893701D01*
G01Y263031D02*
X925984D01*
G01X885039D02*
X889764D01*
G01X886811Y262795D02*
X893701D01*
G01Y260039D02*
X886811D01*
G01X879252Y259862D02*
X877677D01*
G01X893701Y259803D02*
X923032D01*
G01X889764D02*
X885039D01*
G01X893701Y259704D02*
X924102D01*
G01X875000D02*
X893701D01*
G01X877677Y259665D02*
X878984D01*
G01X878750Y259468D02*
X879018D01*
G01X878884Y259206D02*
X878750D01*
G01X878783Y259009D02*
X878884D01*
G01X893701Y258622D02*
X925984D01*
G01X879085Y258189D02*
X878582D01*
G01X878381D02*
X877677D01*
G01X893701Y258130D02*
X924102D01*
G01X875000D02*
X893701D01*
G01Y258031D02*
X923032D01*
G01X885630D02*
X889764D01*
G01X877677Y257992D02*
X879252D01*
G01X888976Y257441D02*
X885630D01*
G01X896457Y256555D02*
X925787D01*
G01X891339D02*
X893701D01*
G01X896457Y256456D02*
X922561D01*
G01X884449D02*
X896457D01*
G01X905512Y256181D02*
X924016D01*
G01X884449Y255275D02*
X896457D01*
G01X922561D02*
X896457D01*
G01Y255177D02*
X925787D01*
G01X891339D02*
X893701D01*
G01X896457Y253405D02*
X925787D01*
G01X891339D02*
X893701D01*
G01X896457Y253307D02*
X922561D01*
G01X884449D02*
X896457D01*
G01X884449Y252126D02*
X896457D01*
G01X922561D02*
X896457D01*
G01Y252027D02*
X925787D01*
G01X891339D02*
X893701D01*
G01X896457Y250256D02*
X925787D01*
G01X891339D02*
X893701D01*
G01X896457Y250157D02*
X922561D01*
G01X884449D02*
X896457D01*
G01X884449Y248976D02*
X896457D01*
G01X922561D02*
X896457D01*
G01Y248878D02*
X925787D01*
G01X891339D02*
X893701D01*
G01X896457Y247106D02*
X925787D01*
G01X891339D02*
X893701D01*
G01X896457Y247008D02*
X922561D01*
G01X884449D02*
X896457D01*
G01X884449Y245826D02*
X896457D01*
G01X922561D02*
X896457D01*
G01Y245728D02*
X925787D01*
G01X891339D02*
X893701D01*
G01X887008Y313031D02*
X881890Y311850D01*
G01X896457Y243956D02*
X925787D01*
G01X891339D02*
X893701D01*
G01X896457Y243858D02*
X922561D01*
G01X884449D02*
X896457D01*
G01X884449Y242677D02*
X896457D01*
G01X922561D02*
X896457D01*
G01Y242578D02*
X925787D01*
G01X891339D02*
X893701D01*
G01X896457Y240807D02*
X925787D01*
G01X891339D02*
X893701D01*
G01X896457Y240708D02*
X922561D01*
G01X884449D02*
X896457D01*
G01X884449Y239527D02*
X896457D01*
G01X922561D02*
X896457D01*
G01Y239429D02*
X925787D01*
G01X891339D02*
X893701D01*
G01X885324Y238326D02*
X885424D01*
G01X885994Y238294D02*
X886094D01*
G01X885324Y238162D02*
X885424D01*
G01X886027Y238130D02*
X886094D01*
G01X891339Y237657D02*
X893701D01*
G01X925787D02*
X896457D01*
G01Y237559D02*
X922561D01*
G01X884449D02*
X896457D01*
G01X886094Y237342D02*
X886027D01*
G01X885424Y237309D02*
X885324D01*
G01X886094Y237178D02*
X885994D01*
G01X885424Y237145D02*
X885324D01*
G01X885290Y236883D02*
X885458D01*
G01X885424Y236686D02*
X885324D01*
G01X924016Y236653D02*
X905512D01*
G01X884449Y236378D02*
X896457D01*
G01X922561D02*
X896457D01*
G01X891339Y236279D02*
X893701D01*
G01X925787D02*
X896457D01*
G01X886027Y235964D02*
X886094D01*
G01X886128Y235767D02*
X885994D01*
G01X885630Y235393D02*
X888976D01*
G01X889764Y234803D02*
X885630D01*
G01X923032D02*
X893701D01*
G01Y234704D02*
X924102D01*
G01X876457D02*
X893701D01*
G01Y234212D02*
X925984D01*
G01X893701Y233130D02*
X876457D01*
G01X924102D02*
X893701D01*
G01Y233031D02*
X923032D01*
G01X885039D02*
X889764D01*
G01X887008Y273031D02*
X881890Y271850D01*
G01X886262Y235800D02*
X886128Y235767D01*
G01X884400Y342795D02*
G03Y339645I2017J-1575D01*
G01X888435D02*
G03Y342795I-2017J1575D01*
G01X888788Y338858D02*
G03Y343582I-2371J2362D01*
G01X884047D02*
G03Y338858I2371J-2362D01*
G01X889921Y341220D02*
G03I-3503J0D01*
G01X899409Y353031D02*
G03I-3740J0D01*
G01X889095Y338070D02*
G03Y344370I-2677J3150D01*
G01X883740D02*
G03Y338070I2677J-3150D01*
G01X885039Y318031D02*
X881890Y316850D01*
G01X885039Y323031D02*
X881890Y321850D01*
G01X885039Y328031D02*
X881890Y326850D01*
G01X919366Y328130D02*
Y329704D01*
G01Y323130D02*
Y324704D01*
G01Y318130D02*
Y319704D01*
G01X919121Y328130D02*
Y329704D01*
G01Y323130D02*
Y324704D01*
G01Y318130D02*
Y319704D01*
G01X918014D02*
Y318130D01*
G01Y324704D02*
Y323130D01*
G01Y329704D02*
Y328130D01*
G01X909449Y362893D02*
Y349941D01*
G01X905512Y346004D02*
Y358956D01*
G01X905315Y352244D02*
Y353819D01*
G01X899961D02*
Y352244D01*
G01X898622Y353819D02*
Y354015D01*
G01Y352047D02*
Y352244D01*
G01Y353819D02*
Y352244D01*
G01X898425Y353819D02*
Y352244D01*
G01X896850Y353819D02*
Y352244D01*
G01X894488Y337657D02*
Y346004D01*
G01Y353819D02*
Y352244D01*
G01X892913D02*
Y353819D01*
G01X892717D02*
Y354015D01*
G01Y352244D02*
Y353819D01*
G01Y352244D02*
Y352047D01*
G01X891378Y352244D02*
Y353819D01*
G01X889764Y329704D02*
Y329803D01*
G01Y328130D02*
Y329704D01*
G01Y328031D02*
Y328130D01*
G01Y324704D02*
Y324803D01*
G01Y323130D02*
Y324704D01*
G01Y323031D02*
Y323130D01*
G01Y319704D02*
Y319803D01*
G01Y318130D02*
Y319704D01*
G01Y318031D02*
Y318130D01*
G01X886024Y353819D02*
Y352244D01*
G01X885827Y346004D02*
Y358956D01*
G01X884134Y328130D02*
Y329704D01*
G01Y323130D02*
Y324704D01*
G01Y318130D02*
Y319704D01*
G01X882559Y328130D02*
Y329704D01*
G01Y323130D02*
Y324704D01*
G01Y318130D02*
Y319704D01*
G01X881890Y349941D02*
Y362893D01*
G01Y330984D02*
Y332736D01*
G01Y325984D02*
Y326850D01*
G01Y320984D02*
Y321850D01*
G01Y315984D02*
Y316850D01*
G01X881772Y319704D02*
Y318130D01*
G01Y324704D02*
Y323130D01*
G01Y329704D02*
Y328130D01*
G01X881378Y319704D02*
Y318130D01*
G01Y324704D02*
Y323130D01*
G01Y329704D02*
Y328130D01*
G01X876457D02*
Y329704D01*
G01Y323130D02*
Y324704D01*
G01Y318130D02*
Y319704D01*
G01X874016Y332736D02*
Y346004D01*
G01X881890Y330984D02*
X885039Y329803D01*
G01X881890Y325984D02*
X885039Y324803D01*
G01X881890Y320984D02*
X885039Y319803D01*
G01X881890Y362893D02*
X909449D01*
G01X905512Y358956D02*
X885827D01*
G01X905512Y356988D02*
X885827D01*
G01X905512Y355000D02*
X885827D01*
G01Y354015D02*
X905512D01*
G01X905315Y353819D02*
X886024D01*
G01X905315Y352244D02*
X886024D01*
G01X905512Y352047D02*
X885827D01*
G01Y351063D02*
X905512D01*
G01X909449Y349941D02*
X936614D01*
G01X881890D02*
X870079D01*
G01X905512Y347972D02*
X885827D01*
G01X927953Y346004D02*
X874016D01*
G01X894488Y344822D02*
X927953D01*
G01X883740Y344370D02*
X889095D01*
G01X888788Y343582D02*
X884047D01*
G01X884400Y342795D02*
X888435D01*
G01X894488Y340610D02*
X874016D01*
G01X905512D02*
X894488D01*
G01X884400Y339645D02*
X888435D01*
G01X884047Y338858D02*
X888788D01*
G01X889095Y338070D02*
X883740D01*
G01X924016Y337657D02*
X874016D01*
G01X893701Y334508D02*
X874016D01*
G01Y332736D02*
X893701D01*
G01D02*
X894980D01*
G01X924803D02*
X896358D01*
G01X889764Y329803D02*
X885039D01*
G01X925984D02*
X893701D01*
G01Y329704D02*
X924223D01*
G01X876457D02*
X893701D01*
G01Y328130D02*
X924223D01*
G01X893701D02*
X876457D01*
G01X893701Y328031D02*
X925984D01*
G01X885039D02*
X889764D01*
G01X893701Y324803D02*
X925984D01*
G01X889764D02*
X885039D01*
G01X893701Y324704D02*
X924223D01*
G01X876457D02*
X893701D01*
G01Y323130D02*
X924223D01*
G01X893701D02*
X876457D01*
G01X893701Y323031D02*
X925984D01*
G01X885039D02*
X889764D01*
G01X893701Y319803D02*
X925984D01*
G01X889764D02*
X885039D01*
G01X893701Y319704D02*
X924223D01*
G01X876457D02*
X893701D01*
G01Y318130D02*
X924223D01*
G01X893701D02*
X876457D01*
G01X893701Y318031D02*
X925984D01*
G01X885039D02*
X889764D01*
G01X894882Y316279D02*
X893701D01*
G01X892519Y565000D02*
X898818D01*
G01X894093Y565295D02*
X892519D01*
G01D02*
X890944D01*
G01D02*
Y567264D01*
G01X892519Y565591D02*
Y565000D01*
G01Y565591D02*
G03Y566772I0J591D01*
G01X890944Y567264D02*
X892519D01*
G01D02*
X894093D01*
G01X890944Y567854D02*
X892519D01*
G01D02*
X894093D01*
G01Y569823D02*
X892519D01*
G01D02*
X890944D01*
G01X892519Y570118D02*
X898818D01*
G01X890944Y569823D02*
Y567854D01*
G01X892519Y570118D02*
Y569528D01*
G01Y568346D02*
Y566772D01*
G01Y568346D02*
G03Y569528I0J591D01*
G01X897243Y565295D02*
X898818D01*
G01D02*
X900393D01*
G01X893503Y570118D02*
Y565000D01*
G01X893700D02*
Y570118D01*
G01X894093Y567264D02*
Y565295D01*
G01X897243Y567264D02*
Y565295D01*
G01X897637Y565000D02*
Y570118D01*
G01X897834D02*
Y565000D01*
G01X898818D02*
Y565591D01*
G01X900393Y565295D02*
Y567264D01*
G01X898818Y566772D02*
G03Y565591I0J-591D01*
G01Y567264D02*
X897243D01*
G01X900393D02*
X898818D01*
G01Y567854D02*
X897243D01*
G01X900393D02*
X898818D01*
G01X898807Y568598D02*
X898714D01*
G01Y569346D02*
X898807D01*
G01X897243Y569823D02*
X898818D01*
G01D02*
X900393D01*
G01X894093Y567854D02*
Y569823D01*
G01X897243Y567854D02*
Y569823D01*
G01X898714Y568598D02*
Y569346D01*
G01X898807D02*
Y568726D01*
G01X898818Y566772D02*
Y568346D01*
G01Y569528D02*
Y570118D01*
G01X898901Y568837D02*
Y568710D01*
G01X900393Y569823D02*
Y567854D01*
G01X898807Y568726D02*
X898901Y568837D01*
G01Y568710D02*
X898807Y568598D01*
G01X898818Y569528D02*
G03Y568346I0J-591D01*
G01X886343Y601259D02*
X886417D01*
G01X886492Y592992D02*
X886417D01*
G01X899409Y585315D02*
G03I-3740J0D01*
G01X888976Y597126D02*
G03I-2558J0D01*
G01X889764D02*
G03I-3346J0D01*
G01X889921D02*
G03I-3503J0D01*
G01X886492Y592993D02*
G03X886417Y601259I-74J4133D01*
G01X886343D02*
G03X886417Y592992I73J-4133D01*
G01X878811Y608759D02*
X878911Y608792D01*
G01X885039Y608543D02*
X881890Y607362D01*
G01X885039Y613543D02*
X881890Y612362D01*
G01X885039Y618543D02*
X881890Y617362D01*
G01X885039Y623543D02*
X881890Y622362D01*
G01X885039Y628543D02*
X881890Y627362D01*
G01X885039Y633543D02*
X881890Y632362D01*
G01X877872Y609613D02*
X878007Y609678D01*
G01X885156Y642329D02*
X885290Y642395D01*
G01X885859Y643740D02*
X885994Y643806D01*
G01X878040Y609481D02*
X877939Y609416D01*
G01X885324Y642198D02*
X885223Y642132D01*
G01X886195Y642920D02*
X886094Y642854D01*
G01X885927Y643576D02*
X886027Y643641D01*
G01X885558Y642920D02*
X885424Y642821D01*
G01X885189Y643576D02*
X885324Y643674D01*
G01X878978Y609941D02*
X879213Y610137D01*
G01X878945D02*
X878710Y609941D01*
G01X879025Y608641D02*
X878978Y608595D01*
G01X879112Y608727D02*
X879025Y608641D01*
G01X877739Y609481D02*
X877872Y609613D01*
G01X886396Y641443D02*
X886262Y641312D01*
G01X886362Y642854D02*
X886262Y642756D01*
G01X885022Y642198D02*
X885156Y642329D01*
G01X885759Y643641D02*
X885859Y643740D01*
G01X885056Y643674D02*
X885156Y643772D01*
G01X886295Y643051D02*
X886195Y642920D01*
G01X885692Y642854D02*
X885591Y642723D01*
G01X885826Y643445D02*
X885927Y643576D01*
G01X878911Y608792D02*
X878978Y608891D01*
G01X877939Y609416D02*
X877872Y609317D01*
G01X886195Y641509D02*
X886262Y641607D01*
G01X885223Y642132D02*
X885156Y642034D01*
G01X886463Y643018D02*
X886362Y642854D01*
G01X884955Y643510D02*
X885056Y643674D01*
G01X879179Y608858D02*
X879112Y608727D01*
G01X877671Y609350D02*
X877739Y609481D01*
G01X886463Y641574D02*
X886396Y641443D01*
G01X885726Y642920D02*
X885692Y642854D01*
G01X885625Y643051D02*
X885558Y642920D01*
G01X885726Y643576D02*
X885759Y643641D01*
G01X884955Y642067D02*
X885022Y642198D01*
G01X885122Y643445D02*
X885189Y643576D01*
G01X891339Y641791D02*
X888976Y641102D01*
G01X891339Y644941D02*
X888976Y644252D01*
G01X886094Y641476D02*
X886195Y641509D01*
G01X885039Y638543D02*
X881890Y637362D01*
G01X886262Y642756D02*
X886094Y642690D01*
G01X885591Y642723D02*
X885424Y642657D01*
G01X885156Y643772D02*
X885324Y643838D01*
G01X878978Y608891D02*
X879012Y608989D01*
G01X886262Y641607D02*
X886295Y641706D01*
G01X879213Y608989D02*
X879179Y608858D01*
G01X886496Y641706D02*
X886463Y641574D01*
G01X877872Y609317D02*
X877839Y609186D01*
G01X886329Y643182D02*
X886300Y643070D01*
G01D02*
X886295Y643051D01*
G01X885793Y643313D02*
X885826Y643445D01*
G01X885659Y643182D02*
X885630Y643070D01*
G01D02*
X885625Y643051D01*
G01X885156Y642034D02*
X885122Y641902D01*
G01X885089Y643313D02*
X885122Y643445D01*
G01X886496Y643182D02*
X886473Y643070D01*
G01D02*
X886463Y643018D01*
G01X884921Y641902D02*
X884955Y642067D01*
G01X884921Y643346D02*
X884955Y643510D01*
G01X877638Y609186D02*
X877671Y609350D01*
G01X922561Y643070D02*
Y641889D01*
G01Y646220D02*
Y645039D01*
G01X921823Y641889D02*
Y643070D01*
G01Y645039D02*
Y646220D01*
G01X919366Y633641D02*
Y635216D01*
G01Y628641D02*
Y630216D01*
G01Y623641D02*
Y625216D01*
G01Y618641D02*
Y620216D01*
G01Y613641D02*
Y615216D01*
G01Y608641D02*
Y610216D01*
G01Y640216D02*
Y638641D01*
G01X919121D02*
Y640216D01*
G01Y633641D02*
Y635216D01*
G01Y628641D02*
Y630216D01*
G01Y623641D02*
Y625216D01*
G01Y618641D02*
Y620216D01*
G01Y613641D02*
Y615216D01*
G01Y608641D02*
Y610216D01*
G01X918014D02*
Y608641D01*
G01Y615216D02*
Y613641D01*
G01Y620216D02*
Y618641D01*
G01Y625216D02*
Y623641D01*
G01Y630216D02*
Y628641D01*
G01Y635216D02*
Y633641D01*
G01Y640216D02*
Y638641D01*
G01X917008Y644941D02*
Y646319D01*
G01Y643169D02*
Y641791D01*
G01X916265Y643070D02*
Y641889D01*
G01Y646220D02*
Y645039D01*
G01X915767Y641889D02*
Y643070D01*
G01Y645039D02*
Y646220D01*
G01X913528Y643070D02*
Y641889D01*
G01Y646220D02*
Y645039D01*
G01X909449Y588405D02*
Y575452D01*
G01X905512Y592342D02*
Y751515D01*
G01Y579389D02*
Y592342D01*
G01X905315Y584527D02*
Y586102D01*
G01X899961D02*
Y584527D01*
G01X898622Y586102D02*
Y586299D01*
G01Y584330D02*
Y584527D01*
G01Y586102D02*
Y584527D01*
G01X898425Y586102D02*
Y584527D01*
G01X897638Y738248D02*
Y605610D01*
G01X896850Y586102D02*
Y584527D01*
G01X896457Y639724D02*
Y664133D01*
G01X896358Y605610D02*
Y738248D01*
G01X894980D02*
Y605610D01*
G01X894488Y592342D02*
Y600689D01*
G01Y586102D02*
Y584527D01*
G01X893701Y603838D02*
Y641889D01*
G01Y645039D02*
Y643070D01*
G01D02*
Y641889D01*
G01Y646220D02*
Y645039D01*
G01X892913Y584527D02*
Y586102D01*
G01X892717D02*
Y586299D01*
G01Y584527D02*
Y586102D01*
G01Y584527D02*
Y584330D01*
G01X891811Y641889D02*
Y643070D01*
G01Y645039D02*
Y646220D01*
G01X891378Y584527D02*
Y586102D01*
G01X890236Y641889D02*
Y643070D01*
G01Y645039D02*
Y646220D01*
G01X889764Y640216D02*
Y640315D01*
G01Y638543D02*
Y638641D01*
G01D02*
Y640216D01*
G01Y635216D02*
Y635315D01*
G01Y633543D02*
Y633641D01*
G01D02*
Y635216D01*
G01Y630216D02*
Y630315D01*
G01Y628543D02*
Y628641D01*
G01D02*
Y630216D01*
G01Y625216D02*
Y625315D01*
G01Y623641D02*
Y625216D01*
G01Y623543D02*
Y623641D01*
G01Y620216D02*
Y620315D01*
G01Y618641D02*
Y620216D01*
G01Y618543D02*
Y618641D01*
G01Y615216D02*
Y615315D01*
G01Y613641D02*
Y615216D01*
G01Y613543D02*
Y613641D01*
G01Y610216D02*
Y610315D01*
G01Y608641D02*
Y610216D01*
G01Y608543D02*
Y608641D01*
G01X889449Y643070D02*
Y641889D01*
G01Y646220D02*
Y645039D01*
G01X889055Y643070D02*
Y641889D01*
G01Y646220D02*
Y645039D01*
G01X888976Y643858D02*
Y644252D01*
G01Y640905D02*
Y641102D01*
G01X886811Y633307D02*
Y630551D01*
G01X886496Y641870D02*
Y641706D01*
G01Y643313D02*
Y643182D01*
G01X886329Y643313D02*
Y643182D01*
G01X886295Y641706D02*
Y641889D01*
G01D02*
Y641902D01*
G01X886128Y642099D02*
Y642296D01*
G01X886024Y586102D02*
Y584527D01*
G01X885827Y579389D02*
Y592342D01*
G01X885826Y641889D02*
Y641706D01*
G01Y641902D02*
Y641889D01*
G01X885793Y643182D02*
Y643313D01*
G01X885659D02*
Y643182D01*
G01X885630Y640315D02*
Y640905D01*
G01X885625Y641706D02*
Y641889D01*
G01D02*
Y641902D01*
G01X885357Y641378D02*
Y641181D01*
G01X885122Y641889D02*
Y641640D01*
G01Y641902D02*
Y641889D01*
G01X885089Y643182D02*
Y643313D01*
G01X884921Y643149D02*
Y643346D01*
G01Y641640D02*
Y641889D01*
G01D02*
Y641902D01*
G01X884449Y645039D02*
Y646220D01*
G01Y641889D02*
Y643070D01*
G01X884134Y638641D02*
Y640216D01*
G01Y633641D02*
Y635216D01*
G01Y628641D02*
Y630216D01*
G01Y623641D02*
Y625216D01*
G01Y618641D02*
Y620216D01*
G01Y613641D02*
Y615216D01*
G01Y608641D02*
Y610216D01*
G01X882559Y638641D02*
Y640216D01*
G01Y633641D02*
Y635216D01*
G01Y628641D02*
Y630216D01*
G01Y623641D02*
Y625216D01*
G01Y618641D02*
Y620216D01*
G01Y613641D02*
Y615216D01*
G01Y608641D02*
Y610216D01*
G01X881890Y636496D02*
Y637362D01*
G01Y631496D02*
Y632362D01*
G01Y626496D02*
Y627362D01*
G01Y621496D02*
Y622362D01*
G01Y616496D02*
Y617362D01*
G01Y611496D02*
Y612362D01*
G01Y605610D02*
Y607362D01*
G01Y575452D02*
Y588405D01*
G01X881772Y610216D02*
Y608641D01*
G01Y615216D02*
Y613641D01*
G01Y620216D02*
Y618641D01*
G01Y625216D02*
Y623641D01*
G01Y630216D02*
Y628641D01*
G01Y635216D02*
Y633641D01*
G01Y640216D02*
Y638641D01*
G01X881378Y610216D02*
Y608641D01*
G01Y615216D02*
Y613641D01*
G01Y620216D02*
Y618641D01*
G01Y625216D02*
Y623641D01*
G01Y630216D02*
Y628641D01*
G01Y635216D02*
Y633641D01*
G01Y640216D02*
Y638641D01*
G01X879213Y610216D02*
Y610334D01*
G01Y610137D02*
Y610216D01*
G01Y609153D02*
Y608989D01*
G01X879012D02*
Y609186D01*
G01X878844Y609383D02*
Y609580D01*
G01X878543Y609186D02*
Y608989D01*
G01X878342D02*
Y609186D01*
G01X878074Y608641D02*
Y608464D01*
G01Y608661D02*
Y608641D01*
G01X877839Y609186D02*
Y608924D01*
G01X877638D02*
Y609186D01*
G01Y610334D02*
Y610216D01*
G01D02*
Y610137D01*
G01X876457Y638641D02*
Y640216D01*
G01Y633641D02*
Y635216D01*
G01Y628641D02*
Y630216D01*
G01Y623641D02*
Y625216D01*
G01Y618641D02*
Y620216D01*
G01Y613641D02*
Y615216D01*
G01Y608641D02*
Y610216D01*
G01X874016Y592342D02*
Y605610D01*
G01X870079Y755452D02*
Y588405D01*
G01X886463Y643477D02*
X886496Y643313D01*
G01X886492Y641889D02*
X886496Y641870D01*
G01X886463Y642034D02*
X886492Y641889D01*
G01X885793Y642067D02*
X885826Y641902D01*
G01X884937Y643070D02*
X884921Y643149D01*
G01X884955Y642985D02*
X884937Y643070D01*
G01X884955Y641476D02*
X884921Y641640D01*
G01X879179Y609317D02*
X879213Y609153D01*
G01X878509Y609350D02*
X878543Y609186D01*
G01X877671Y608759D02*
X877638Y608924D01*
G01X886295Y643445D02*
X886329Y643313D01*
G01X885821Y643070D02*
X885793Y643182D01*
G01X885826Y643051D02*
X885821Y643070D01*
G01X885625Y643445D02*
X885659Y643313D01*
G01X885625Y641902D02*
X885591Y642034D01*
G01X885659Y641574D02*
X885625Y641706D01*
G01X885117Y643070D02*
X885089Y643182D01*
G01X885122Y643051D02*
X885117Y643070D01*
G01X885122Y641640D02*
X885156Y641509D01*
G01X878342Y609186D02*
X878308Y609317D01*
G01X878375Y608858D02*
X878342Y608989D01*
G01X877839Y608924D02*
X877872Y608792D01*
G01X886295Y641902D02*
X886262Y642001D01*
G01X885826Y641706D02*
X885859Y641607D01*
G01X879012Y609186D02*
X878978Y609284D01*
G01X878543Y608989D02*
X878576Y608891D01*
G01X885692Y643641D02*
X885726Y643576D01*
G01X885558D02*
X885625Y643445D01*
G01X885759Y642854D02*
X885726Y642920D01*
G01Y642198D02*
X885793Y642067D01*
G01X885189Y642920D02*
X885122Y643051D01*
G01X885726Y641443D02*
X885659Y641574D01*
G01X878442Y609481D02*
X878509Y609350D01*
G01X878442Y608727D02*
X878375Y608858D01*
G01X886362Y643641D02*
X886463Y643477D01*
G01X885056Y642821D02*
X884955Y642985D01*
G01X885056Y641312D02*
X884955Y641476D01*
G01X877772Y608595D02*
X877744Y608641D01*
G01D02*
X877671Y608759D01*
G01X885591Y642034D02*
X885524Y642132D01*
G01X885859Y641607D02*
X885927Y641509D01*
G01X878308Y609317D02*
X878241Y609416D01*
G01X878576Y608891D02*
X878643Y608792D01*
G01X886195Y643576D02*
X886295Y643445D01*
G01X885591Y643772D02*
X885692Y643641D01*
G01X885927Y642920D02*
X885826Y643051D01*
G01X886362Y642165D02*
X886463Y642034D01*
G01X879079Y609448D02*
X879179Y609317D01*
G01X886262Y643740D02*
X886362Y643641D01*
G01X885859Y642756D02*
X885759Y642854D01*
G01X886262Y642001D02*
X886195Y642067D01*
G01X885591Y642329D02*
X885726Y642198D01*
G01X885156Y642723D02*
X885056Y642821D01*
G01X885859Y641312D02*
X885726Y641443D01*
G01X885156Y641509D02*
X885256Y641410D01*
G01X878978Y609284D02*
X878911Y609350D01*
G01X878308Y609613D02*
X878442Y609481D01*
G01X878576Y608595D02*
X878529Y608641D01*
G01D02*
X878442Y608727D01*
G01X877872Y608792D02*
X877973Y608694D01*
G01X885424Y643674D02*
X885558Y643576D01*
G01X886228Y642263D02*
X886362Y642165D01*
G01X885324Y642821D02*
X885189Y642920D01*
G01X878945Y609547D02*
X879079Y609448D01*
G01X886094Y643641D02*
X886195Y643576D01*
G01X886027Y642854D02*
X885927Y642920D01*
G01X885524Y642132D02*
X885424Y642198D01*
G01X878241Y609416D02*
X878141Y609481D01*
G01X885223Y641213D02*
X885056Y641312D01*
G01X877939Y608497D02*
X877772Y608595D01*
G01X885994Y642690D02*
X885859Y642756D01*
G01X886195Y642067D02*
X886128Y642099D01*
G01X885458Y642395D02*
X885591Y642329D01*
G01X878911Y609350D02*
X878844Y609383D01*
G01X878174Y609678D02*
X878308Y609613D01*
G01X886094Y643806D02*
X886262Y643740D01*
G01X885424Y643838D02*
X885591Y643772D01*
G01X885324Y642657D02*
X885156Y642723D01*
G01X881890Y636496D02*
X885039Y635315D01*
G01X881890Y631496D02*
X885039Y630315D01*
G01X881890Y626496D02*
X885039Y625315D01*
G01X881890Y621496D02*
X885039Y620315D01*
G01X881890Y616496D02*
X885039Y615315D01*
G01X881890Y611496D02*
X885039Y610315D01*
G01X886128Y642296D02*
X886228Y642263D01*
G01X885927Y641509D02*
X886027Y641476D01*
G01X885256Y641410D02*
X885357Y641378D01*
G01X878844Y609580D02*
X878945Y609547D01*
G01X878643Y608792D02*
X878744Y608759D01*
G01X877973Y608694D02*
X878074Y608661D01*
G01X888976Y643858D02*
X891339Y643169D01*
G01X885994Y641279D02*
X885859Y641312D01*
G01X885357Y641181D02*
X885223Y641213D01*
G01X878710Y608563D02*
X878576Y608595D01*
G01X878074Y608464D02*
X877939Y608497D01*
G01X884449Y645039D02*
X896457D01*
G01X922561D02*
X896457D01*
G01Y644941D02*
X925787D01*
G01X891339D02*
X893701D01*
G01X885324Y643838D02*
X885424D01*
G01X885994Y643806D02*
X886094D01*
G01X885324Y643674D02*
X885424D01*
G01X886027Y643641D02*
X886094D01*
G01X891339Y643169D02*
X893701D01*
G01X925787D02*
X896457D01*
G01Y643070D02*
X922561D01*
G01X884449D02*
X896457D01*
G01X886094Y642854D02*
X886027D01*
G01X885424Y642821D02*
X885324D01*
G01X886094Y642690D02*
X885994D01*
G01X885424Y642657D02*
X885324D01*
G01X885290Y642395D02*
X885458D01*
G01X885424Y642198D02*
X885324D01*
G01X924016Y642165D02*
X905512D01*
G01X884449Y641889D02*
X896457D01*
G01X922561D02*
X896457D01*
G01X891339Y641791D02*
X893701D01*
G01X925787D02*
X896457D01*
G01X886027Y641476D02*
X886094D01*
G01X886128Y641279D02*
X885994D01*
G01X885630Y640905D02*
X888976D01*
G01X889764Y640315D02*
X885630D01*
G01X923032D02*
X893701D01*
G01Y640216D02*
X924102D01*
G01X876457D02*
X893701D01*
G01Y639724D02*
X925984D01*
G01X893701Y638641D02*
X876457D01*
G01X924102D02*
X893701D01*
G01Y638543D02*
X923032D01*
G01X885039D02*
X889764D01*
G01Y635315D02*
X885039D01*
G01X925984D02*
X893701D01*
G01Y635216D02*
X924223D01*
G01X876457D02*
X893701D01*
G01Y633641D02*
X924223D01*
G01X893701D02*
X876457D01*
G01X893701Y633543D02*
X925984D01*
G01X885039D02*
X889764D01*
G01X886811Y633307D02*
X893701D01*
G01Y630551D02*
X886811D01*
G01X893701Y630315D02*
X925984D01*
G01X889764D02*
X885039D01*
G01X893701Y630216D02*
X924223D01*
G01X876457D02*
X893701D01*
G01Y628641D02*
X924223D01*
G01X893701D02*
X876457D01*
G01X893701Y628543D02*
X925984D01*
G01X885039D02*
X889764D01*
G01X893701Y625315D02*
X925984D01*
G01X889764D02*
X885039D01*
G01X893701Y625216D02*
X924223D01*
G01X876457D02*
X893701D01*
G01Y623641D02*
X924223D01*
G01X893701D02*
X876457D01*
G01X893701Y623543D02*
X925984D01*
G01X885039D02*
X889764D01*
G01X893701Y620315D02*
X925984D01*
G01X889764D02*
X885039D01*
G01X893701Y620216D02*
X924223D01*
G01X876457D02*
X893701D01*
G01Y618641D02*
X924223D01*
G01X893701D02*
X876457D01*
G01X893701Y618543D02*
X925984D01*
G01X885039D02*
X889764D01*
G01X893701Y615315D02*
X925984D01*
G01X889764D02*
X885039D01*
G01X893701Y615216D02*
X924223D01*
G01X876457D02*
X893701D01*
G01Y613641D02*
X924223D01*
G01X893701D02*
X876457D01*
G01X893701Y613543D02*
X925984D01*
G01X885039D02*
X889764D01*
G01X879213Y610334D02*
X877638D01*
G01X893701Y610315D02*
X925984D01*
G01X889764D02*
X885039D01*
G01X893701Y610216D02*
X924223D01*
G01X876457D02*
X893701D01*
G01X877638Y610137D02*
X878945D01*
G01X878710Y609941D02*
X878978D01*
G01X878007Y609678D02*
X878174D01*
G01X878141Y609481D02*
X878040D01*
G01X878744Y608759D02*
X878811D01*
G01X893701Y608641D02*
X924223D01*
G01X893701D02*
X876457D01*
G01X878844Y608563D02*
X878710D01*
G01X893701Y608543D02*
X925984D01*
G01X885039D02*
X889764D01*
G01X896358Y605610D02*
X924803D01*
G01X893701D02*
X894980D01*
G01X893701D02*
X874016D01*
G01Y603838D02*
X893701D01*
G01X874016Y600689D02*
X924016D01*
G01X894488Y597736D02*
X905512D01*
G01X874016D02*
X894488D01*
G01X927953Y593523D02*
X894488D01*
G01X927953Y592342D02*
X874016D01*
G01X885827Y590374D02*
X905512D01*
G01X870079Y588405D02*
X881890D01*
G01X936614D02*
X909449D01*
G01X905512Y587283D02*
X885827D01*
G01Y586299D02*
X905512D01*
G01X905315Y586102D02*
X886024D01*
G01X905315Y584527D02*
X886024D01*
G01X905512Y584330D02*
X885827D01*
G01Y583346D02*
X905512D01*
G01X885827Y581358D02*
X905512D01*
G01X885827Y579389D02*
X905512D01*
G01X909449Y575452D02*
X881890D01*
G01X886262Y641312D02*
X886128Y641279D01*
G01X878978Y608595D02*
X878844Y608563D01*
G01X878649Y664685D02*
X878515Y664586D01*
G01X879018Y664980D02*
X879252Y665177D01*
G01X878984D02*
X878750Y664980D01*
G01X878615Y664422D02*
X878683Y664488D01*
G01X878515Y664586D02*
X878415Y664455D01*
G01X891339Y648090D02*
X888976Y647401D01*
G01X891339Y651240D02*
X888976Y650551D01*
G01X891339Y654389D02*
X888976Y653700D01*
G01X891339Y657539D02*
X888976Y656850D01*
G01X891339Y660689D02*
X888976Y660000D01*
G01X878683Y664488D02*
X878783Y664520D01*
G01X878750Y664717D02*
X878649Y664685D01*
G01X885039Y668543D02*
X881890Y667362D01*
G01X885039Y673543D02*
X881890Y672362D01*
G01X885039Y683543D02*
X881890Y682362D01*
G01X885039Y688543D02*
X881890Y687362D01*
G01X885039Y693543D02*
X881890Y692362D01*
G01X885039Y698543D02*
X881890Y697362D01*
G01X885039Y703543D02*
X881890Y702362D01*
G01X885039Y708543D02*
X881890Y707362D01*
G01X885039Y713543D02*
X881890Y712362D01*
G01X878582Y664324D02*
X878615Y664422D01*
G01X878415Y664455D02*
X878381Y664291D01*
G01X922561Y649370D02*
Y648189D01*
G01Y652519D02*
Y651338D01*
G01Y655669D02*
Y654488D01*
G01Y658819D02*
Y657637D01*
G01Y661968D02*
Y660787D01*
G01X921823D02*
Y661968D01*
G01Y657637D02*
Y658819D01*
G01Y654488D02*
Y655669D01*
G01Y651338D02*
Y652519D01*
G01Y648189D02*
Y649370D01*
G01X919366Y728641D02*
Y730216D01*
G01Y723641D02*
Y725216D01*
G01Y718641D02*
Y720216D01*
G01Y713641D02*
Y715216D01*
G01Y708641D02*
Y710216D01*
G01Y703641D02*
Y705216D01*
G01Y698641D02*
Y700216D01*
G01Y693641D02*
Y695216D01*
G01Y688641D02*
Y690216D01*
G01Y683641D02*
Y685216D01*
G01Y678641D02*
Y680216D01*
G01Y673641D02*
Y675216D01*
G01Y668641D02*
Y670216D01*
G01Y665216D02*
Y663641D01*
G01X919121Y728641D02*
Y730216D01*
G01Y723641D02*
Y725216D01*
G01Y718641D02*
Y720216D01*
G01Y713641D02*
Y715216D01*
G01Y708641D02*
Y710216D01*
G01Y703641D02*
Y705216D01*
G01Y698641D02*
Y700216D01*
G01Y693641D02*
Y695216D01*
G01Y688641D02*
Y690216D01*
G01Y683641D02*
Y685216D01*
G01Y678641D02*
Y680216D01*
G01Y673641D02*
Y675216D01*
G01Y668641D02*
Y670216D01*
G01Y663641D02*
Y665216D01*
G01X918014D02*
Y663641D01*
G01Y670216D02*
Y668641D01*
G01Y675216D02*
Y673641D01*
G01Y680216D02*
Y678641D01*
G01Y685216D02*
Y683641D01*
G01Y690216D02*
Y688641D01*
G01Y695216D02*
Y693641D01*
G01Y700216D02*
Y698641D01*
G01Y705216D02*
Y703641D01*
G01Y710216D02*
Y708641D01*
G01Y715216D02*
Y713641D01*
G01Y720216D02*
Y718641D01*
G01Y725216D02*
Y723641D01*
G01Y730216D02*
Y728641D01*
G01X917008Y657539D02*
Y658917D01*
G01Y651240D02*
Y652618D01*
G01Y654389D02*
Y655767D01*
G01Y648090D02*
Y649468D01*
G01Y662067D02*
Y660689D01*
G01X916265Y649370D02*
Y648189D01*
G01Y655669D02*
Y654488D01*
G01Y652519D02*
Y651338D01*
G01Y658819D02*
Y657637D01*
G01Y661968D02*
Y660787D01*
G01X915767D02*
Y661968D01*
G01Y657637D02*
Y658819D01*
G01Y654488D02*
Y655669D01*
G01Y651338D02*
Y652519D01*
G01Y648189D02*
Y649370D01*
G01X913528D02*
Y648189D01*
G01Y652519D02*
Y651338D01*
G01Y655669D02*
Y654488D01*
G01Y658819D02*
Y657637D01*
G01Y661968D02*
Y660787D01*
G01X885039Y723543D02*
X881890Y722362D01*
G01X885039Y728543D02*
X881890Y727362D01*
G01X894882Y717067D02*
Y721791D01*
G01Y677067D02*
Y681791D01*
G01X893701Y720216D02*
Y740019D01*
G01Y680216D02*
Y718641D01*
G01Y661968D02*
Y678641D01*
G01Y648189D02*
Y646220D01*
G01Y651338D02*
Y649370D01*
G01D02*
Y648189D01*
G01Y654488D02*
Y652519D01*
G01D02*
Y651338D01*
G01Y655669D02*
Y654488D01*
G01Y657637D02*
Y655669D01*
G01Y660787D02*
Y658819D01*
G01D02*
Y657637D01*
G01Y661968D02*
Y660787D01*
G01Y680216D02*
Y678641D01*
G01Y720216D02*
Y718641D01*
G01X891811Y660787D02*
Y661968D01*
G01Y657637D02*
Y658819D01*
G01Y651338D02*
Y652519D01*
G01Y654488D02*
Y655669D01*
G01Y648189D02*
Y649370D01*
G01X891732Y720216D02*
Y720315D01*
G01Y718543D02*
Y718641D01*
G01D02*
Y720216D01*
G01Y680216D02*
Y680315D01*
G01Y678641D02*
Y680216D01*
G01Y678543D02*
Y678641D01*
G01X890236Y660787D02*
Y661968D01*
G01Y657637D02*
Y658819D01*
G01Y654488D02*
Y655669D01*
G01Y651338D02*
Y652519D01*
G01Y648189D02*
Y649370D01*
G01X889764Y728543D02*
Y728641D01*
G01D02*
Y730216D01*
G01Y725216D02*
Y725315D01*
G01Y723543D02*
Y723641D01*
G01D02*
Y725216D01*
G01Y715216D02*
Y715315D01*
G01Y713543D02*
Y713641D01*
G01D02*
Y715216D01*
G01Y710216D02*
Y710315D01*
G01Y708543D02*
Y708641D01*
G01D02*
Y710216D01*
G01Y705216D02*
Y705315D01*
G01Y703543D02*
Y703641D01*
G01D02*
Y705216D01*
G01Y700216D02*
Y700315D01*
G01Y698641D02*
Y700216D01*
G01Y698543D02*
Y698641D01*
G01Y695216D02*
Y695315D01*
G01Y693641D02*
Y695216D01*
G01Y693543D02*
Y693641D01*
G01Y690216D02*
Y690315D01*
G01Y688641D02*
Y690216D01*
G01Y688543D02*
Y688641D01*
G01Y685216D02*
Y685315D01*
G01Y683641D02*
Y685216D01*
G01Y683543D02*
Y683641D01*
G01Y675216D02*
Y675315D01*
G01Y673543D02*
Y673641D01*
G01D02*
Y675216D01*
G01Y670216D02*
Y670315D01*
G01Y668543D02*
Y668641D01*
G01D02*
Y670216D01*
G01Y665216D02*
Y665315D01*
G01Y663543D02*
Y663641D01*
G01D02*
Y665216D01*
G01X889449Y649370D02*
Y648189D01*
G01Y652519D02*
Y651338D01*
G01Y655669D02*
Y654488D01*
G01Y658819D02*
Y657637D01*
G01Y661968D02*
Y660787D01*
G01X889055Y649370D02*
Y648189D01*
G01Y652519D02*
Y651338D01*
G01Y655669D02*
Y654488D01*
G01Y658819D02*
Y657637D01*
G01Y661968D02*
Y660787D01*
G01X888976Y662756D02*
Y662952D01*
G01Y656456D02*
Y656850D01*
G01Y659606D02*
Y660000D01*
G01Y653307D02*
Y653700D01*
G01Y647008D02*
Y647401D01*
G01Y650157D02*
Y650551D01*
G01X886811Y668307D02*
Y665551D01*
G01Y693307D02*
Y690551D01*
G01Y718307D02*
Y715551D01*
G01X885630Y662952D02*
Y663543D01*
G01X884449Y660787D02*
Y661968D01*
G01Y657637D02*
Y658819D01*
G01Y651338D02*
Y652519D01*
G01Y654488D02*
Y655669D01*
G01Y648189D02*
Y649370D01*
G01X884134Y728641D02*
Y730216D01*
G01Y723641D02*
Y725216D01*
G01Y718641D02*
Y720216D01*
G01Y713641D02*
Y715216D01*
G01Y708641D02*
Y710216D01*
G01Y703641D02*
Y705216D01*
G01Y698641D02*
Y700216D01*
G01Y693641D02*
Y695216D01*
G01Y688641D02*
Y690216D01*
G01Y683641D02*
Y685216D01*
G01Y678641D02*
Y680216D01*
G01Y673641D02*
Y675216D01*
G01Y668641D02*
Y670216D01*
G01Y663641D02*
Y665216D01*
G01X882559Y728641D02*
Y730216D01*
G01Y723641D02*
Y725216D01*
G01Y718641D02*
Y720216D01*
G01Y713641D02*
Y715216D01*
G01Y708641D02*
Y710216D01*
G01Y703641D02*
Y705216D01*
G01Y698641D02*
Y700216D01*
G01Y693641D02*
Y695216D01*
G01Y688641D02*
Y690216D01*
G01Y683641D02*
Y685216D01*
G01Y678641D02*
Y680216D01*
G01Y673641D02*
Y675216D01*
G01Y668641D02*
Y670216D01*
G01Y663641D02*
Y665216D01*
G01X881890Y726496D02*
Y727362D01*
G01Y721496D02*
Y722362D01*
G01Y716496D02*
Y717362D01*
G01Y711496D02*
Y712362D01*
G01Y706496D02*
Y707362D01*
G01Y701496D02*
Y702362D01*
G01Y696496D02*
Y697362D01*
G01Y691496D02*
Y692362D01*
G01Y686496D02*
Y687362D01*
G01Y681496D02*
Y682362D01*
G01Y676496D02*
Y677362D01*
G01Y671496D02*
Y672362D01*
G01Y666496D02*
Y667362D01*
G01X881772Y665216D02*
Y663641D01*
G01Y670216D02*
Y668641D01*
G01Y675216D02*
Y673641D01*
G01Y680216D02*
Y678641D01*
G01Y685216D02*
Y683641D01*
G01Y690216D02*
Y688641D01*
G01Y695216D02*
Y693641D01*
G01Y700216D02*
Y698641D01*
G01Y705216D02*
Y703641D01*
G01Y710216D02*
Y708641D01*
G01Y715216D02*
Y713641D01*
G01Y720216D02*
Y718641D01*
G01Y725216D02*
Y723641D01*
G01Y730216D02*
Y728641D01*
G01X881378Y665216D02*
Y663641D01*
G01Y670216D02*
Y668641D01*
G01Y675216D02*
Y673641D01*
G01Y680216D02*
Y678641D01*
G01Y685216D02*
Y683641D01*
G01Y690216D02*
Y688641D01*
G01Y695216D02*
Y693641D01*
G01Y700216D02*
Y698641D01*
G01Y705216D02*
Y703641D01*
G01Y710216D02*
Y708641D01*
G01Y715216D02*
Y713641D01*
G01Y720216D02*
Y718641D01*
G01Y725216D02*
Y723641D01*
G01Y730216D02*
Y728641D01*
G01X879252Y665216D02*
Y665374D01*
G01Y663504D02*
Y663641D01*
G01Y665177D02*
Y665216D01*
G01Y663641D02*
Y664291D01*
G01X879085Y664324D02*
Y663700D01*
G01X878582D02*
Y664324D01*
G01X878381Y664291D02*
Y663700D01*
G01X877677Y665374D02*
Y665216D01*
G01Y663641D02*
Y663504D01*
G01Y665216D02*
Y665177D01*
G01Y663700D02*
Y663641D01*
G01X876457Y728641D02*
Y730216D01*
G01Y723641D02*
Y725216D01*
G01Y713641D02*
Y715216D01*
G01Y708641D02*
Y710216D01*
G01Y703641D02*
Y705216D01*
G01Y698641D02*
Y700216D01*
G01Y693641D02*
Y695216D01*
G01Y688641D02*
Y690216D01*
G01Y683641D02*
Y685216D01*
G01Y673641D02*
Y675216D01*
G01Y668641D02*
Y670216D01*
G01X875000Y718641D02*
Y720216D01*
G01Y678641D02*
Y680216D01*
G01Y663641D02*
Y665216D01*
G01X879252Y664291D02*
X879219Y664455D01*
G01X879051Y664422D02*
X879085Y664324D01*
G01X879219Y664455D02*
X879118Y664586D01*
G01X878984Y664488D02*
X879051Y664422D01*
G01X879118Y664586D02*
X878984Y664685D01*
G01X881890Y726496D02*
X885039Y725315D01*
G01X881890Y716496D02*
X885039Y715315D01*
G01X881890Y711496D02*
X885039Y710315D01*
G01X881890Y706496D02*
X885039Y705315D01*
G01X881890Y701496D02*
X885039Y700315D01*
G01X881890Y696496D02*
X885039Y695315D01*
G01X881890Y691496D02*
X885039Y690315D01*
G01X881890Y686496D02*
X885039Y685315D01*
G01X881890Y676496D02*
X885039Y675315D01*
G01X881890Y671496D02*
X885039Y670315D01*
G01X881890Y666496D02*
X885039Y665315D01*
G01X878984Y664685D02*
X878884Y664717D01*
G01Y664520D02*
X878984Y664488D01*
G01X888976Y662756D02*
X891339Y662067D01*
G01X881890Y721496D02*
X887008Y720315D01*
G01X888976Y659606D02*
X891339Y658917D01*
G01X888976Y656456D02*
X891339Y655767D01*
G01X888976Y653307D02*
X891339Y652618D01*
G01X888976Y650157D02*
X891339Y649468D01*
G01X888976Y647008D02*
X891339Y646319D01*
G01X881890Y681496D02*
X887008Y680315D01*
G01X893701Y728641D02*
X924223D01*
G01X893701D02*
X876457D01*
G01X893701Y728543D02*
X925984D01*
G01X885039D02*
X889764D01*
G01X893701Y725315D02*
X925984D01*
G01X889764D02*
X885039D01*
G01X893701Y725216D02*
X924223D01*
G01X876457D02*
X893701D01*
G01Y723641D02*
X924223D01*
G01X893701D02*
X876457D01*
G01X893701Y723543D02*
X925984D01*
G01X885039D02*
X889764D01*
G01X894882Y721791D02*
X893701D01*
G01X891732Y720315D02*
X887008D01*
G01X925984D02*
X894882D01*
G01Y720216D02*
X924223D01*
G01X875000D02*
X894882D01*
G01Y718641D02*
X924223D01*
G01X875000D02*
X894882D01*
G01Y718543D02*
X925984D01*
G01X887008D02*
X891732D01*
G01X886811Y718307D02*
X893701D01*
G01Y717067D02*
X894882D01*
G01X893701Y715551D02*
X886811D01*
G01X893701Y715315D02*
X925984D01*
G01X889764D02*
X885039D01*
G01X893701Y715216D02*
X924223D01*
G01X876457D02*
X893701D01*
G01Y713641D02*
X924223D01*
G01X893701D02*
X876457D01*
G01X893701Y713543D02*
X925984D01*
G01X885039D02*
X889764D01*
G01X893701Y710315D02*
X925984D01*
G01X889764D02*
X885039D01*
G01X893701Y710216D02*
X924223D01*
G01X876457D02*
X893701D01*
G01Y708641D02*
X924223D01*
G01X893701D02*
X876457D01*
G01X893701Y708543D02*
X925984D01*
G01X885039D02*
X889764D01*
G01X893701Y705315D02*
X925984D01*
G01X889764D02*
X885039D01*
G01X893701Y705216D02*
X924223D01*
G01X876457D02*
X893701D01*
G01Y703641D02*
X924223D01*
G01X893701D02*
X876457D01*
G01X893701Y703543D02*
X925984D01*
G01X885039D02*
X889764D01*
G01X893701Y700315D02*
X925984D01*
G01X889764D02*
X885039D01*
G01X893701Y700216D02*
X924223D01*
G01X876457D02*
X893701D01*
G01Y698641D02*
X924223D01*
G01X893701D02*
X876457D01*
G01X893701Y698543D02*
X925984D01*
G01X885039D02*
X889764D01*
G01X893701Y695315D02*
X925984D01*
G01X889764D02*
X885039D01*
G01X893701Y695216D02*
X924223D01*
G01X876457D02*
X893701D01*
G01Y693641D02*
X924223D01*
G01X893701D02*
X876457D01*
G01X893701Y693543D02*
X925984D01*
G01X885039D02*
X889764D01*
G01X886811Y693307D02*
X893701D01*
G01Y690551D02*
X886811D01*
G01X893701Y690315D02*
X925984D01*
G01X889764D02*
X885039D01*
G01X893701Y690216D02*
X924223D01*
G01X876457D02*
X893701D01*
G01Y688641D02*
X924223D01*
G01X893701D02*
X876457D01*
G01X893701Y688543D02*
X925984D01*
G01X885039D02*
X889764D01*
G01X893701Y685315D02*
X925984D01*
G01X889764D02*
X885039D01*
G01X893701Y685216D02*
X924223D01*
G01X876457D02*
X893701D01*
G01Y683641D02*
X924223D01*
G01X893701D02*
X876457D01*
G01X893701Y683543D02*
X925984D01*
G01X885039D02*
X889764D01*
G01X894882Y681791D02*
X893701D01*
G01X891732Y680315D02*
X887008D01*
G01X925984D02*
X894882D01*
G01Y680216D02*
X924223D01*
G01X875000D02*
X894882D01*
G01Y678641D02*
X924223D01*
G01X875000D02*
X894882D01*
G01Y678543D02*
X925984D01*
G01X887008D02*
X891732D01*
G01X893701Y677067D02*
X894882D01*
G01X893701Y675315D02*
X925984D01*
G01X889764D02*
X885039D01*
G01X893701Y675216D02*
X924223D01*
G01X876457D02*
X893701D01*
G01Y673641D02*
X924223D01*
G01X893701D02*
X876457D01*
G01X893701Y673543D02*
X925984D01*
G01X885039D02*
X889764D01*
G01X893701Y670315D02*
X925984D01*
G01X889764D02*
X885039D01*
G01X893701Y670216D02*
X924223D01*
G01X876457D02*
X893701D01*
G01Y668641D02*
X876457D01*
G01X924223D02*
X893701D01*
G01Y668543D02*
X925984D01*
G01X885039D02*
X889764D01*
G01X886811Y668307D02*
X893701D01*
G01Y665551D02*
X886811D01*
G01X879252Y665374D02*
X877677D01*
G01X893701Y665315D02*
X923032D01*
G01X889764D02*
X885039D01*
G01X893701Y665216D02*
X924102D01*
G01X875000D02*
X893701D01*
G01X877677Y665177D02*
X878984D01*
G01X878750Y664980D02*
X879018D01*
G01X878884Y664717D02*
X878750D01*
G01X878783Y664520D02*
X878884D01*
G01X893701Y664133D02*
X925984D01*
G01X879085Y663700D02*
X878582D01*
G01X878381D02*
X877677D01*
G01X893701Y663641D02*
X924102D01*
G01X875000D02*
X893701D01*
G01Y663543D02*
X923032D01*
G01X885630D02*
X889764D01*
G01X877677Y663504D02*
X879252D01*
G01X888976Y662952D02*
X885630D01*
G01X896457Y662067D02*
X925787D01*
G01X891339D02*
X893701D01*
G01X896457Y661968D02*
X922561D01*
G01X884449D02*
X896457D01*
G01X905512Y661693D02*
X924016D01*
G01X884449Y660787D02*
X896457D01*
G01X922561D02*
X896457D01*
G01Y660689D02*
X925787D01*
G01X891339D02*
X893701D01*
G01X896457Y658917D02*
X925787D01*
G01X891339D02*
X893701D01*
G01X896457Y658819D02*
X922561D01*
G01X884449D02*
X896457D01*
G01X884449Y657637D02*
X896457D01*
G01X922561D02*
X896457D01*
G01Y657539D02*
X925787D01*
G01X891339D02*
X893701D01*
G01X896457Y655767D02*
X925787D01*
G01X891339D02*
X893701D01*
G01X896457Y655669D02*
X922561D01*
G01X884449D02*
X896457D01*
G01X884449Y654488D02*
X896457D01*
G01X922561D02*
X896457D01*
G01Y654389D02*
X925787D01*
G01X891339D02*
X893701D01*
G01X896457Y652618D02*
X925787D01*
G01X891339D02*
X893701D01*
G01X896457Y652519D02*
X922561D01*
G01X884449D02*
X896457D01*
G01X884449Y651338D02*
X896457D01*
G01X922561D02*
X896457D01*
G01Y651240D02*
X925787D01*
G01X891339D02*
X893701D01*
G01X896457Y649468D02*
X925787D01*
G01X891339D02*
X893701D01*
G01X896457Y649370D02*
X922561D01*
G01X884449D02*
X896457D01*
G01X884449Y648189D02*
X896457D01*
G01X922561D02*
X896457D01*
G01Y648090D02*
X925787D01*
G01X891339D02*
X893701D01*
G01X896457Y646319D02*
X925787D01*
G01X891339D02*
X893701D01*
G01X896457Y646220D02*
X922561D01*
G01X884449D02*
X896457D01*
G01X887008Y718543D02*
X881890Y717362D01*
G01X887008Y678543D02*
X881890Y677362D01*
G01X899409Y758543D02*
G03I-3740J0D01*
G01X884400Y748307D02*
G03Y745157I2017J-1575D01*
G01X888435D02*
G03Y748307I-2017J1575D01*
G01X888788Y744370D02*
G03Y749094I-2371J2362D01*
G01X884047D02*
G03Y744370I2371J-2362D01*
G01X889921Y746732D02*
G03I-3503J0D01*
G01X889095Y743582D02*
G03Y749882I-2677J3150D01*
G01X883740D02*
G03Y743582I2677J-3150D01*
G01X919366Y733641D02*
Y735216D01*
G01X919121Y733641D02*
Y735216D01*
G01X918014D02*
Y733641D01*
G01X885039Y733543D02*
X881890Y732362D01*
G01X909449Y768405D02*
Y755452D01*
G01X905512Y751515D02*
Y764468D01*
G01X905315Y757756D02*
Y759330D01*
G01X899961D02*
Y757756D01*
G01X898622Y757559D02*
Y757756D01*
G01Y759330D02*
Y759527D01*
G01Y759330D02*
Y757756D01*
G01X898425Y759330D02*
Y757756D01*
G01X896850Y759330D02*
Y757756D01*
G01X894488Y743169D02*
Y751515D01*
G01Y759330D02*
Y757756D01*
G01X892913D02*
Y759330D01*
G01X892717D02*
Y759527D01*
G01Y757756D02*
Y759330D01*
G01Y757756D02*
Y757559D01*
G01X891378Y757756D02*
Y759330D01*
G01X889764Y735216D02*
Y735315D01*
G01Y733543D02*
Y733641D01*
G01D02*
Y735216D01*
G01Y730216D02*
Y730315D01*
G01X886024Y759330D02*
Y757756D01*
G01X885827Y751515D02*
Y764468D01*
G01X884134Y733641D02*
Y735216D01*
G01X882559Y733641D02*
Y735216D01*
G01X881890Y755452D02*
Y768405D01*
G01Y736496D02*
Y738248D01*
G01Y731496D02*
Y732362D01*
G01X881772Y735216D02*
Y733641D01*
G01X881378Y735216D02*
Y733641D01*
G01X876457D02*
Y735216D01*
G01X874016Y738248D02*
Y751515D01*
G01X881890Y736496D02*
X885039Y735315D01*
G01X881890Y731496D02*
X885039Y730315D01*
G01X881890Y768405D02*
X909449D01*
G01X905512Y764468D02*
X885827D01*
G01X905512Y762500D02*
X885827D01*
G01X905512Y760511D02*
X885827D01*
G01Y759527D02*
X905512D01*
G01X905315Y759330D02*
X886024D01*
G01X905315Y757756D02*
X886024D01*
G01X905512Y757559D02*
X885827D01*
G01Y756574D02*
X905512D01*
G01X909449Y755452D02*
X936614D01*
G01X881890D02*
X870079D01*
G01X905512Y753484D02*
X885827D01*
G01X927953Y751515D02*
X874016D01*
G01X894488Y750334D02*
X927953D01*
G01X883740Y749882D02*
X889095D01*
G01X888788Y749094D02*
X884047D01*
G01X884400Y748307D02*
X888435D01*
G01X894488Y746122D02*
X874016D01*
G01X905512D02*
X894488D01*
G01X884400Y745157D02*
X888435D01*
G01X884047Y744370D02*
X888788D01*
G01X889095Y743582D02*
X883740D01*
G01X924016Y743169D02*
X874016D01*
G01X893701Y740019D02*
X874016D01*
G01Y738248D02*
X893701D01*
G01D02*
X894980D01*
G01X924803D02*
X896358D01*
G01X889764Y735315D02*
X885039D01*
G01X925984D02*
X893701D01*
G01Y735216D02*
X924223D01*
G01X876457D02*
X893701D01*
G01Y733641D02*
X924223D01*
G01X893701D02*
X876457D01*
G01X893701Y733543D02*
X925984D01*
G01X885039D02*
X889764D01*
G01X893701Y730315D02*
X925984D01*
G01X889764D02*
X885039D01*
G01X893701Y730216D02*
X924223D01*
G01X876457D02*
X893701D01*
G01X892519Y970512D02*
X898818D01*
G01X894093Y970807D02*
X892519D01*
G01D02*
X890944D01*
G01Y972776D02*
X892519D01*
G01D02*
X894093D01*
G01X890944Y973366D02*
X892519D01*
G01D02*
X894093D01*
G01Y975335D02*
X892519D01*
G01D02*
X890944D01*
G01X892519Y975630D02*
X898818D01*
G01X890944Y975335D02*
Y973366D01*
G01Y970807D02*
Y972776D01*
G01X892519Y975630D02*
Y975039D01*
G01Y971102D02*
Y970512D01*
G01Y973858D02*
Y972283D01*
G01Y971102D02*
G03Y972283I0J590D01*
G01Y973858D02*
G03Y975039I0J591D01*
G01X897243Y970807D02*
X898818D01*
G01D02*
X900393D01*
G01X898818Y972776D02*
X897243D01*
G01X900393D02*
X898818D01*
G01Y973366D02*
X897243D01*
G01X900393D02*
X898818D01*
G01X898807Y974110D02*
X898714D01*
G01Y974858D02*
X898807D01*
G01X897243Y975335D02*
X898818D01*
G01D02*
X900393D01*
G01X898807Y974238D02*
X898901Y974349D01*
G01Y974222D02*
X898807Y974110D01*
G01X893503Y975630D02*
Y970512D01*
G01X893700D02*
Y975630D01*
G01X894093Y972776D02*
Y970807D01*
G01Y973366D02*
Y975335D01*
G01X897243Y972776D02*
Y970807D01*
G01Y973366D02*
Y975335D01*
G01X897637Y970512D02*
Y975630D01*
G01X897834D02*
Y970512D01*
G01X898714Y974110D02*
Y974858D01*
G01X898807D02*
Y974238D01*
G01X898818Y970512D02*
Y971102D01*
G01Y972283D02*
Y973858D01*
G01Y975039D02*
Y975630D01*
G01X898901Y974349D02*
Y974222D01*
G01X900393Y975335D02*
Y973366D01*
G01Y970807D02*
Y972776D01*
G01X898818Y972283D02*
G03Y971102I0J-591D01*
G01Y975039D02*
G03Y973858I0J-590D01*
G01X886343Y1006771D02*
X886417D01*
G01X886492Y998504D02*
X886417D01*
G01X888976Y1002637D02*
G03I-2558J0D01*
G01X889764D02*
G03I-3346J0D01*
G01X889921D02*
G03I-3503J0D01*
G01X886492Y998504D02*
G03X886417Y1006771I-73J4133D01*
G01X886343Y1006770D02*
G03X886417Y998504I75J-4133D01*
G01X899409Y990826D02*
G03I-3740J0D01*
G01X922561Y1048582D02*
Y1047401D01*
G01Y1051732D02*
Y1050551D01*
G01Y1054882D02*
Y1053700D01*
G01Y1058031D02*
Y1056850D01*
G01Y1061181D02*
Y1060000D01*
G01X921823D02*
Y1061181D01*
G01Y1053700D02*
Y1054882D01*
G01Y1056850D02*
Y1058031D01*
G01Y1050551D02*
Y1051732D01*
G01Y1047401D02*
Y1048582D01*
G01X919366Y1039153D02*
Y1040728D01*
G01Y1034153D02*
Y1035728D01*
G01Y1029153D02*
Y1030728D01*
G01Y1024153D02*
Y1025728D01*
G01Y1019153D02*
Y1020728D01*
G01Y1014153D02*
Y1015728D01*
G01Y1045728D02*
Y1044153D01*
G01X919121D02*
Y1045728D01*
G01Y1039153D02*
Y1040728D01*
G01Y1034153D02*
Y1035728D01*
G01Y1029153D02*
Y1030728D01*
G01Y1024153D02*
Y1025728D01*
G01Y1019153D02*
Y1020728D01*
G01Y1014153D02*
Y1015728D01*
G01X918014D02*
Y1014153D01*
G01Y1020728D02*
Y1019153D01*
G01Y1025728D02*
Y1024153D01*
G01Y1030728D02*
Y1029153D01*
G01Y1035728D02*
Y1034153D01*
G01Y1040728D02*
Y1039153D01*
G01Y1045728D02*
Y1044153D01*
G01X917008Y1059901D02*
Y1061279D01*
G01Y1053602D02*
Y1054980D01*
G01Y1056752D02*
Y1058130D01*
G01Y1050452D02*
Y1051830D01*
G01Y1048681D02*
Y1047303D01*
G01X916265Y1048582D02*
Y1047401D01*
G01Y1051732D02*
Y1050551D01*
G01Y1054882D02*
Y1053700D01*
G01Y1058031D02*
Y1056850D01*
G01Y1061181D02*
Y1060000D01*
G01X915767D02*
Y1061181D01*
G01Y1056850D02*
Y1058031D01*
G01Y1053700D02*
Y1054882D01*
G01Y1050551D02*
Y1051732D01*
G01Y1047401D02*
Y1048582D01*
G01X913528D02*
Y1047401D01*
G01Y1051732D02*
Y1050551D01*
G01Y1054882D02*
Y1053700D01*
G01Y1058031D02*
Y1056850D01*
G01Y1061181D02*
Y1060000D01*
G01X886463Y1048989D02*
X886496Y1048825D01*
G01X886492Y1047401D02*
X886496Y1047382D01*
G01X886463Y1047546D02*
X886492Y1047401D01*
G01X885793Y1047578D02*
X885826Y1047414D01*
G01X884937Y1048582D02*
X884921Y1048661D01*
G01X884955Y1048497D02*
X884937Y1048582D01*
G01X884955Y1046988D02*
X884921Y1047152D01*
G01X879179Y1014829D02*
X879213Y1014665D01*
G01X878509Y1014862D02*
X878543Y1014698D01*
G01X877671Y1014271D02*
X877638Y1014435D01*
G01X886295Y1048956D02*
X886329Y1048825D01*
G01X885821Y1048582D02*
X885793Y1048694D01*
G01X885826Y1048563D02*
X885821Y1048582D01*
G01X885625Y1048956D02*
X885659Y1048825D01*
G01X885625Y1047414D02*
X885591Y1047546D01*
G01X885659Y1047086D02*
X885625Y1047217D01*
G01X885117Y1048582D02*
X885089Y1048694D01*
G01X885122Y1048563D02*
X885117Y1048582D01*
G01X885122Y1047152D02*
X885156Y1047020D01*
G01X878342Y1014698D02*
X878308Y1014829D01*
G01X878375Y1014370D02*
X878342Y1014501D01*
G01X877839Y1014435D02*
X877872Y1014304D01*
G01X886295Y1047414D02*
X886262Y1047513D01*
G01X885826Y1047217D02*
X885859Y1047119D01*
G01X879012Y1014698D02*
X878978Y1014796D01*
G01X878543Y1014501D02*
X878576Y1014402D01*
G01X885692Y1049153D02*
X885726Y1049087D01*
G01X885558D02*
X885625Y1048956D01*
G01X885759Y1048366D02*
X885726Y1048432D01*
G01Y1047709D02*
X885793Y1047578D01*
G01X885189Y1048432D02*
X885122Y1048563D01*
G01X885726Y1046955D02*
X885659Y1047086D01*
G01X878442Y1014993D02*
X878509Y1014862D01*
G01X878442Y1014239D02*
X878375Y1014370D01*
G01X886362Y1049153D02*
X886463Y1048989D01*
G01X885056Y1048333D02*
X884955Y1048497D01*
G01X885056Y1046824D02*
X884955Y1046988D01*
G01X885591Y1047546D02*
X885524Y1047644D01*
G01X885859Y1047119D02*
X885927Y1047020D01*
G01X886195Y1049087D02*
X886295Y1048956D01*
G01X885591Y1049284D02*
X885692Y1049153D01*
G01X885927Y1048432D02*
X885826Y1048563D01*
G01X886362Y1047677D02*
X886463Y1047546D01*
G01X878978Y1014402D02*
X879012Y1014501D01*
G01X886262Y1047119D02*
X886295Y1047217D01*
G01X879213Y1014501D02*
X879179Y1014370D01*
G01X886496Y1047217D02*
X886463Y1047086D01*
G01X877872Y1014829D02*
X877839Y1014698D01*
G01X886329Y1048694D02*
X886300Y1048582D01*
G01D02*
X886295Y1048563D01*
G01X885793Y1048825D02*
X885826Y1048956D01*
G01X885659Y1048694D02*
X885630Y1048582D01*
G01D02*
X885625Y1048563D01*
G01X885156Y1047546D02*
X885122Y1047414D01*
G01X885089Y1048825D02*
X885122Y1048956D01*
G01X886496Y1048694D02*
X886473Y1048582D01*
G01D02*
X886463Y1048530D01*
G01X884921Y1047414D02*
X884955Y1047578D01*
G01X884921Y1048858D02*
X884955Y1049022D01*
G01X877638Y1014698D02*
X877671Y1014862D01*
G01X909449Y993917D02*
Y980964D01*
G01X905512Y997854D02*
Y1157027D01*
G01Y984901D02*
Y997854D01*
G01X905315Y990039D02*
Y991614D01*
G01X899961D02*
Y990039D01*
G01X898622Y991614D02*
Y991811D01*
G01Y989842D02*
Y990039D01*
G01Y991614D02*
Y990039D01*
G01X898425Y991614D02*
Y990039D01*
G01X897638Y1143759D02*
Y1011122D01*
G01X896850Y991614D02*
Y990039D01*
G01X896457Y1045236D02*
Y1069645D01*
G01X896358Y1011122D02*
Y1143759D01*
G01X894980D02*
Y1011122D01*
G01X894488Y997854D02*
Y1006200D01*
G01Y991614D02*
Y990039D01*
G01X893701Y1009350D02*
Y1047401D01*
G01Y1048582D02*
Y1047401D01*
G01Y1050551D02*
Y1048582D01*
G01Y1053700D02*
Y1051732D01*
G01D02*
Y1050551D01*
G01Y1056850D02*
Y1054882D01*
G01D02*
Y1053700D01*
G01Y1058031D02*
Y1056850D01*
G01Y1060000D02*
Y1058031D01*
G01Y1061181D02*
Y1060000D01*
G01X892913Y990039D02*
Y991614D01*
G01X892717D02*
Y991811D01*
G01Y990039D02*
Y991614D01*
G01Y990039D02*
Y989842D01*
G01X891811Y1060000D02*
Y1061181D01*
G01Y1056850D02*
Y1058031D01*
G01Y1053700D02*
Y1054882D01*
G01Y1050551D02*
Y1051732D01*
G01Y1047401D02*
Y1048582D01*
G01X891378Y990039D02*
Y991614D01*
G01X890236Y1060000D02*
Y1061181D01*
G01Y1056850D02*
Y1058031D01*
G01Y1053700D02*
Y1054882D01*
G01Y1050551D02*
Y1051732D01*
G01Y1047401D02*
Y1048582D01*
G01X889764Y1045728D02*
Y1045826D01*
G01Y1044153D02*
Y1045728D01*
G01Y1044055D02*
Y1044153D01*
G01Y1040728D02*
Y1040826D01*
G01Y1039153D02*
Y1040728D01*
G01Y1039055D02*
Y1039153D01*
G01Y1035728D02*
Y1035826D01*
G01Y1034055D02*
Y1034153D01*
G01D02*
Y1035728D01*
G01Y1030728D02*
Y1030826D01*
G01Y1029055D02*
Y1029153D01*
G01D02*
Y1030728D01*
G01Y1025728D02*
Y1025826D01*
G01Y1024055D02*
Y1024153D01*
G01D02*
Y1025728D01*
G01Y1020728D02*
Y1020826D01*
G01Y1019055D02*
Y1019153D01*
G01D02*
Y1020728D01*
G01Y1015728D02*
Y1015826D01*
G01Y1014055D02*
Y1014153D01*
G01D02*
Y1015728D01*
G01X889449Y1048582D02*
Y1047401D01*
G01Y1051732D02*
Y1050551D01*
G01Y1054882D02*
Y1053700D01*
G01Y1058031D02*
Y1056850D01*
G01Y1061181D02*
Y1060000D01*
G01X889055Y1048582D02*
Y1047401D01*
G01Y1051732D02*
Y1050551D01*
G01Y1058031D02*
Y1056850D01*
G01Y1054882D02*
Y1053700D01*
G01Y1061181D02*
Y1060000D01*
G01X888976Y1055669D02*
Y1056063D01*
G01Y1058819D02*
Y1059212D01*
G01Y1052519D02*
Y1052913D01*
G01Y1046417D02*
Y1046614D01*
G01Y1049370D02*
Y1049763D01*
G01X886811Y1038819D02*
Y1036063D01*
G01X886496Y1047382D02*
Y1047217D01*
G01Y1048825D02*
Y1048694D01*
G01X886329Y1048825D02*
Y1048694D01*
G01X886295Y1047217D02*
Y1047401D01*
G01D02*
Y1047414D01*
G01X886128Y1047611D02*
Y1047808D01*
G01X886024Y991614D02*
Y990039D01*
G01X885827Y984901D02*
Y997854D01*
G01X885826Y1047401D02*
Y1047217D01*
G01Y1047414D02*
Y1047401D01*
G01X885793Y1048694D02*
Y1048825D01*
G01X885659D02*
Y1048694D01*
G01X885630Y1045826D02*
Y1046417D01*
G01X885625Y1047217D02*
Y1047401D01*
G01D02*
Y1047414D01*
G01X885357Y1046889D02*
Y1046693D01*
G01X885122Y1047401D02*
Y1047152D01*
G01Y1047414D02*
Y1047401D01*
G01X885089Y1048694D02*
Y1048825D01*
G01X884921Y1047152D02*
Y1047401D01*
G01Y1048661D02*
Y1048858D01*
G01Y1047401D02*
Y1047414D01*
G01X884449Y1060000D02*
Y1061181D01*
G01Y1053700D02*
Y1054882D01*
G01Y1056850D02*
Y1058031D01*
G01Y1050551D02*
Y1051732D01*
G01Y1047401D02*
Y1048582D01*
G01X884134Y1044153D02*
Y1045728D01*
G01Y1039153D02*
Y1040728D01*
G01Y1034153D02*
Y1035728D01*
G01Y1029153D02*
Y1030728D01*
G01Y1024153D02*
Y1025728D01*
G01Y1019153D02*
Y1020728D01*
G01Y1014153D02*
Y1015728D01*
G01X882559Y1044153D02*
Y1045728D01*
G01Y1039153D02*
Y1040728D01*
G01Y1034153D02*
Y1035728D01*
G01Y1029153D02*
Y1030728D01*
G01Y1024153D02*
Y1025728D01*
G01Y1019153D02*
Y1020728D01*
G01Y1014153D02*
Y1015728D01*
G01X881890Y1042008D02*
Y1042874D01*
G01Y1037008D02*
Y1037874D01*
G01Y1032008D02*
Y1032874D01*
G01Y1027008D02*
Y1027874D01*
G01Y1022008D02*
Y1022874D01*
G01Y1017008D02*
Y1017874D01*
G01Y1011122D02*
Y1012874D01*
G01Y980964D02*
Y993917D01*
G01X881772Y1015728D02*
Y1014153D01*
G01Y1020728D02*
Y1019153D01*
G01Y1025728D02*
Y1024153D01*
G01Y1030728D02*
Y1029153D01*
G01Y1035728D02*
Y1034153D01*
G01Y1040728D02*
Y1039153D01*
G01Y1045728D02*
Y1044153D01*
G01X881378Y1015728D02*
Y1014153D01*
G01Y1020728D02*
Y1019153D01*
G01Y1025728D02*
Y1024153D01*
G01Y1030728D02*
Y1029153D01*
G01Y1035728D02*
Y1034153D01*
G01Y1040728D02*
Y1039153D01*
G01Y1045728D02*
Y1044153D01*
G01X879213Y1015728D02*
Y1015846D01*
G01Y1015649D02*
Y1015728D01*
G01Y1014665D02*
Y1014501D01*
G01X879012D02*
Y1014698D01*
G01X878844Y1014895D02*
Y1015091D01*
G01X878543Y1014698D02*
Y1014501D01*
G01X878342D02*
Y1014698D01*
G01X878074Y1014153D02*
Y1013976D01*
G01Y1014173D02*
Y1014153D01*
G01X877839Y1014698D02*
Y1014435D01*
G01X877638D02*
Y1014698D01*
G01Y1015846D02*
Y1015728D01*
G01D02*
Y1015649D01*
G01X876457Y1044153D02*
Y1045728D01*
G01Y1039153D02*
Y1040728D01*
G01Y1034153D02*
Y1035728D01*
G01Y1029153D02*
Y1030728D01*
G01Y1024153D02*
Y1025728D01*
G01Y1019153D02*
Y1020728D01*
G01Y1014153D02*
Y1015728D01*
G01X874016Y997854D02*
Y1011122D01*
G01X870079Y1160964D02*
Y993917D01*
G01X877772Y1014107D02*
X877744Y1014153D01*
G01D02*
X877671Y1014271D01*
G01X878308Y1014829D02*
X878241Y1014928D01*
G01X878576Y1014402D02*
X878643Y1014304D01*
G01X879079Y1014960D02*
X879179Y1014829D01*
G01X886262Y1049252D02*
X886362Y1049153D01*
G01X885859Y1048267D02*
X885759Y1048366D01*
G01X886262Y1047513D02*
X886195Y1047578D01*
G01X885591Y1047841D02*
X885726Y1047709D01*
G01X885156Y1048235D02*
X885056Y1048333D01*
G01X885859Y1046824D02*
X885726Y1046955D01*
G01X885156Y1047020D02*
X885256Y1046922D01*
G01X878978Y1014796D02*
X878911Y1014862D01*
G01X878308Y1015124D02*
X878442Y1014993D01*
G01X878576Y1014107D02*
X878529Y1014153D01*
G01D02*
X878442Y1014239D01*
G01X877872Y1014304D02*
X877973Y1014206D01*
G01X885424Y1049186D02*
X885558Y1049087D01*
G01X886228Y1047775D02*
X886362Y1047677D01*
G01X885324Y1048333D02*
X885189Y1048432D01*
G01X886094Y1049153D02*
X886195Y1049087D01*
G01X886027Y1048366D02*
X885927Y1048432D01*
G01X885524Y1047644D02*
X885424Y1047709D01*
G01X886295Y1048563D02*
X886195Y1048432D01*
G01X885692Y1048366D02*
X885591Y1048235D01*
G01X885826Y1048956D02*
X885927Y1049087D01*
G01X878911Y1014304D02*
X878978Y1014402D01*
G01X877939Y1014928D02*
X877872Y1014829D01*
G01X886195Y1047020D02*
X886262Y1047119D01*
G01X885223Y1047644D02*
X885156Y1047546D01*
G01X886463Y1048530D02*
X886362Y1048366D01*
G01X884955Y1049022D02*
X885056Y1049186D01*
G01X879179Y1014370D02*
X879112Y1014239D01*
G01X877671Y1014862D02*
X877739Y1014993D01*
G01X886463Y1047086D02*
X886396Y1046955D01*
G01X885726Y1048432D02*
X885692Y1048366D01*
G01X885625Y1048563D02*
X885558Y1048432D01*
G01X884955Y1047578D02*
X885022Y1047709D01*
G01X885726Y1049087D02*
X885759Y1049153D01*
G01X885122Y1048956D02*
X885189Y1049087D01*
G01X878945Y1015059D02*
X879079Y1014960D01*
G01X878241Y1014928D02*
X878141Y1014993D01*
G01X885223Y1046725D02*
X885056Y1046824D01*
G01X877939Y1014009D02*
X877772Y1014107D01*
G01X885994Y1048202D02*
X885859Y1048267D01*
G01X886195Y1047578D02*
X886128Y1047611D01*
G01X885458Y1047906D02*
X885591Y1047841D01*
G01X878911Y1014862D02*
X878844Y1014895D01*
G01X878174Y1015190D02*
X878308Y1015124D01*
G01X886094Y1049317D02*
X886262Y1049252D01*
G01X885424Y1049350D02*
X885591Y1049284D01*
G01X885324Y1048169D02*
X885156Y1048235D01*
G01X881890Y1042008D02*
X885039Y1040826D01*
G01X881890Y1037008D02*
X885039Y1035826D01*
G01X886128Y1047808D02*
X886228Y1047775D01*
G01X888976Y1058819D02*
X891339Y1058130D01*
G01X878040Y1014993D02*
X877939Y1014928D01*
G01X885558Y1048432D02*
X885424Y1048333D01*
G01X885189Y1049087D02*
X885324Y1049186D01*
G01X878978Y1015452D02*
X879213Y1015649D01*
G01X878945D02*
X878710Y1015452D01*
G01X879025Y1014153D02*
X878978Y1014107D01*
G01X879112Y1014239D02*
X879025Y1014153D01*
G01X877739Y1014993D02*
X877872Y1015124D01*
G01X886396Y1046955D02*
X886262Y1046824D01*
G01X886362Y1048366D02*
X886262Y1048267D01*
G01X885022Y1047709D02*
X885156Y1047841D01*
G01X885759Y1049153D02*
X885859Y1049252D01*
G01X885056Y1049186D02*
X885156Y1049284D01*
G01X881890Y1032008D02*
X885039Y1030826D01*
G01X881890Y1027008D02*
X885039Y1025826D01*
G01X881890Y1022008D02*
X885039Y1020826D01*
G01X881890Y1017008D02*
X885039Y1015826D01*
G01X885927Y1047020D02*
X886027Y1046988D01*
G01X885256Y1046922D02*
X885357Y1046889D01*
G01X878844Y1015091D02*
X878945Y1015059D01*
G01X878643Y1014304D02*
X878744Y1014271D01*
G01X877973Y1014206D02*
X878074Y1014173D01*
G01X888976Y1055669D02*
X891339Y1054980D01*
G01X888976Y1052519D02*
X891339Y1051830D01*
G01X888976Y1049370D02*
X891339Y1048681D01*
G01X885994Y1046791D02*
X885859Y1046824D01*
G01X885357Y1046693D02*
X885223Y1046725D01*
G01X878710Y1014074D02*
X878576Y1014107D01*
G01X878074Y1013976D02*
X877939Y1014009D01*
G01X878811Y1014271D02*
X878911Y1014304D01*
G01X885039Y1014055D02*
X881890Y1012874D01*
G01X885039Y1019055D02*
X881890Y1017874D01*
G01X885039Y1024055D02*
X881890Y1022874D01*
G01X885039Y1029055D02*
X881890Y1027874D01*
G01X885039Y1034055D02*
X881890Y1032874D01*
G01X885039Y1039055D02*
X881890Y1037874D01*
G01X877872Y1015124D02*
X878007Y1015190D01*
G01X885156Y1047841D02*
X885290Y1047906D01*
G01X885859Y1049252D02*
X885994Y1049317D01*
G01X885324Y1047709D02*
X885223Y1047644D01*
G01X886195Y1048432D02*
X886094Y1048366D01*
G01X885927Y1049087D02*
X886027Y1049153D01*
G01X884449Y1060000D02*
X896457D01*
G01X922561D02*
X896457D01*
G01Y1059901D02*
X925787D01*
G01X891339D02*
X893701D01*
G01X896457Y1058130D02*
X925787D01*
G01X891339D02*
X893701D01*
G01X896457Y1058031D02*
X922561D01*
G01X884449D02*
X896457D01*
G01X884449Y1056850D02*
X896457D01*
G01X922561D02*
X896457D01*
G01Y1056752D02*
X925787D01*
G01X891339D02*
X893701D01*
G01X896457Y1054980D02*
X925787D01*
G01X891339D02*
X893701D01*
G01X896457Y1054882D02*
X922561D01*
G01X884449D02*
X896457D01*
G01X884449Y1053700D02*
X896457D01*
G01X922561D02*
X896457D01*
G01Y1053602D02*
X925787D01*
G01X891339D02*
X893701D01*
G01X896457Y1051830D02*
X925787D01*
G01X891339D02*
X893701D01*
G01X896457Y1051732D02*
X922561D01*
G01X884449D02*
X896457D01*
G01X884449Y1050551D02*
X896457D01*
G01X922561D02*
X896457D01*
G01Y1050452D02*
X925787D01*
G01X891339D02*
X893701D01*
G01X885324Y1049350D02*
X885424D01*
G01X885994Y1049317D02*
X886094D01*
G01X885324Y1049186D02*
X885424D01*
G01X886027Y1049153D02*
X886094D01*
G01X891339Y1048681D02*
X893701D01*
G01X925787D02*
X896457D01*
G01Y1048582D02*
X922561D01*
G01X884449D02*
X896457D01*
G01X886094Y1048366D02*
X886027D01*
G01X885424Y1048333D02*
X885324D01*
G01X886094Y1048202D02*
X885994D01*
G01X885424Y1048169D02*
X885324D01*
G01X885290Y1047906D02*
X885458D01*
G01X885424Y1047709D02*
X885324D01*
G01X924016Y1047677D02*
X905512D01*
G01X884449Y1047401D02*
X896457D01*
G01X922561D02*
X896457D01*
G01X891339Y1047303D02*
X893701D01*
G01X925787D02*
X896457D01*
G01X886027Y1046988D02*
X886094D01*
G01X886128Y1046791D02*
X885994D01*
G01X885630Y1046417D02*
X888976D01*
G01X889764Y1045826D02*
X885630D01*
G01X923032D02*
X893701D01*
G01Y1045728D02*
X924102D01*
G01X876457D02*
X893701D01*
G01Y1045236D02*
X925984D01*
G01X893701Y1044153D02*
X876457D01*
G01X924102D02*
X893701D01*
G01Y1044055D02*
X923032D01*
G01X885039D02*
X889764D01*
G01Y1040826D02*
X885039D01*
G01X925984D02*
X893701D01*
G01Y1040728D02*
X924223D01*
G01X876457D02*
X893701D01*
G01Y1039153D02*
X924223D01*
G01X893701D02*
X876457D01*
G01X893701Y1039055D02*
X925984D01*
G01X885039D02*
X889764D01*
G01X886811Y1038819D02*
X893701D01*
G01Y1036063D02*
X886811D01*
G01X893701Y1035826D02*
X925984D01*
G01X889764D02*
X885039D01*
G01X893701Y1035728D02*
X924223D01*
G01X876457D02*
X893701D01*
G01Y1034153D02*
X924223D01*
G01X893701D02*
X876457D01*
G01X893701Y1034055D02*
X925984D01*
G01X885039D02*
X889764D01*
G01X893701Y1030826D02*
X925984D01*
G01X889764D02*
X885039D01*
G01X893701Y1030728D02*
X924223D01*
G01X876457D02*
X893701D01*
G01Y1029153D02*
X924223D01*
G01X893701D02*
X876457D01*
G01X893701Y1029055D02*
X925984D01*
G01X885039D02*
X889764D01*
G01X893701Y1025826D02*
X925984D01*
G01X889764D02*
X885039D01*
G01X893701Y1025728D02*
X924223D01*
G01X876457D02*
X893701D01*
G01Y1024153D02*
X924223D01*
G01X893701D02*
X876457D01*
G01X893701Y1024055D02*
X925984D01*
G01X885039D02*
X889764D01*
G01X893701Y1020826D02*
X925984D01*
G01X889764D02*
X885039D01*
G01X893701Y1020728D02*
X924223D01*
G01X876457D02*
X893701D01*
G01Y1019153D02*
X924223D01*
G01X893701D02*
X876457D01*
G01X893701Y1019055D02*
X925984D01*
G01X885039D02*
X889764D01*
G01X879213Y1015846D02*
X877638D01*
G01X893701Y1015826D02*
X925984D01*
G01X889764D02*
X885039D01*
G01X893701Y1015728D02*
X924223D01*
G01X876457D02*
X893701D01*
G01X877638Y1015649D02*
X878945D01*
G01X878710Y1015452D02*
X878978D01*
G01X878007Y1015190D02*
X878174D01*
G01X878141Y1014993D02*
X878040D01*
G01X878744Y1014271D02*
X878811D01*
G01X893701Y1014153D02*
X924223D01*
G01X893701D02*
X876457D01*
G01X878844Y1014074D02*
X878710D01*
G01X893701Y1014055D02*
X925984D01*
G01X885039D02*
X889764D01*
G01X896358Y1011122D02*
X924803D01*
G01X893701D02*
X894980D01*
G01X893701D02*
X874016D01*
G01Y1009350D02*
X893701D01*
G01X891339Y1047303D02*
X888976Y1046614D01*
G01X891339Y1050452D02*
X888976Y1049763D01*
G01X891339Y1053602D02*
X888976Y1052913D01*
G01X891339Y1056752D02*
X888976Y1056063D01*
G01X891339Y1059901D02*
X888976Y1059212D01*
G01X886094Y1046988D02*
X886195Y1047020D01*
G01X885039Y1044055D02*
X881890Y1042874D01*
G01X886262Y1048267D02*
X886094Y1048202D01*
G01X885591Y1048235D02*
X885424Y1048169D01*
G01X885156Y1049284D02*
X885324Y1049350D01*
G01X874016Y1006200D02*
X924016D01*
G01X894488Y1003248D02*
X905512D01*
G01X874016D02*
X894488D01*
G01X927953Y999035D02*
X894488D01*
G01X927953Y997854D02*
X874016D01*
G01X885827Y995885D02*
X905512D01*
G01X870079Y993917D02*
X881890D01*
G01X936614D02*
X909449D01*
G01X905512Y992795D02*
X885827D01*
G01Y991811D02*
X905512D01*
G01X905315Y991614D02*
X886024D01*
G01X905315Y990039D02*
X886024D01*
G01X905512Y989842D02*
X885827D01*
G01Y988858D02*
X905512D01*
G01X885827Y986870D02*
X905512D01*
G01X885827Y984901D02*
X905512D01*
G01X909449Y980964D02*
X881890D01*
G01X886262Y1046824D02*
X886128Y1046791D01*
G01X878978Y1014107D02*
X878844Y1014074D01*
G01X922561Y1067480D02*
Y1066299D01*
G01Y1064330D02*
Y1063149D01*
G01X921823Y1066299D02*
Y1067480D01*
G01Y1063149D02*
Y1064330D01*
G01X919366Y1139153D02*
Y1140728D01*
G01Y1134153D02*
Y1135728D01*
G01Y1129153D02*
Y1130728D01*
G01Y1124153D02*
Y1125728D01*
G01Y1119153D02*
Y1120728D01*
G01Y1114153D02*
Y1115728D01*
G01Y1109153D02*
Y1110728D01*
G01Y1104153D02*
Y1105728D01*
G01Y1099153D02*
Y1100728D01*
G01Y1094153D02*
Y1095728D01*
G01Y1089153D02*
Y1090728D01*
G01Y1084153D02*
Y1085728D01*
G01Y1079153D02*
Y1080728D01*
G01Y1074153D02*
Y1075728D01*
G01Y1070728D02*
Y1069153D01*
G01X919121Y1139153D02*
Y1140728D01*
G01Y1134153D02*
Y1135728D01*
G01Y1129153D02*
Y1130728D01*
G01Y1124153D02*
Y1125728D01*
G01Y1119153D02*
Y1120728D01*
G01Y1114153D02*
Y1115728D01*
G01Y1109153D02*
Y1110728D01*
G01Y1104153D02*
Y1105728D01*
G01Y1099153D02*
Y1100728D01*
G01Y1094153D02*
Y1095728D01*
G01Y1089153D02*
Y1090728D01*
G01Y1084153D02*
Y1085728D01*
G01Y1079153D02*
Y1080728D01*
G01Y1074153D02*
Y1075728D01*
G01Y1069153D02*
Y1070728D01*
G01X918014D02*
Y1069153D01*
G01Y1075728D02*
Y1074153D01*
G01Y1080728D02*
Y1079153D01*
G01Y1085728D02*
Y1084153D01*
G01Y1090728D02*
Y1089153D01*
G01Y1095728D02*
Y1094153D01*
G01Y1100728D02*
Y1099153D01*
G01Y1105728D02*
Y1104153D01*
G01Y1110728D02*
Y1109153D01*
G01Y1115728D02*
Y1114153D01*
G01Y1120728D02*
Y1119153D01*
G01Y1125728D02*
Y1124153D01*
G01Y1130728D02*
Y1129153D01*
G01Y1135728D02*
Y1134153D01*
G01Y1140728D02*
Y1139153D01*
G01X917008Y1063051D02*
Y1064429D01*
G01Y1067578D02*
Y1066200D01*
G01X916265Y1067480D02*
Y1066299D01*
G01Y1064330D02*
Y1063149D01*
G01X915767Y1066299D02*
Y1067480D01*
G01Y1063149D02*
Y1064330D01*
G01X913528Y1067480D02*
Y1066299D01*
G01Y1064330D02*
Y1063149D01*
G01X879252Y1069803D02*
X879219Y1069967D01*
G01X879051Y1069934D02*
X879085Y1069835D01*
G01X879219Y1069967D02*
X879118Y1070098D01*
G01X878582Y1069835D02*
X878615Y1069934D01*
G01X878415Y1069967D02*
X878381Y1069803D01*
G01X894882Y1122578D02*
Y1127303D01*
G01Y1082578D02*
Y1087303D01*
G01X893701Y1125728D02*
Y1145531D01*
G01Y1085728D02*
Y1124153D01*
G01Y1067480D02*
Y1084153D01*
G01Y1063149D02*
Y1061181D01*
G01Y1066299D02*
Y1064330D01*
G01D02*
Y1063149D01*
G01Y1067480D02*
Y1066299D01*
G01Y1085728D02*
Y1084153D01*
G01Y1125728D02*
Y1124153D01*
G01X891811Y1066299D02*
Y1067480D01*
G01Y1063149D02*
Y1064330D01*
G01X891732Y1125728D02*
Y1125826D01*
G01Y1124153D02*
Y1125728D01*
G01Y1124055D02*
Y1124153D01*
G01Y1085728D02*
Y1085826D01*
G01Y1084055D02*
Y1084153D01*
G01D02*
Y1085728D01*
G01X890236Y1066299D02*
Y1067480D01*
G01Y1063149D02*
Y1064330D01*
G01X889764Y1140728D02*
Y1140826D01*
G01Y1139055D02*
Y1139153D01*
G01D02*
Y1140728D01*
G01Y1135728D02*
Y1135826D01*
G01Y1134153D02*
Y1135728D01*
G01Y1134055D02*
Y1134153D01*
G01Y1130728D02*
Y1130826D01*
G01Y1129153D02*
Y1130728D01*
G01Y1129055D02*
Y1129153D01*
G01Y1120728D02*
Y1120826D01*
G01Y1119153D02*
Y1120728D01*
G01Y1119055D02*
Y1119153D01*
G01Y1115728D02*
Y1115826D01*
G01Y1114153D02*
Y1115728D01*
G01Y1114055D02*
Y1114153D01*
G01Y1110728D02*
Y1110826D01*
G01Y1109055D02*
Y1109153D01*
G01D02*
Y1110728D01*
G01Y1105728D02*
Y1105826D01*
G01Y1104055D02*
Y1104153D01*
G01D02*
Y1105728D01*
G01Y1100728D02*
Y1100826D01*
G01Y1099055D02*
Y1099153D01*
G01D02*
Y1100728D01*
G01Y1095728D02*
Y1095826D01*
G01Y1094055D02*
Y1094153D01*
G01D02*
Y1095728D01*
G01Y1090728D02*
Y1090826D01*
G01Y1089055D02*
Y1089153D01*
G01D02*
Y1090728D01*
G01Y1080728D02*
Y1080826D01*
G01Y1079055D02*
Y1079153D01*
G01D02*
Y1080728D01*
G01Y1075728D02*
Y1075826D01*
G01Y1074055D02*
Y1074153D01*
G01D02*
Y1075728D01*
G01Y1070728D02*
Y1070826D01*
G01Y1069055D02*
Y1069153D01*
G01D02*
Y1070728D01*
G01X889449Y1067480D02*
Y1066299D01*
G01Y1064330D02*
Y1063149D01*
G01X889055Y1067480D02*
Y1066299D01*
G01Y1064330D02*
Y1063149D01*
G01X888976Y1068267D02*
Y1068464D01*
G01Y1065118D02*
Y1065511D01*
G01Y1061968D02*
Y1062362D01*
G01X886811Y1073819D02*
Y1071063D01*
G01Y1098819D02*
Y1096063D01*
G01Y1123819D02*
Y1121063D01*
G01X885630Y1068464D02*
Y1069055D01*
G01X884449Y1066299D02*
Y1067480D01*
G01Y1063149D02*
Y1064330D01*
G01X884134Y1139153D02*
Y1140728D01*
G01Y1134153D02*
Y1135728D01*
G01Y1129153D02*
Y1130728D01*
G01Y1124153D02*
Y1125728D01*
G01Y1119153D02*
Y1120728D01*
G01Y1114153D02*
Y1115728D01*
G01Y1109153D02*
Y1110728D01*
G01Y1104153D02*
Y1105728D01*
G01Y1099153D02*
Y1100728D01*
G01Y1094153D02*
Y1095728D01*
G01Y1089153D02*
Y1090728D01*
G01Y1084153D02*
Y1085728D01*
G01Y1079153D02*
Y1080728D01*
G01Y1074153D02*
Y1075728D01*
G01Y1069153D02*
Y1070728D01*
G01X882559Y1139153D02*
Y1140728D01*
G01Y1134153D02*
Y1135728D01*
G01Y1129153D02*
Y1130728D01*
G01Y1124153D02*
Y1125728D01*
G01Y1119153D02*
Y1120728D01*
G01Y1114153D02*
Y1115728D01*
G01Y1109153D02*
Y1110728D01*
G01Y1104153D02*
Y1105728D01*
G01Y1099153D02*
Y1100728D01*
G01Y1094153D02*
Y1095728D01*
G01Y1089153D02*
Y1090728D01*
G01Y1084153D02*
Y1085728D01*
G01Y1079153D02*
Y1080728D01*
G01Y1074153D02*
Y1075728D01*
G01Y1069153D02*
Y1070728D01*
G01X881890Y1142008D02*
Y1143759D01*
G01Y1137008D02*
Y1137874D01*
G01Y1132008D02*
Y1132874D01*
G01Y1127008D02*
Y1127874D01*
G01Y1122008D02*
Y1122874D01*
G01Y1117008D02*
Y1117874D01*
G01Y1112008D02*
Y1112874D01*
G01Y1107008D02*
Y1107874D01*
G01Y1102008D02*
Y1102874D01*
G01Y1097008D02*
Y1097874D01*
G01Y1092008D02*
Y1092874D01*
G01Y1087008D02*
Y1087874D01*
G01Y1082008D02*
Y1082874D01*
G01Y1077008D02*
Y1077874D01*
G01Y1072008D02*
Y1072874D01*
G01X881772Y1070728D02*
Y1069153D01*
G01Y1075728D02*
Y1074153D01*
G01Y1080728D02*
Y1079153D01*
G01Y1085728D02*
Y1084153D01*
G01Y1090728D02*
Y1089153D01*
G01Y1095728D02*
Y1094153D01*
G01Y1100728D02*
Y1099153D01*
G01Y1105728D02*
Y1104153D01*
G01Y1110728D02*
Y1109153D01*
G01Y1115728D02*
Y1114153D01*
G01Y1120728D02*
Y1119153D01*
G01Y1125728D02*
Y1124153D01*
G01Y1130728D02*
Y1129153D01*
G01Y1135728D02*
Y1134153D01*
G01Y1140728D02*
Y1139153D01*
G01X881378Y1070728D02*
Y1069153D01*
G01Y1075728D02*
Y1074153D01*
G01Y1080728D02*
Y1079153D01*
G01Y1085728D02*
Y1084153D01*
G01Y1090728D02*
Y1089153D01*
G01Y1095728D02*
Y1094153D01*
G01Y1100728D02*
Y1099153D01*
G01Y1105728D02*
Y1104153D01*
G01Y1110728D02*
Y1109153D01*
G01Y1115728D02*
Y1114153D01*
G01Y1120728D02*
Y1119153D01*
G01Y1125728D02*
Y1124153D01*
G01Y1130728D02*
Y1129153D01*
G01Y1135728D02*
Y1134153D01*
G01Y1140728D02*
Y1139153D01*
G01X879252Y1070728D02*
Y1070885D01*
G01Y1069015D02*
Y1069153D01*
G01Y1070689D02*
Y1070728D01*
G01Y1069153D02*
Y1069803D01*
G01X879085Y1069835D02*
Y1069212D01*
G01X878582D02*
Y1069835D01*
G01X878381Y1069803D02*
Y1069212D01*
G01X877677Y1070885D02*
Y1070728D01*
G01Y1069153D02*
Y1069015D01*
G01Y1070728D02*
Y1070689D01*
G01Y1069212D02*
Y1069153D01*
G01X876457Y1139153D02*
Y1140728D01*
G01Y1134153D02*
Y1135728D01*
G01Y1129153D02*
Y1130728D01*
G01Y1119153D02*
Y1120728D01*
G01Y1114153D02*
Y1115728D01*
G01Y1109153D02*
Y1110728D01*
G01Y1104153D02*
Y1105728D01*
G01Y1099153D02*
Y1100728D01*
G01Y1094153D02*
Y1095728D01*
G01Y1089153D02*
Y1090728D01*
G01Y1079153D02*
Y1080728D01*
G01Y1074153D02*
Y1075728D01*
G01X875000Y1124153D02*
Y1125728D01*
G01Y1084153D02*
Y1085728D01*
G01Y1069153D02*
Y1070728D01*
G01X878984Y1070000D02*
X879051Y1069934D01*
G01X879118Y1070098D02*
X878984Y1070196D01*
G01X881890Y1142008D02*
X885039Y1140826D01*
G01X881890Y1137008D02*
X885039Y1135826D01*
G01X881890Y1132008D02*
X885039Y1130826D01*
G01X881890Y1122008D02*
X885039Y1120826D01*
G01X881890Y1117008D02*
X885039Y1115826D01*
G01X878515Y1070098D02*
X878415Y1069967D01*
G01X881890Y1112008D02*
X885039Y1110826D01*
G01X881890Y1107008D02*
X885039Y1105826D01*
G01X881890Y1102008D02*
X885039Y1100826D01*
G01X881890Y1097008D02*
X885039Y1095826D01*
G01X881890Y1092008D02*
X885039Y1090826D01*
G01X881890Y1082008D02*
X885039Y1080826D01*
G01X881890Y1077008D02*
X885039Y1075826D01*
G01X881890Y1072008D02*
X885039Y1070826D01*
G01X878984Y1070196D02*
X878884Y1070229D01*
G01Y1070032D02*
X878984Y1070000D01*
G01X888976Y1068267D02*
X891339Y1067578D01*
G01X888976Y1065118D02*
X891339Y1064429D01*
G01X888976Y1061968D02*
X891339Y1061279D01*
G01X881890Y1127008D02*
X887008Y1125826D01*
G01X881890Y1087008D02*
X887008Y1085826D01*
G01X879018Y1070492D02*
X879252Y1070689D01*
G01X878984D02*
X878750Y1070492D01*
G01X878615Y1069934D02*
X878683Y1070000D01*
G01X889764Y1140826D02*
X885039D01*
G01X925984D02*
X893701D01*
G01Y1140728D02*
X924223D01*
G01X876457D02*
X893701D01*
G01Y1139153D02*
X924223D01*
G01X893701D02*
X876457D01*
G01X893701Y1139055D02*
X925984D01*
G01X885039D02*
X889764D01*
G01X893701Y1135826D02*
X925984D01*
G01X889764D02*
X885039D01*
G01X893701Y1135728D02*
X924223D01*
G01X876457D02*
X893701D01*
G01Y1134153D02*
X924223D01*
G01X893701D02*
X876457D01*
G01X893701Y1134055D02*
X925984D01*
G01X885039D02*
X889764D01*
G01X893701Y1130826D02*
X925984D01*
G01X889764D02*
X885039D01*
G01X893701Y1130728D02*
X924223D01*
G01X876457D02*
X893701D01*
G01Y1129153D02*
X924223D01*
G01X893701D02*
X876457D01*
G01X893701Y1129055D02*
X925984D01*
G01X885039D02*
X889764D01*
G01X894882Y1127303D02*
X893701D01*
G01X891732Y1125826D02*
X887008D01*
G01X925984D02*
X894882D01*
G01Y1125728D02*
X924223D01*
G01X875000D02*
X894882D01*
G01Y1124153D02*
X924223D01*
G01X875000D02*
X894882D01*
G01Y1124055D02*
X925984D01*
G01X887008D02*
X891732D01*
G01X886811Y1123819D02*
X893701D01*
G01Y1122578D02*
X894882D01*
G01X893701Y1121063D02*
X886811D01*
G01X893701Y1120826D02*
X925984D01*
G01X889764D02*
X885039D01*
G01X893701Y1120728D02*
X924223D01*
G01X876457D02*
X893701D01*
G01Y1119153D02*
X924223D01*
G01X893701D02*
X876457D01*
G01X893701Y1119055D02*
X925984D01*
G01X885039D02*
X889764D01*
G01X893701Y1115826D02*
X925984D01*
G01X889764D02*
X885039D01*
G01X893701Y1115728D02*
X924223D01*
G01X876457D02*
X893701D01*
G01Y1114153D02*
X924223D01*
G01X893701D02*
X876457D01*
G01X893701Y1114055D02*
X925984D01*
G01X885039D02*
X889764D01*
G01X893701Y1110826D02*
X925984D01*
G01X889764D02*
X885039D01*
G01X893701Y1110728D02*
X924223D01*
G01X876457D02*
X893701D01*
G01Y1109153D02*
X924223D01*
G01X893701D02*
X876457D01*
G01X893701Y1109055D02*
X925984D01*
G01X885039D02*
X889764D01*
G01X893701Y1105826D02*
X925984D01*
G01X889764D02*
X885039D01*
G01X893701Y1105728D02*
X924223D01*
G01X876457D02*
X893701D01*
G01Y1104153D02*
X924223D01*
G01X893701D02*
X876457D01*
G01X893701Y1104055D02*
X925984D01*
G01X885039D02*
X889764D01*
G01X893701Y1100826D02*
X925984D01*
G01X889764D02*
X885039D01*
G01X893701Y1100728D02*
X924223D01*
G01X876457D02*
X893701D01*
G01Y1099153D02*
X924223D01*
G01X893701D02*
X876457D01*
G01X893701Y1099055D02*
X925984D01*
G01X885039D02*
X889764D01*
G01X886811Y1098819D02*
X893701D01*
G01Y1096063D02*
X886811D01*
G01X893701Y1095826D02*
X925984D01*
G01X889764D02*
X885039D01*
G01X893701Y1095728D02*
X924223D01*
G01X876457D02*
X893701D01*
G01Y1094153D02*
X924223D01*
G01X893701D02*
X876457D01*
G01X893701Y1094055D02*
X925984D01*
G01X885039D02*
X889764D01*
G01X893701Y1090826D02*
X925984D01*
G01X889764D02*
X885039D01*
G01X893701Y1090728D02*
X924223D01*
G01X876457D02*
X893701D01*
G01Y1089153D02*
X924223D01*
G01X893701D02*
X876457D01*
G01X893701Y1089055D02*
X925984D01*
G01X885039D02*
X889764D01*
G01X894882Y1087303D02*
X893701D01*
G01X891732Y1085826D02*
X887008D01*
G01X925984D02*
X894882D01*
G01Y1085728D02*
X924223D01*
G01X875000D02*
X894882D01*
G01Y1084153D02*
X924223D01*
G01X875000D02*
X894882D01*
G01Y1084055D02*
X925984D01*
G01X887008D02*
X891732D01*
G01X893701Y1082578D02*
X894882D01*
G01X878649Y1070196D02*
X878515Y1070098D01*
G01X893701Y1080826D02*
X925984D01*
G01X889764D02*
X885039D01*
G01X893701Y1080728D02*
X924223D01*
G01X876457D02*
X893701D01*
G01Y1079153D02*
X924223D01*
G01X893701D02*
X876457D01*
G01X893701Y1079055D02*
X925984D01*
G01X885039D02*
X889764D01*
G01X893701Y1075826D02*
X925984D01*
G01X889764D02*
X885039D01*
G01X893701Y1075728D02*
X924223D01*
G01X876457D02*
X893701D01*
G01Y1074153D02*
X876457D01*
G01X924223D02*
X893701D01*
G01Y1074055D02*
X925984D01*
G01X885039D02*
X889764D01*
G01X886811Y1073819D02*
X893701D01*
G01Y1071063D02*
X886811D01*
G01X879252Y1070885D02*
X877677D01*
G01X893701Y1070826D02*
X923032D01*
G01X889764D02*
X885039D01*
G01X893701Y1070728D02*
X924102D01*
G01X875000D02*
X893701D01*
G01X877677Y1070689D02*
X878984D01*
G01X878750Y1070492D02*
X879018D01*
G01X878884Y1070229D02*
X878750D01*
G01X878783Y1070032D02*
X878884D01*
G01X893701Y1069645D02*
X925984D01*
G01X879085Y1069212D02*
X878582D01*
G01X878381D02*
X877677D01*
G01X893701Y1069153D02*
X924102D01*
G01X875000D02*
X893701D01*
G01Y1069055D02*
X923032D01*
G01X885630D02*
X889764D01*
G01X877677Y1069015D02*
X879252D01*
G01X888976Y1068464D02*
X885630D01*
G01X896457Y1067578D02*
X925787D01*
G01X891339D02*
X893701D01*
G01X896457Y1067480D02*
X922561D01*
G01X884449D02*
X896457D01*
G01X905512Y1067204D02*
X924016D01*
G01X884449Y1066299D02*
X896457D01*
G01X922561D02*
X896457D01*
G01Y1066200D02*
X925787D01*
G01X891339D02*
X893701D01*
G01X896457Y1064429D02*
X925787D01*
G01X891339D02*
X893701D01*
G01X896457Y1064330D02*
X922561D01*
G01X884449D02*
X896457D01*
G01X884449Y1063149D02*
X896457D01*
G01X922561D02*
X896457D01*
G01Y1063051D02*
X925787D01*
G01X891339D02*
X893701D01*
G01X896457Y1061279D02*
X925787D01*
G01X891339D02*
X893701D01*
G01X896457Y1061181D02*
X922561D01*
G01X884449D02*
X896457D01*
G01X887008Y1124055D02*
X881890Y1122874D01*
G01X891339Y1063051D02*
X888976Y1062362D01*
G01X891339Y1066200D02*
X888976Y1065511D01*
G01X878683Y1070000D02*
X878783Y1070032D01*
G01X878750Y1070229D02*
X878649Y1070196D01*
G01X885039Y1074055D02*
X881890Y1072874D01*
G01X885039Y1079055D02*
X881890Y1077874D01*
G01X885039Y1089055D02*
X881890Y1087874D01*
G01X885039Y1094055D02*
X881890Y1092874D01*
G01X885039Y1099055D02*
X881890Y1097874D01*
G01X885039Y1104055D02*
X881890Y1102874D01*
G01X885039Y1109055D02*
X881890Y1107874D01*
G01X885039Y1114055D02*
X881890Y1112874D01*
G01X885039Y1119055D02*
X881890Y1117874D01*
G01X887008Y1084055D02*
X881890Y1082874D01*
G01X885039Y1129055D02*
X881890Y1127874D01*
G01X885039Y1134055D02*
X881890Y1132874D01*
G01X885039Y1139055D02*
X881890Y1137874D01*
G01X899409Y1164055D02*
G03I-3740J0D01*
G01X884400Y1153819D02*
G03Y1150669I2017J-1575D01*
G01X888435D02*
G03Y1153819I-2017J1575D01*
G01X888788Y1149882D02*
G03Y1154606I-2371J2362D01*
G01X884047D02*
G03Y1149882I2371J-2362D01*
G01X889921Y1152244D02*
G03I-3503J0D01*
G01X889095Y1149094D02*
G03Y1155393I-2678J3149D01*
G01X883740D02*
G03Y1149094I2678J-3150D01*
G01X909449Y1173917D02*
Y1160964D01*
G01X905512Y1157027D02*
Y1169980D01*
G01X905315Y1163267D02*
Y1164842D01*
G01X899961D02*
Y1163267D01*
G01X898622Y1163070D02*
Y1163267D01*
G01Y1164842D02*
Y1165039D01*
G01Y1164842D02*
Y1163267D01*
G01X898425Y1164842D02*
Y1163267D01*
G01X896850Y1164842D02*
Y1163267D01*
G01X894488Y1148681D02*
Y1157027D01*
G01Y1164842D02*
Y1163267D01*
G01X892913D02*
Y1164842D01*
G01X892717D02*
Y1165039D01*
G01Y1163267D02*
Y1164842D01*
G01Y1163267D02*
Y1163070D01*
G01X891378Y1163267D02*
Y1164842D01*
G01X886024D02*
Y1163267D01*
G01X885827Y1157027D02*
Y1169980D01*
G01X881890Y1160964D02*
Y1173917D01*
G01X874016Y1143759D02*
Y1157027D01*
G01X881890Y1173917D02*
X909449D01*
G01X905512Y1169980D02*
X885827D01*
G01X905512Y1168011D02*
X885827D01*
G01X905512Y1166023D02*
X885827D01*
G01Y1165039D02*
X905512D01*
G01X905315Y1164842D02*
X886024D01*
G01X905315Y1163267D02*
X886024D01*
G01X905512Y1163070D02*
X885827D01*
G01Y1162086D02*
X905512D01*
G01X909449Y1160964D02*
X936614D01*
G01X881890D02*
X870079D01*
G01X905512Y1158996D02*
X885827D01*
G01X927953Y1157027D02*
X874016D01*
G01X894488Y1155846D02*
X927953D01*
G01X883740Y1155393D02*
X889095D01*
G01X888788Y1154606D02*
X884047D01*
G01X884400Y1153819D02*
X888435D01*
G01X894488Y1151633D02*
X874016D01*
G01X905512D02*
X894488D01*
G01X884400Y1150669D02*
X888435D01*
G01X884047Y1149882D02*
X888788D01*
G01X889095Y1149094D02*
X883740D01*
G01X924016Y1148681D02*
X874016D01*
G01X893701Y1145531D02*
X874016D01*
G01Y1143759D02*
X893701D01*
G01D02*
X894980D01*
G01X924803D02*
X896358D01*
G01X890944Y1380846D02*
Y1378878D01*
G01Y1376319D02*
Y1378287D01*
G01X892519Y1381142D02*
Y1380551D01*
G01Y1379370D02*
Y1377795D01*
G01Y1376614D02*
Y1376024D01*
G01D02*
X898818D01*
G01X894093Y1376319D02*
X892519D01*
G01D02*
X890944D01*
G01Y1378287D02*
X892519D01*
G01D02*
X894093D01*
G01X890944Y1378878D02*
X892519D01*
G01D02*
X894093D01*
G01Y1380846D02*
X892519D01*
G01D02*
X890944D01*
G01X892519Y1381142D02*
X898818D01*
G01X892519Y1376614D02*
G03Y1377795I0J591D01*
G01Y1379370D02*
G03Y1380551I0J590D01*
G01X898807Y1379750D02*
X898901Y1379861D01*
G01Y1379733D02*
X898807Y1379622D01*
G01X893503Y1381142D02*
Y1376024D01*
G01X893700D02*
Y1381142D01*
G01X894093Y1378287D02*
Y1376319D01*
G01Y1378878D02*
Y1380846D01*
G01X897243Y1378287D02*
Y1376319D01*
G01Y1378878D02*
Y1380846D01*
G01X897637Y1376024D02*
Y1381142D01*
G01X897834D02*
Y1376024D01*
G01X898714Y1379622D02*
Y1380370D01*
G01X898807D02*
Y1379750D01*
G01X898818Y1376024D02*
Y1376614D01*
G01Y1377795D02*
Y1379370D01*
G01Y1380551D02*
Y1381142D01*
G01X898901Y1379861D02*
Y1379733D01*
G01X900393Y1380846D02*
Y1378878D01*
G01Y1376319D02*
Y1378287D01*
G01X897243Y1376319D02*
X898818D01*
G01D02*
X900393D01*
G01X898818Y1378287D02*
X897243D01*
G01X900393D02*
X898818D01*
G01Y1378878D02*
X897243D01*
G01X900393D02*
X898818D01*
G01X898807Y1379622D02*
X898714D01*
G01Y1380370D02*
X898807D01*
G01X897243Y1380846D02*
X898818D01*
G01D02*
X900393D01*
G01X898818Y1377795D02*
G03Y1376614I0J-591D01*
G01Y1380551D02*
G03Y1379370I0J-591D01*
G01X885827Y1390413D02*
X905512D01*
G01X909449Y1386476D02*
X881890D01*
G01X909449Y1399429D02*
Y1386476D01*
G01X905512Y1390413D02*
Y1403366D01*
G01X885827Y1390413D02*
Y1403366D01*
G01X881890Y1386476D02*
Y1399429D01*
G01X886343Y1412283D02*
X886417D01*
G01X886492Y1404016D02*
X886417Y1404015D01*
G01X899409Y1396338D02*
G03I-3740J0D01*
G01X888976Y1408149D02*
G03I-2558J0D01*
G01X889764D02*
G03I-3346J0D01*
G01X889921D02*
G03I-3503J0D01*
G01X886492Y1404016D02*
G03X886417Y1412283I-73J4133D01*
G01X886343Y1412282D02*
G03X886417Y1404015I73J-4133D01*
G01X886362Y1454665D02*
X886463Y1454501D01*
G01X885056Y1453845D02*
X884955Y1454009D01*
G01X885056Y1452335D02*
X884955Y1452500D01*
G01X885591Y1453058D02*
X885524Y1453156D01*
G01X885859Y1452631D02*
X885927Y1452532D01*
G01X886195Y1454599D02*
X886295Y1454468D01*
G01X885591Y1454796D02*
X885692Y1454665D01*
G01X885927Y1453943D02*
X885826Y1454074D01*
G01X886362Y1453189D02*
X886463Y1453058D01*
G01X886262Y1454763D02*
X886362Y1454665D01*
G01X885859Y1453779D02*
X885759Y1453878D01*
G01X886262Y1453024D02*
X886195Y1453090D01*
G01X885591Y1453353D02*
X885726Y1453221D01*
G01X885156Y1453746D02*
X885056Y1453845D01*
G01X885859Y1452335D02*
X885726Y1452467D01*
G01X885156Y1452532D02*
X885256Y1452434D01*
G01X878978Y1420308D02*
X878911Y1420374D01*
G01X878308Y1420636D02*
X878442Y1420505D01*
G01X878576Y1419619D02*
X878529Y1419665D01*
G01D02*
X878442Y1419750D01*
G01X877872Y1419816D02*
X877973Y1419717D01*
G01X885424Y1454698D02*
X885558Y1454599D01*
G01X886228Y1453287D02*
X886362Y1453189D01*
G01X885324Y1453845D02*
X885189Y1453943D01*
G01X878945Y1420570D02*
X879079Y1420472D01*
G01X886094Y1454665D02*
X886195Y1454599D01*
G01X886027Y1453878D02*
X885927Y1453943D01*
G01X885524Y1453156D02*
X885424Y1453221D01*
G01X878241Y1420439D02*
X878141Y1420505D01*
G01X885223Y1452237D02*
X885056Y1452335D01*
G01X877939Y1419520D02*
X877772Y1419619D01*
G01X885994Y1453713D02*
X885859Y1453779D01*
G01X886195Y1453090D02*
X886128Y1453123D01*
G01X885458Y1453418D02*
X885591Y1453353D01*
G01X886094Y1454829D02*
X886262Y1454763D01*
G01X885424Y1454862D02*
X885591Y1454796D01*
G01X885324Y1453681D02*
X885156Y1453746D01*
G01X881890Y1447519D02*
X885039Y1446338D01*
G01X881890Y1442519D02*
X885039Y1441338D01*
G01X886128Y1453320D02*
X886228Y1453287D01*
G01X885927Y1452532D02*
X886027Y1452500D01*
G01X885256Y1452434D02*
X885357Y1452401D01*
G01X888976Y1473779D02*
X891339Y1473090D01*
G01X888976Y1470630D02*
X891339Y1469941D01*
G01X888976Y1467480D02*
X891339Y1466791D01*
G01X888976Y1464330D02*
X891339Y1463641D01*
G01X888976Y1461181D02*
X891339Y1460492D01*
G01X888976Y1458031D02*
X891339Y1457342D01*
G01X888976Y1454882D02*
X891339Y1454193D01*
G01X886295Y1454468D02*
X886329Y1454337D01*
G01X885821Y1454094D02*
X885793Y1454206D01*
G01X885826Y1454074D02*
X885821Y1454094D01*
G01X885625Y1454468D02*
X885659Y1454337D01*
G01X885625Y1452926D02*
X885591Y1453058D01*
G01X885659Y1452598D02*
X885625Y1452729D01*
G01X885117Y1454094D02*
X885089Y1454206D01*
G01X885122Y1454074D02*
X885117Y1454094D01*
G01X886295Y1452926D02*
X886262Y1453024D01*
G01X885826Y1452729D02*
X885859Y1452631D01*
G01X879012Y1420209D02*
X878978Y1420308D01*
G01X878543Y1420013D02*
X878576Y1419914D01*
G01X885692Y1454665D02*
X885726Y1454599D01*
G01X885558D02*
X885625Y1454468D01*
G01X885759Y1453878D02*
X885726Y1453943D01*
G01Y1453221D02*
X885793Y1453090D01*
G01X885189Y1453943D02*
X885122Y1454074D01*
G01X885726Y1452467D02*
X885659Y1452598D01*
G01X878442Y1420505D02*
X878509Y1420374D01*
G01X878442Y1419750D02*
X878375Y1419882D01*
G01X877772Y1419619D02*
X877744Y1419665D01*
G01D02*
X877671Y1419783D01*
G01X878308Y1420341D02*
X878241Y1420439D01*
G01X878576Y1419914D02*
X878643Y1419816D01*
G01X879079Y1420472D02*
X879179Y1420341D01*
G01X878911Y1420374D02*
X878844Y1420406D01*
G01X878174Y1420702D02*
X878308Y1420636D01*
G01X881890Y1437519D02*
X885039Y1436338D01*
G01X881890Y1432519D02*
X885039Y1431338D01*
G01X881890Y1427519D02*
X885039Y1426338D01*
G01X881890Y1422519D02*
X885039Y1421338D01*
G01X878844Y1420603D02*
X878945Y1420570D01*
G01X878643Y1419816D02*
X878744Y1419783D01*
G01X877973Y1419717D02*
X878074Y1419685D01*
G01X885994Y1452303D02*
X885859Y1452335D01*
G01X885357Y1452204D02*
X885223Y1452237D01*
G01X878710Y1419586D02*
X878576Y1419619D01*
G01X878074Y1419488D02*
X877939Y1419520D01*
G01X896457Y1473090D02*
X925787D01*
G01X891339D02*
X893701D01*
G01X896457Y1472992D02*
X922561D01*
G01X884449D02*
X896457D01*
G01X905512Y1472716D02*
X924016D01*
G01X884449Y1471811D02*
X896457D01*
G01X922561D02*
X896457D01*
G01Y1471712D02*
X925787D01*
G01X891339D02*
X893701D01*
G01X896457Y1469941D02*
X925787D01*
G01X891339D02*
X893701D01*
G01X896457Y1469842D02*
X922561D01*
G01X884449D02*
X896457D01*
G01X884449Y1468661D02*
X896457D01*
G01X922561D02*
X896457D01*
G01Y1468563D02*
X925787D01*
G01X891339D02*
X893701D01*
G01X896457Y1466791D02*
X925787D01*
G01X891339D02*
X893701D01*
G01X896457Y1466693D02*
X922561D01*
G01X884449D02*
X896457D01*
G01X884449Y1465511D02*
X896457D01*
G01X922561D02*
X896457D01*
G01Y1465413D02*
X925787D01*
G01X891339D02*
X893701D01*
G01X896457Y1463641D02*
X925787D01*
G01X891339D02*
X893701D01*
G01X896457Y1463543D02*
X922561D01*
G01X884449D02*
X896457D01*
G01X886463Y1454501D02*
X886496Y1454337D01*
G01X886492Y1452913D02*
X886496Y1452893D01*
G01X886463Y1453058D02*
X886492Y1452913D01*
G01X885793Y1453090D02*
X885826Y1452926D01*
G01X884937Y1454094D02*
X884921Y1454173D01*
G01X884955Y1454009D02*
X884937Y1454094D01*
G01X884955Y1452500D02*
X884921Y1452664D01*
G01X879179Y1420341D02*
X879213Y1420177D01*
G01X878509Y1420374D02*
X878543Y1420209D01*
G01X877671Y1419783D02*
X877638Y1419947D01*
G01X885122Y1452664D02*
X885156Y1452532D01*
G01X878342Y1420209D02*
X878308Y1420341D01*
G01X878375Y1419882D02*
X878342Y1420013D01*
G01X877839Y1419947D02*
X877872Y1419816D01*
G01X884449Y1462362D02*
X896457D01*
G01X922561D02*
X896457D01*
G01Y1462263D02*
X925787D01*
G01X891339D02*
X893701D01*
G01X896457Y1460492D02*
X925787D01*
G01X891339D02*
X893701D01*
G01X896457Y1460393D02*
X922561D01*
G01X884449D02*
X896457D01*
G01X884449Y1459212D02*
X896457D01*
G01X922561D02*
X896457D01*
G01Y1459114D02*
X925787D01*
G01X891339D02*
X893701D01*
G01X896457Y1457342D02*
X925787D01*
G01X891339D02*
X893701D01*
G01X896457Y1457244D02*
X922561D01*
G01X884449D02*
X896457D01*
G01X884449Y1456063D02*
X896457D01*
G01X922561D02*
X896457D01*
G01Y1455964D02*
X925787D01*
G01X891339D02*
X893701D01*
G01X885324Y1454862D02*
X885424D01*
G01X885994Y1454829D02*
X886094D01*
G01X885324Y1454698D02*
X885424D01*
G01X886027Y1454665D02*
X886094D01*
G01X891339Y1454193D02*
X893701D01*
G01X925787D02*
X896457D01*
G01Y1454094D02*
X922561D01*
G01X884449D02*
X896457D01*
G01X886094Y1453878D02*
X886027D01*
G01X885424Y1453845D02*
X885324D01*
G01X886094Y1453713D02*
X885994D01*
G01X885424Y1453681D02*
X885324D01*
G01X885290Y1453418D02*
X885458D01*
G01X885424Y1453221D02*
X885324D01*
G01X924016Y1453189D02*
X905512D01*
G01X884449Y1452913D02*
X896457D01*
G01X922561D02*
X896457D01*
G01X891339Y1452815D02*
X893701D01*
G01X925787D02*
X896457D01*
G01X886027Y1452500D02*
X886094D01*
G01X886128Y1452303D02*
X885994D01*
G01X885630Y1451929D02*
X888976D01*
G01X889764Y1451338D02*
X885630D01*
G01X923032D02*
X893701D01*
G01Y1451240D02*
X924102D01*
G01X876457D02*
X893701D01*
G01Y1450748D02*
X925984D01*
G01X893701Y1449665D02*
X876457D01*
G01X924102D02*
X893701D01*
G01Y1449567D02*
X923032D01*
G01X885039D02*
X889764D01*
G01Y1446338D02*
X885039D01*
G01X925984D02*
X893701D01*
G01Y1446240D02*
X924223D01*
G01X876457D02*
X893701D01*
G01Y1444665D02*
X924223D01*
G01X893701D02*
X876457D01*
G01X893701Y1444567D02*
X925984D01*
G01X885039D02*
X889764D01*
G01X886811Y1444330D02*
X893701D01*
G01Y1441574D02*
X886811D01*
G01X893701Y1441338D02*
X925984D01*
G01X889764D02*
X885039D01*
G01X893701Y1441240D02*
X924223D01*
G01X876457D02*
X893701D01*
G01Y1439665D02*
X924223D01*
G01X893701D02*
X876457D01*
G01X893701Y1439567D02*
X925984D01*
G01X885039D02*
X889764D01*
G01X893701Y1436338D02*
X925984D01*
G01X889764D02*
X885039D01*
G01X893701Y1436240D02*
X924223D01*
G01X876457D02*
X893701D01*
G01Y1434665D02*
X924223D01*
G01X893701D02*
X876457D01*
G01X893701Y1434567D02*
X925984D01*
G01X885039D02*
X889764D01*
G01X893701Y1431338D02*
X925984D01*
G01X889764D02*
X885039D01*
G01X893701Y1431240D02*
X924223D01*
G01X876457D02*
X893701D01*
G01Y1429665D02*
X924223D01*
G01X893701D02*
X876457D01*
G01X893701Y1429567D02*
X925984D01*
G01X885039D02*
X889764D01*
G01X893701Y1426338D02*
X925984D01*
G01X889764D02*
X885039D01*
G01X893701Y1426240D02*
X924223D01*
G01X876457D02*
X893701D01*
G01Y1424665D02*
X924223D01*
G01X893701D02*
X876457D01*
G01X893701Y1424567D02*
X925984D01*
G01X885039D02*
X889764D01*
G01X879213Y1421358D02*
X877638D01*
G01X893701Y1421338D02*
X925984D01*
G01X889764D02*
X885039D01*
G01X893701Y1421240D02*
X924223D01*
G01X876457D02*
X893701D01*
G01X877638Y1421161D02*
X878945D01*
G01X878710Y1420964D02*
X878978D01*
G01X878007Y1420702D02*
X878174D01*
G01X878141Y1420505D02*
X878040D01*
G01X878744Y1419783D02*
X878811D01*
G01X893701Y1419665D02*
X924223D01*
G01X893701D02*
X876457D01*
G01X878844Y1419586D02*
X878710D01*
G01X893701Y1419567D02*
X925984D01*
G01X885039D02*
X889764D01*
G01X896358Y1416633D02*
X924803D01*
G01X893701D02*
X894980D01*
G01X893701D02*
X874016D01*
G01Y1414862D02*
X893701D01*
G01X874016Y1411712D02*
X924016D01*
G01X894488Y1408759D02*
X905512D01*
G01X874016D02*
X894488D01*
G01X927953Y1404547D02*
X894488D01*
G01X927953Y1403366D02*
X874016D01*
G01X885827Y1401397D02*
X905512D01*
G01X870079Y1399429D02*
X881890D01*
G01X936614D02*
X909449D01*
G01X905512Y1398307D02*
X885827D01*
G01Y1397322D02*
X905512D01*
G01X905315Y1397126D02*
X886024D01*
G01X905315Y1395551D02*
X886024D01*
G01X905512Y1395354D02*
X885827D01*
G01Y1394370D02*
X905512D01*
G01X885827Y1392382D02*
X905512D01*
G01X922561Y1454094D02*
Y1452913D01*
G01Y1457244D02*
Y1456063D01*
G01Y1460393D02*
Y1459212D01*
G01Y1463543D02*
Y1462362D01*
G01Y1466693D02*
Y1465511D01*
G01Y1469842D02*
Y1468661D01*
G01Y1472992D02*
Y1471811D01*
G01X921823D02*
Y1472992D01*
G01Y1465511D02*
Y1466693D01*
G01Y1468661D02*
Y1469842D01*
G01Y1462362D02*
Y1463543D01*
G01Y1456063D02*
Y1457244D01*
G01Y1459212D02*
Y1460393D01*
G01Y1452913D02*
Y1454094D01*
G01X919366Y1444665D02*
Y1446240D01*
G01Y1439665D02*
Y1441240D01*
G01Y1434665D02*
Y1436240D01*
G01Y1429665D02*
Y1431240D01*
G01Y1424665D02*
Y1426240D01*
G01Y1419665D02*
Y1421240D01*
G01Y1451240D02*
Y1449665D01*
G01X919121D02*
Y1451240D01*
G01Y1444665D02*
Y1446240D01*
G01Y1439665D02*
Y1441240D01*
G01Y1434665D02*
Y1436240D01*
G01Y1429665D02*
Y1431240D01*
G01Y1424665D02*
Y1426240D01*
G01Y1419665D02*
Y1421240D01*
G01X918014D02*
Y1419665D01*
G01Y1426240D02*
Y1424665D01*
G01Y1431240D02*
Y1429665D01*
G01Y1436240D02*
Y1434665D01*
G01Y1441240D02*
Y1439665D01*
G01Y1446240D02*
Y1444665D01*
G01Y1451240D02*
Y1449665D01*
G01X917008Y1465413D02*
Y1466791D01*
G01Y1468563D02*
Y1469941D01*
G01Y1462263D02*
Y1463641D01*
G01Y1455964D02*
Y1457342D01*
G01Y1459114D02*
Y1460492D01*
G01Y1454193D02*
Y1452815D01*
G01Y1473090D02*
Y1471712D01*
G01X916265Y1454094D02*
Y1452913D01*
G01Y1457244D02*
Y1456063D01*
G01Y1460393D02*
Y1459212D01*
G01Y1463543D02*
Y1462362D01*
G01Y1469842D02*
Y1468661D01*
G01Y1466693D02*
Y1465511D01*
G01Y1472992D02*
Y1471811D01*
G01X915767D02*
Y1472992D01*
G01Y1468661D02*
Y1469842D01*
G01Y1465511D02*
Y1466693D01*
G01Y1462362D02*
Y1463543D01*
G01Y1459212D02*
Y1460393D01*
G01Y1456063D02*
Y1457244D01*
G01Y1452913D02*
Y1454094D01*
G01X913528D02*
Y1452913D01*
G01Y1457244D02*
Y1456063D01*
G01Y1460393D02*
Y1459212D01*
G01Y1463543D02*
Y1462362D01*
G01Y1466693D02*
Y1465511D01*
G01Y1469842D02*
Y1468661D01*
G01Y1472992D02*
Y1471811D01*
G01X886262Y1452335D02*
X886128Y1452303D01*
G01X878978Y1419619D02*
X878844Y1419586D01*
G01X905512Y1403366D02*
Y1562539D01*
G01X905315Y1395551D02*
Y1397126D01*
G01X899961D02*
Y1395551D01*
G01X898622Y1397126D02*
Y1397322D01*
G01Y1395354D02*
Y1395551D01*
G01Y1397126D02*
Y1395551D01*
G01X898425Y1397126D02*
Y1395551D01*
G01X897638Y1549271D02*
Y1416633D01*
G01X896850Y1397126D02*
Y1395551D01*
G01X896457Y1450748D02*
Y1475157D01*
G01X896358Y1416633D02*
Y1549271D01*
G01X894980D02*
Y1416633D01*
G01X894488Y1403366D02*
Y1411712D01*
G01Y1397126D02*
Y1395551D01*
G01X893701Y1472992D02*
Y1489665D01*
G01Y1414862D02*
Y1452913D01*
G01Y1456063D02*
Y1454094D01*
G01D02*
Y1452913D01*
G01Y1459212D02*
Y1457244D01*
G01D02*
Y1456063D01*
G01Y1460393D02*
Y1459212D01*
G01Y1462362D02*
Y1460393D01*
G01Y1465511D02*
Y1463543D01*
G01D02*
Y1462362D01*
G01Y1468661D02*
Y1466693D01*
G01D02*
Y1465511D01*
G01Y1469842D02*
Y1468661D01*
G01Y1471811D02*
Y1469842D01*
G01Y1472992D02*
Y1471811D01*
G01X892913Y1395551D02*
Y1397126D01*
G01X892717D02*
Y1397322D01*
G01Y1395551D02*
Y1397126D01*
G01Y1395551D02*
Y1395354D01*
G01X891811Y1471811D02*
Y1472992D01*
G01Y1468661D02*
Y1469842D01*
G01Y1465511D02*
Y1466693D01*
G01Y1462362D02*
Y1463543D01*
G01Y1456063D02*
Y1457244D01*
G01Y1459212D02*
Y1460393D01*
G01Y1452913D02*
Y1454094D01*
G01X891378Y1395551D02*
Y1397126D01*
G01X890236Y1471811D02*
Y1472992D01*
G01Y1468661D02*
Y1469842D01*
G01Y1465511D02*
Y1466693D01*
G01Y1462362D02*
Y1463543D01*
G01Y1459212D02*
Y1460393D01*
G01Y1456063D02*
Y1457244D01*
G01Y1452913D02*
Y1454094D01*
G01X889764Y1451240D02*
Y1451338D01*
G01Y1449567D02*
Y1449665D01*
G01D02*
Y1451240D01*
G01Y1446240D02*
Y1446338D01*
G01Y1444567D02*
Y1444665D01*
G01D02*
Y1446240D01*
G01Y1441240D02*
Y1441338D01*
G01Y1439567D02*
Y1439665D01*
G01D02*
Y1441240D01*
G01Y1436240D02*
Y1436338D01*
G01Y1434567D02*
Y1434665D01*
G01D02*
Y1436240D01*
G01Y1431240D02*
Y1431338D01*
G01Y1429567D02*
Y1429665D01*
G01D02*
Y1431240D01*
G01Y1426240D02*
Y1426338D01*
G01Y1424567D02*
Y1424665D01*
G01D02*
Y1426240D01*
G01Y1421240D02*
Y1421338D01*
G01Y1419665D02*
Y1421240D01*
G01Y1419567D02*
Y1419665D01*
G01X889449Y1454094D02*
Y1452913D01*
G01Y1457244D02*
Y1456063D01*
G01Y1460393D02*
Y1459212D01*
G01Y1463543D02*
Y1462362D01*
G01Y1466693D02*
Y1465511D01*
G01Y1469842D02*
Y1468661D01*
G01Y1472992D02*
Y1471811D01*
G01X889055Y1454094D02*
Y1452913D01*
G01Y1457244D02*
Y1456063D01*
G01Y1460393D02*
Y1459212D01*
G01Y1463543D02*
Y1462362D01*
G01Y1469842D02*
Y1468661D01*
G01Y1466693D02*
Y1465511D01*
G01Y1472992D02*
Y1471811D01*
G01X888976Y1473779D02*
Y1473976D01*
G01Y1467480D02*
Y1467874D01*
G01Y1470630D02*
Y1471023D01*
G01Y1464330D02*
Y1464724D01*
G01Y1458031D02*
Y1458425D01*
G01Y1461181D02*
Y1461574D01*
G01Y1454882D02*
Y1455275D01*
G01Y1451929D02*
Y1452126D01*
G01X886811Y1444330D02*
Y1441574D01*
G01X886496Y1452893D02*
Y1452729D01*
G01Y1454337D02*
Y1454206D01*
G01X886329Y1454337D02*
Y1454206D01*
G01X886295Y1452729D02*
Y1452913D01*
G01D02*
Y1452926D01*
G01X886128Y1453123D02*
Y1453320D01*
G01X886024Y1397126D02*
Y1395551D01*
G01X885826Y1452913D02*
Y1452729D01*
G01Y1452926D02*
Y1452913D01*
G01X885793Y1454206D02*
Y1454337D01*
G01X885659D02*
Y1454206D01*
G01X885630Y1451338D02*
Y1451929D01*
G01X885625Y1452729D02*
Y1452913D01*
G01D02*
Y1452926D01*
G01X885357Y1452401D02*
Y1452204D01*
G01X885122Y1452913D02*
Y1452664D01*
G01Y1452926D02*
Y1452913D01*
G01X885089Y1454206D02*
Y1454337D01*
G01X884921Y1452664D02*
Y1452913D01*
G01Y1454173D02*
Y1454370D01*
G01Y1452913D02*
Y1452926D01*
G01X884449Y1471811D02*
Y1472992D01*
G01Y1465511D02*
Y1466693D01*
G01Y1468661D02*
Y1469842D01*
G01Y1462362D02*
Y1463543D01*
G01Y1456063D02*
Y1457244D01*
G01Y1459212D02*
Y1460393D01*
G01Y1452913D02*
Y1454094D01*
G01X884134Y1449665D02*
Y1451240D01*
G01Y1444665D02*
Y1446240D01*
G01Y1439665D02*
Y1441240D01*
G01Y1434665D02*
Y1436240D01*
G01Y1429665D02*
Y1431240D01*
G01Y1424665D02*
Y1426240D01*
G01Y1419665D02*
Y1421240D01*
G01X882559Y1449665D02*
Y1451240D01*
G01Y1444665D02*
Y1446240D01*
G01Y1439665D02*
Y1441240D01*
G01Y1434665D02*
Y1436240D01*
G01Y1429665D02*
Y1431240D01*
G01Y1424665D02*
Y1426240D01*
G01Y1419665D02*
Y1421240D01*
G01X881890Y1447519D02*
Y1448385D01*
G01Y1442519D02*
Y1443385D01*
G01Y1437519D02*
Y1438385D01*
G01Y1432519D02*
Y1433385D01*
G01Y1427519D02*
Y1428385D01*
G01Y1422519D02*
Y1423385D01*
G01Y1416633D02*
Y1418385D01*
G01X881772Y1421240D02*
Y1419665D01*
G01Y1426240D02*
Y1424665D01*
G01Y1431240D02*
Y1429665D01*
G01Y1436240D02*
Y1434665D01*
G01Y1441240D02*
Y1439665D01*
G01Y1446240D02*
Y1444665D01*
G01Y1451240D02*
Y1449665D01*
G01X881378Y1421240D02*
Y1419665D01*
G01Y1426240D02*
Y1424665D01*
G01Y1431240D02*
Y1429665D01*
G01Y1436240D02*
Y1434665D01*
G01Y1441240D02*
Y1439665D01*
G01Y1446240D02*
Y1444665D01*
G01Y1451240D02*
Y1449665D01*
G01X879213Y1421240D02*
Y1421358D01*
G01Y1421161D02*
Y1421240D01*
G01Y1420177D02*
Y1420013D01*
G01X879012D02*
Y1420209D01*
G01X878844Y1420406D02*
Y1420603D01*
G01X878543Y1420209D02*
Y1420013D01*
G01X878342D02*
Y1420209D01*
G01X878074Y1419665D02*
Y1419488D01*
G01Y1419685D02*
Y1419665D01*
G01X877839Y1420209D02*
Y1419947D01*
G01X877638D02*
Y1420209D01*
G01Y1421358D02*
Y1421240D01*
G01D02*
Y1421161D01*
G01X876457Y1449665D02*
Y1451240D01*
G01Y1444665D02*
Y1446240D01*
G01Y1439665D02*
Y1441240D01*
G01Y1434665D02*
Y1436240D01*
G01Y1429665D02*
Y1431240D01*
G01Y1424665D02*
Y1426240D01*
G01Y1419665D02*
Y1421240D01*
G01X874016Y1403366D02*
Y1416633D01*
G01X870079Y1566476D02*
Y1399429D01*
G01X879213Y1420013D02*
X879179Y1419882D01*
G01X886496Y1452729D02*
X886463Y1452598D01*
G01X877872Y1420341D02*
X877839Y1420209D01*
G01X886329Y1454206D02*
X886300Y1454094D01*
G01D02*
X886295Y1454074D01*
G01X885793Y1454337D02*
X885826Y1454468D01*
G01X885659Y1454206D02*
X885630Y1454094D01*
G01D02*
X885625Y1454074D01*
G01X885156Y1453058D02*
X885122Y1452926D01*
G01X885089Y1454337D02*
X885122Y1454468D01*
G01X886496Y1454206D02*
X886473Y1454094D01*
G01D02*
X886463Y1454042D01*
G01X884921Y1452926D02*
X884955Y1453090D01*
G01X884921Y1454370D02*
X884955Y1454534D01*
G01X877638Y1420209D02*
X877671Y1420374D01*
G01X878978Y1419914D02*
X879012Y1420013D01*
G01X886262Y1452631D02*
X886295Y1452729D01*
G01X879179Y1419882D02*
X879112Y1419750D01*
G01X877671Y1420374D02*
X877739Y1420505D01*
G01X886463Y1452598D02*
X886396Y1452467D01*
G01X885726Y1453943D02*
X885692Y1453878D01*
G01X885625Y1454074D02*
X885558Y1453943D01*
G01X884955Y1453090D02*
X885022Y1453221D01*
G01X885726Y1454599D02*
X885759Y1454665D01*
G01X885122Y1454468D02*
X885189Y1454599D01*
G01X886295Y1454074D02*
X886195Y1453943D01*
G01X885692Y1453878D02*
X885591Y1453746D01*
G01X885826Y1454468D02*
X885927Y1454599D01*
G01X878911Y1419816D02*
X878978Y1419914D01*
G01X877939Y1420439D02*
X877872Y1420341D01*
G01X886195Y1452532D02*
X886262Y1452631D01*
G01X885223Y1453156D02*
X885156Y1453058D01*
G01X886463Y1454042D02*
X886362Y1453878D01*
G01X884955Y1454534D02*
X885056Y1454698D01*
G01X879025Y1419665D02*
X878978Y1419619D01*
G01X879112Y1419750D02*
X879025Y1419665D01*
G01X877739Y1420505D02*
X877872Y1420636D01*
G01X878978Y1420964D02*
X879213Y1421161D01*
G01X878945D02*
X878710Y1420964D01*
G01X886396Y1452467D02*
X886262Y1452335D01*
G01X886362Y1453878D02*
X886262Y1453779D01*
G01X885022Y1453221D02*
X885156Y1453353D01*
G01X885759Y1454665D02*
X885859Y1454763D01*
G01X885056Y1454698D02*
X885156Y1454796D01*
G01X878040Y1420505D02*
X877939Y1420439D01*
G01X885324Y1453221D02*
X885223Y1453156D01*
G01X886195Y1453943D02*
X886094Y1453878D01*
G01X885927Y1454599D02*
X886027Y1454665D01*
G01X885558Y1453943D02*
X885424Y1453845D01*
G01X885189Y1454599D02*
X885324Y1454698D01*
G01X878811Y1419783D02*
X878911Y1419816D01*
G01X885039Y1419567D02*
X881890Y1418385D01*
G01X885039Y1424567D02*
X881890Y1423385D01*
G01X885039Y1429567D02*
X881890Y1428385D01*
G01X885039Y1434567D02*
X881890Y1433385D01*
G01X885039Y1439567D02*
X881890Y1438385D01*
G01X885039Y1444567D02*
X881890Y1443385D01*
G01X886262Y1453779D02*
X886094Y1453713D01*
G01X885591Y1453746D02*
X885424Y1453681D01*
G01X885156Y1454796D02*
X885324Y1454862D01*
G01X877872Y1420636D02*
X878007Y1420702D01*
G01X885156Y1453353D02*
X885290Y1453418D01*
G01X885859Y1454763D02*
X885994Y1454829D01*
G01X891339Y1452815D02*
X888976Y1452126D01*
G01X891339Y1455964D02*
X888976Y1455275D01*
G01X891339Y1459114D02*
X888976Y1458425D01*
G01X891339Y1462263D02*
X888976Y1461574D01*
G01X891339Y1465413D02*
X888976Y1464724D01*
G01X891339Y1468563D02*
X888976Y1467874D01*
G01X891339Y1471712D02*
X888976Y1471023D01*
G01X886094Y1452500D02*
X886195Y1452532D01*
G01X885039Y1449567D02*
X881890Y1448385D01*
G01X884400Y1559330D02*
G03Y1556181I2017J-1574D01*
G01X888435D02*
G03Y1559330I-2017J1575D01*
G01X888788Y1555393D02*
G03Y1560118I-2370J2362D01*
G01X884047D02*
G03Y1555393I2370J-2363D01*
G01X889921Y1557756D02*
G03I-3503J0D01*
G01X889095Y1554606D02*
G03Y1560905I-2678J3149D01*
G01X883740D02*
G03Y1554606I2678J-3149D01*
G01X881890Y1547519D02*
X885039Y1546338D01*
G01X881890Y1542519D02*
X885039Y1541338D01*
G01X881890Y1537519D02*
X885039Y1536338D01*
G01X881890Y1527519D02*
X885039Y1526338D01*
G01X881890Y1522519D02*
X885039Y1521338D01*
G01X879219Y1475479D02*
X879118Y1475610D01*
G01X878984Y1475511D02*
X879051Y1475446D01*
G01X879118Y1475610D02*
X878984Y1475708D01*
G01X881890Y1517519D02*
X885039Y1516338D01*
G01X881890Y1512519D02*
X885039Y1511338D01*
G01X881890Y1507519D02*
X885039Y1506338D01*
G01X881890Y1502519D02*
X885039Y1501338D01*
G01X881890Y1497519D02*
X885039Y1496338D01*
G01X881890Y1487519D02*
X885039Y1486338D01*
G01X881890Y1482519D02*
X885039Y1481338D01*
G01X881890Y1477519D02*
X885039Y1476338D01*
G01X878984Y1475708D02*
X878884Y1475741D01*
G01Y1475544D02*
X878984Y1475511D01*
G01X881890Y1532519D02*
X887008Y1531338D01*
G01X881890Y1492519D02*
X887008Y1491338D01*
G01X884400Y1556181D02*
X888435D01*
G01X884047Y1555393D02*
X888788D01*
G01X889095Y1554606D02*
X883740D01*
G01X924016Y1554193D02*
X874016D01*
G01X893701Y1551043D02*
X874016D01*
G01Y1549271D02*
X893701D01*
G01D02*
X894980D01*
G01X924803D02*
X896358D01*
G01X889764Y1546338D02*
X885039D01*
G01X925984D02*
X893701D01*
G01Y1546240D02*
X924223D01*
G01X876457D02*
X893701D01*
G01Y1544665D02*
X924223D01*
G01X893701D02*
X876457D01*
G01X893701Y1544567D02*
X925984D01*
G01X885039D02*
X889764D01*
G01X893701Y1541338D02*
X925984D01*
G01X889764D02*
X885039D01*
G01X893701Y1541240D02*
X924223D01*
G01X876457D02*
X893701D01*
G01Y1539665D02*
X924223D01*
G01X893701D02*
X876457D01*
G01X893701Y1539567D02*
X925984D01*
G01X885039D02*
X889764D01*
G01X879051Y1475446D02*
X879085Y1475347D01*
G01X893701Y1536338D02*
X925984D01*
G01X889764D02*
X885039D01*
G01X893701Y1536240D02*
X924223D01*
G01X876457D02*
X893701D01*
G01Y1534665D02*
X924223D01*
G01X893701D02*
X876457D01*
G01X893701Y1534567D02*
X925984D01*
G01X885039D02*
X889764D01*
G01X894882Y1532815D02*
X893701D01*
G01X891732Y1531338D02*
X887008D01*
G01X925984D02*
X894882D01*
G01Y1531240D02*
X924223D01*
G01X875000D02*
X894882D01*
G01Y1529665D02*
X924223D01*
G01X875000D02*
X894882D01*
G01Y1529567D02*
X925984D01*
G01X887008D02*
X891732D01*
G01X886811Y1529330D02*
X893701D01*
G01Y1528090D02*
X894882D01*
G01X893701Y1526574D02*
X886811D01*
G01X893701Y1526338D02*
X925984D01*
G01X889764D02*
X885039D01*
G01X893701Y1526240D02*
X924223D01*
G01X876457D02*
X893701D01*
G01Y1524665D02*
X924223D01*
G01X893701D02*
X876457D01*
G01X893701Y1524567D02*
X925984D01*
G01X885039D02*
X889764D01*
G01X893701Y1521338D02*
X925984D01*
G01X889764D02*
X885039D01*
G01X893701Y1521240D02*
X924223D01*
G01X876457D02*
X893701D01*
G01Y1519665D02*
X924223D01*
G01X893701D02*
X876457D01*
G01X893701Y1519567D02*
X925984D01*
G01X885039D02*
X889764D01*
G01X893701Y1516338D02*
X925984D01*
G01X889764D02*
X885039D01*
G01X893701Y1516240D02*
X924223D01*
G01X876457D02*
X893701D01*
G01Y1514665D02*
X924223D01*
G01X893701D02*
X876457D01*
G01X893701Y1514567D02*
X925984D01*
G01X885039D02*
X889764D01*
G01X893701Y1511338D02*
X925984D01*
G01X889764D02*
X885039D01*
G01X893701Y1511240D02*
X924223D01*
G01X876457D02*
X893701D01*
G01Y1509665D02*
X924223D01*
G01X893701D02*
X876457D01*
G01X893701Y1509567D02*
X925984D01*
G01X885039D02*
X889764D01*
G01X893701Y1506338D02*
X925984D01*
G01X889764D02*
X885039D01*
G01X893701Y1506240D02*
X924223D01*
G01X876457D02*
X893701D01*
G01Y1504665D02*
X924223D01*
G01X893701D02*
X876457D01*
G01X893701Y1504567D02*
X925984D01*
G01X885039D02*
X889764D01*
G01X886811Y1504330D02*
X893701D01*
G01Y1501574D02*
X886811D01*
G01X893701Y1501338D02*
X925984D01*
G01X889764D02*
X885039D01*
G01X893701Y1501240D02*
X924223D01*
G01X876457D02*
X893701D01*
G01Y1499665D02*
X924223D01*
G01X893701D02*
X876457D01*
G01X893701Y1499567D02*
X925984D01*
G01X885039D02*
X889764D01*
G01X893701Y1496338D02*
X925984D01*
G01X889764D02*
X885039D01*
G01X893701Y1496240D02*
X924223D01*
G01X876457D02*
X893701D01*
G01Y1494665D02*
X924223D01*
G01X893701D02*
X876457D01*
G01X893701Y1494567D02*
X925984D01*
G01X885039D02*
X889764D01*
G01X894882Y1492815D02*
X893701D01*
G01X891732Y1491338D02*
X887008D01*
G01X925984D02*
X894882D01*
G01Y1491240D02*
X924223D01*
G01X875000D02*
X894882D01*
G01Y1489665D02*
X924223D01*
G01X875000D02*
X894882D01*
G01Y1489567D02*
X925984D01*
G01X887008D02*
X891732D01*
G01X893701Y1488090D02*
X894882D01*
G01X893701Y1486338D02*
X925984D01*
G01X889764D02*
X885039D01*
G01X893701Y1486240D02*
X924223D01*
G01X876457D02*
X893701D01*
G01Y1484665D02*
X924223D01*
G01X893701D02*
X876457D01*
G01X893701Y1484567D02*
X925984D01*
G01X885039D02*
X889764D01*
G01X893701Y1481338D02*
X925984D01*
G01X889764D02*
X885039D01*
G01X893701Y1481240D02*
X924223D01*
G01X876457D02*
X893701D01*
G01Y1479665D02*
X876457D01*
G01X924223D02*
X893701D01*
G01Y1479567D02*
X925984D01*
G01X885039D02*
X889764D01*
G01X886811Y1479330D02*
X893701D01*
G01Y1476574D02*
X886811D01*
G01X879252Y1476397D02*
X877677D01*
G01X893701Y1476338D02*
X923032D01*
G01X889764D02*
X885039D01*
G01X893701Y1476240D02*
X924102D01*
G01X875000D02*
X893701D01*
G01X877677Y1476200D02*
X878984D01*
G01X878750Y1476004D02*
X879018D01*
G01X878884Y1475741D02*
X878750D01*
G01X878783Y1475544D02*
X878884D01*
G01X893701Y1475157D02*
X925984D01*
G01X879085Y1474724D02*
X878582D01*
G01X878381D02*
X877677D01*
G01X893701Y1474665D02*
X924102D01*
G01X875000D02*
X893701D01*
G01Y1474567D02*
X923032D01*
G01X885630D02*
X889764D01*
G01X877677Y1474527D02*
X879252D01*
G01X888976Y1473976D02*
X885630D01*
G01X879252Y1475315D02*
X879219Y1475479D01*
G01X887008Y1529567D02*
X881890Y1528385D01*
G01X887008Y1489567D02*
X881890Y1488385D01*
G01X919366Y1544665D02*
Y1546240D01*
G01Y1539665D02*
Y1541240D01*
G01Y1534665D02*
Y1536240D01*
G01Y1529665D02*
Y1531240D01*
G01Y1524665D02*
Y1526240D01*
G01Y1519665D02*
Y1521240D01*
G01Y1514665D02*
Y1516240D01*
G01Y1509665D02*
Y1511240D01*
G01Y1504665D02*
Y1506240D01*
G01Y1499665D02*
Y1501240D01*
G01Y1494665D02*
Y1496240D01*
G01Y1489665D02*
Y1491240D01*
G01Y1484665D02*
Y1486240D01*
G01Y1479665D02*
Y1481240D01*
G01Y1476240D02*
Y1474665D01*
G01X919121Y1544665D02*
Y1546240D01*
G01Y1539665D02*
Y1541240D01*
G01Y1534665D02*
Y1536240D01*
G01Y1529665D02*
Y1531240D01*
G01Y1524665D02*
Y1526240D01*
G01Y1519665D02*
Y1521240D01*
G01Y1514665D02*
Y1516240D01*
G01Y1509665D02*
Y1511240D01*
G01Y1504665D02*
Y1506240D01*
G01Y1499665D02*
Y1501240D01*
G01Y1494665D02*
Y1496240D01*
G01Y1489665D02*
Y1491240D01*
G01Y1484665D02*
Y1486240D01*
G01Y1479665D02*
Y1481240D01*
G01Y1474665D02*
Y1476240D01*
G01X918014D02*
Y1474665D01*
G01Y1481240D02*
Y1479665D01*
G01Y1486240D02*
Y1484665D01*
G01Y1491240D02*
Y1489665D01*
G01Y1496240D02*
Y1494665D01*
G01Y1501240D02*
Y1499665D01*
G01Y1506240D02*
Y1504665D01*
G01Y1511240D02*
Y1509665D01*
G01Y1516240D02*
Y1514665D01*
G01Y1521240D02*
Y1519665D01*
G01Y1526240D02*
Y1524665D01*
G01Y1531240D02*
Y1529665D01*
G01Y1536240D02*
Y1534665D01*
G01Y1541240D02*
Y1539665D01*
G01Y1546240D02*
Y1544665D01*
G01X894882Y1528090D02*
Y1532815D01*
G01Y1488090D02*
Y1492815D01*
G01X894488Y1554193D02*
Y1562539D01*
G01X893701Y1531240D02*
Y1551043D01*
G01Y1491240D02*
Y1529665D01*
G01Y1491240D02*
Y1489665D01*
G01Y1531240D02*
Y1529665D01*
G01X891732Y1531240D02*
Y1531338D01*
G01Y1529567D02*
Y1529665D01*
G01D02*
Y1531240D01*
G01Y1491240D02*
Y1491338D01*
G01Y1489665D02*
Y1491240D01*
G01Y1489567D02*
Y1489665D01*
G01X889764Y1546240D02*
Y1546338D01*
G01Y1544665D02*
Y1546240D01*
G01Y1544567D02*
Y1544665D01*
G01Y1541240D02*
Y1541338D01*
G01Y1539567D02*
Y1539665D01*
G01D02*
Y1541240D01*
G01Y1536240D02*
Y1536338D01*
G01Y1534567D02*
Y1534665D01*
G01D02*
Y1536240D01*
G01Y1526240D02*
Y1526338D01*
G01Y1524567D02*
Y1524665D01*
G01D02*
Y1526240D01*
G01Y1521240D02*
Y1521338D01*
G01Y1519567D02*
Y1519665D01*
G01D02*
Y1521240D01*
G01Y1516240D02*
Y1516338D01*
G01Y1514567D02*
Y1514665D01*
G01D02*
Y1516240D01*
G01Y1511240D02*
Y1511338D01*
G01Y1509567D02*
Y1509665D01*
G01D02*
Y1511240D01*
G01Y1506240D02*
Y1506338D01*
G01Y1504567D02*
Y1504665D01*
G01D02*
Y1506240D01*
G01Y1501240D02*
Y1501338D01*
G01Y1499567D02*
Y1499665D01*
G01D02*
Y1501240D01*
G01Y1496240D02*
Y1496338D01*
G01Y1494567D02*
Y1494665D01*
G01D02*
Y1496240D01*
G01Y1486240D02*
Y1486338D01*
G01Y1484665D02*
Y1486240D01*
G01Y1484567D02*
Y1484665D01*
G01Y1481240D02*
Y1481338D01*
G01Y1479665D02*
Y1481240D01*
G01Y1479567D02*
Y1479665D01*
G01Y1476240D02*
Y1476338D01*
G01Y1474665D02*
Y1476240D01*
G01Y1474567D02*
Y1474665D01*
G01X886811Y1479330D02*
Y1476574D01*
G01Y1504330D02*
Y1501574D01*
G01Y1529330D02*
Y1526574D01*
G01X885630Y1473976D02*
Y1474567D01*
G01X884134Y1544665D02*
Y1546240D01*
G01Y1539665D02*
Y1541240D01*
G01Y1534665D02*
Y1536240D01*
G01Y1529665D02*
Y1531240D01*
G01Y1524665D02*
Y1526240D01*
G01Y1519665D02*
Y1521240D01*
G01Y1514665D02*
Y1516240D01*
G01Y1509665D02*
Y1511240D01*
G01Y1504665D02*
Y1506240D01*
G01Y1499665D02*
Y1501240D01*
G01Y1494665D02*
Y1496240D01*
G01Y1489665D02*
Y1491240D01*
G01Y1484665D02*
Y1486240D01*
G01Y1479665D02*
Y1481240D01*
G01Y1474665D02*
Y1476240D01*
G01X882559Y1544665D02*
Y1546240D01*
G01Y1539665D02*
Y1541240D01*
G01Y1534665D02*
Y1536240D01*
G01Y1529665D02*
Y1531240D01*
G01Y1524665D02*
Y1526240D01*
G01Y1519665D02*
Y1521240D01*
G01Y1514665D02*
Y1516240D01*
G01Y1509665D02*
Y1511240D01*
G01Y1504665D02*
Y1506240D01*
G01Y1499665D02*
Y1501240D01*
G01Y1494665D02*
Y1496240D01*
G01Y1489665D02*
Y1491240D01*
G01Y1484665D02*
Y1486240D01*
G01Y1479665D02*
Y1481240D01*
G01Y1474665D02*
Y1476240D01*
G01X881890Y1547519D02*
Y1549271D01*
G01Y1542519D02*
Y1543385D01*
G01Y1537519D02*
Y1538385D01*
G01Y1532519D02*
Y1533385D01*
G01Y1527519D02*
Y1528385D01*
G01Y1522519D02*
Y1523385D01*
G01Y1517519D02*
Y1518385D01*
G01Y1512519D02*
Y1513385D01*
G01Y1507519D02*
Y1508385D01*
G01Y1502519D02*
Y1503385D01*
G01Y1497519D02*
Y1498385D01*
G01Y1492519D02*
Y1493385D01*
G01Y1487519D02*
Y1488385D01*
G01Y1482519D02*
Y1483385D01*
G01Y1477519D02*
Y1478385D01*
G01X881772Y1476240D02*
Y1474665D01*
G01Y1481240D02*
Y1479665D01*
G01Y1486240D02*
Y1484665D01*
G01Y1491240D02*
Y1489665D01*
G01Y1496240D02*
Y1494665D01*
G01Y1501240D02*
Y1499665D01*
G01Y1506240D02*
Y1504665D01*
G01Y1511240D02*
Y1509665D01*
G01Y1516240D02*
Y1514665D01*
G01Y1521240D02*
Y1519665D01*
G01Y1526240D02*
Y1524665D01*
G01Y1531240D02*
Y1529665D01*
G01Y1536240D02*
Y1534665D01*
G01Y1541240D02*
Y1539665D01*
G01Y1546240D02*
Y1544665D01*
G01X881378Y1476240D02*
Y1474665D01*
G01Y1481240D02*
Y1479665D01*
G01Y1486240D02*
Y1484665D01*
G01Y1491240D02*
Y1489665D01*
G01Y1496240D02*
Y1494665D01*
G01Y1501240D02*
Y1499665D01*
G01Y1506240D02*
Y1504665D01*
G01Y1511240D02*
Y1509665D01*
G01Y1516240D02*
Y1514665D01*
G01Y1521240D02*
Y1519665D01*
G01Y1526240D02*
Y1524665D01*
G01Y1531240D02*
Y1529665D01*
G01Y1536240D02*
Y1534665D01*
G01Y1541240D02*
Y1539665D01*
G01Y1546240D02*
Y1544665D01*
G01X879252Y1476240D02*
Y1476397D01*
G01Y1476200D02*
Y1476240D01*
G01Y1474527D02*
Y1474665D01*
G01D02*
Y1475315D01*
G01X879085Y1475347D02*
Y1474724D01*
G01X878582D02*
Y1475347D01*
G01X878381Y1475315D02*
Y1474724D01*
G01X877677Y1474665D02*
Y1474527D01*
G01Y1474724D02*
Y1474665D01*
G01Y1476397D02*
Y1476240D01*
G01D02*
Y1476200D01*
G01X876457Y1544665D02*
Y1546240D01*
G01Y1539665D02*
Y1541240D01*
G01Y1534665D02*
Y1536240D01*
G01Y1524665D02*
Y1526240D01*
G01Y1519665D02*
Y1521240D01*
G01Y1514665D02*
Y1516240D01*
G01Y1509665D02*
Y1511240D01*
G01Y1504665D02*
Y1506240D01*
G01Y1499665D02*
Y1501240D01*
G01Y1494665D02*
Y1496240D01*
G01Y1484665D02*
Y1486240D01*
G01Y1479665D02*
Y1481240D01*
G01X875000Y1529665D02*
Y1531240D01*
G01Y1489665D02*
Y1491240D01*
G01Y1474665D02*
Y1476240D01*
G01X874016Y1549271D02*
Y1562539D01*
G01X878415Y1475479D02*
X878381Y1475315D01*
G01X878582Y1475347D02*
X878615Y1475446D01*
G01X878515Y1475610D02*
X878415Y1475479D01*
G01X879018Y1476004D02*
X879252Y1476200D01*
G01X878984D02*
X878750Y1476004D01*
G01X878615Y1475446D02*
X878683Y1475511D01*
G01X878649Y1475708D02*
X878515Y1475610D01*
G01X878683Y1475511D02*
X878783Y1475544D01*
G01X878750Y1475741D02*
X878649Y1475708D01*
G01X885039Y1479567D02*
X881890Y1478385D01*
G01X885039Y1484567D02*
X881890Y1483385D01*
G01X885039Y1494567D02*
X881890Y1493385D01*
G01X885039Y1499567D02*
X881890Y1498385D01*
G01X885039Y1504567D02*
X881890Y1503385D01*
G01X885039Y1509567D02*
X881890Y1508385D01*
G01X885039Y1514567D02*
X881890Y1513385D01*
G01X885039Y1519567D02*
X881890Y1518385D01*
G01X885039Y1524567D02*
X881890Y1523385D01*
G01X885039Y1534567D02*
X881890Y1533385D01*
G01X885039Y1539567D02*
X881890Y1538385D01*
G01X885039Y1544567D02*
X881890Y1543385D01*
G01X899409Y1569567D02*
G03I-3740J0D01*
G01X881890Y1579429D02*
X909449D01*
G01X905512Y1575492D02*
X885827D01*
G01X905512Y1573523D02*
X885827D01*
G01X905512Y1571535D02*
X885827D01*
G01Y1570551D02*
X905512D01*
G01X905315Y1570354D02*
X886024D01*
G01X905315Y1568779D02*
X886024D01*
G01X905512Y1568582D02*
X885827D01*
G01Y1567598D02*
X905512D01*
G01X909449Y1566476D02*
X936614D01*
G01X881890D02*
X870079D01*
G01X905512Y1564508D02*
X885827D01*
G01X927953Y1562539D02*
X874016D01*
G01X894488Y1561358D02*
X927953D01*
G01X883740Y1560905D02*
X889095D01*
G01X888788Y1560118D02*
X884047D01*
G01X884400Y1559330D02*
X888435D01*
G01X894488Y1557145D02*
X874016D01*
G01X905512D02*
X894488D01*
G01X909449Y1579429D02*
Y1566476D01*
G01X905512Y1562539D02*
Y1575492D01*
G01X905315Y1568779D02*
Y1570354D01*
G01X899961D02*
Y1568779D01*
G01X898622Y1570354D02*
Y1570551D01*
G01Y1568582D02*
Y1568779D01*
G01Y1570354D02*
Y1568779D01*
G01X898425Y1570354D02*
Y1568779D01*
G01X896850Y1570354D02*
Y1568779D01*
G01X894488Y1570354D02*
Y1568779D01*
G01X892913D02*
Y1570354D01*
G01X892717D02*
Y1570551D01*
G01Y1568779D02*
Y1570354D01*
G01Y1568779D02*
Y1568582D01*
G01X891378Y1568779D02*
Y1570354D01*
G01X886024D02*
Y1568779D01*
G01X885827Y1562539D02*
Y1575492D01*
G01X881890Y1566476D02*
Y1579429D01*
G01X848779Y1713782D02*
X850337Y1714620D01*
G01X851649Y1715457D02*
X851977Y1715625D01*
G01X850501Y1714369D02*
X849353Y1713782D01*
G01X852060Y1715206D02*
X851814Y1715039D01*
G01X851321Y1715122D02*
X851649Y1715457D01*
G01X850501Y1713196D02*
X850337Y1712944D01*
G01X851814Y1715039D02*
X851649Y1714787D01*
G01X851239D02*
X851321Y1715122D01*
G01X844842Y1711772D02*
Y1715709D01*
G01X845334D02*
Y1714117D01*
G01Y1713615D02*
Y1711772D01*
G01X847630D02*
Y1713615D01*
G01Y1714117D02*
Y1715709D01*
G01X848123D02*
Y1711772D01*
G01X852469Y1713615D02*
Y1713950D01*
G01X851239Y1712442D02*
X851157Y1712693D01*
G01X851568D02*
X851649Y1712526D01*
G01X852469Y1715290D02*
X852060Y1715206D01*
G01X851977Y1715625D02*
X852552Y1715709D01*
G01X851403Y1712191D02*
X851239Y1712442D01*
G01X850337Y1714620D02*
X850501Y1714369D01*
G01X852962Y1711772D02*
X852306D01*
G01X848123D02*
X847630D01*
G01X845334D02*
X844842D01*
G01X852388Y1712191D02*
X852880D01*
G01X851157Y1712693D02*
X851568D01*
G01X852798Y1713615D02*
X852469D01*
G01X847630D02*
X845334D01*
G01X852469Y1713950D02*
X852798D01*
G01X845334Y1714117D02*
X847630D01*
G01X851649Y1714787D02*
X851239D01*
G01X852798Y1715290D02*
X852469D01*
G01X847630Y1715709D02*
X848123D01*
G01X844842D02*
X845334D01*
G01X852552D02*
X852716D01*
G01X851977Y1712274D02*
X852388Y1712191D01*
G01X851649Y1712526D02*
X851814Y1712358D01*
G01X852306Y1711772D02*
X851977Y1711856D01*
G01D02*
X851649Y1712023D01*
G01X851814Y1712358D02*
X851977Y1712274D01*
G01X849353Y1713782D02*
X850501Y1713196D01*
G01X850337Y1712944D02*
X848779Y1713782D01*
G01X851649Y1712023D02*
X851403Y1712191D01*
G01X870038Y1705354D02*
Y1736850D01*
G01X852798Y1713950D02*
X853290Y1714117D01*
G01X855340Y1714369D02*
X855586Y1714452D01*
G01Y1714117D02*
X855340Y1714033D01*
G01X856653Y1714369D02*
X856899Y1714452D01*
G01X859031Y1714369D02*
X859277Y1714452D01*
G01Y1714117D02*
X859031Y1714033D01*
G01X860343Y1714369D02*
X860590Y1714452D01*
G01X856817Y1714117D02*
X856653Y1714033D01*
G01X853290Y1712274D02*
X853454Y1712358D01*
G01X853618Y1712023D02*
X853290Y1711856D01*
G01X860508Y1714117D02*
X860343Y1714033D01*
G01X853864Y1712191D02*
X853618Y1712023D01*
G01X853782Y1714033D02*
X853454Y1713782D01*
G01X853290Y1714117D02*
X853454Y1714285D01*
G01X855176Y1714201D02*
X855340Y1714369D01*
G01X853454Y1712358D02*
X853618Y1712526D01*
G01X855340Y1714033D02*
X855176Y1713866D01*
G01X856406Y1714117D02*
X856653Y1714369D01*
G01Y1714033D02*
X856571Y1713950D01*
G01X858867Y1714201D02*
X859031Y1714369D01*
G01Y1714033D02*
X858867Y1713866D01*
G01X860097Y1714117D02*
X860343Y1714369D01*
G01Y1714033D02*
X860262Y1713950D01*
G01X853946Y1714285D02*
X853782Y1714033D01*
G01X854028Y1712442D02*
X853864Y1712191D01*
G01X853454Y1714285D02*
X853618Y1714620D01*
G01Y1712526D02*
X853700Y1712693D01*
G01X856571Y1713950D02*
X856489Y1713782D01*
G01X860262Y1713950D02*
X860180Y1713782D01*
G01X854028Y1714620D02*
X853946Y1714285D01*
G01X854110Y1712693D02*
X854028Y1712442D01*
G01X853618Y1714620D02*
Y1714787D01*
G01X853700Y1712693D02*
Y1713028D01*
G01X854028Y1714787D02*
Y1714620D01*
G01X854110Y1713028D02*
Y1712693D01*
G01X854766Y1711772D02*
Y1714452D01*
G01X855176Y1713866D02*
Y1711772D01*
G01Y1714452D02*
Y1714201D01*
G01X856079Y1711772D02*
Y1713782D01*
G01X856489D02*
Y1711772D01*
G01X857391D02*
Y1713782D01*
G01X857801D02*
Y1711772D01*
G01X858457D02*
Y1714452D01*
G01X858867Y1713866D02*
Y1711772D01*
G01Y1714452D02*
Y1714201D01*
G01X859769Y1711772D02*
Y1713782D01*
G01X860180D02*
Y1711772D01*
G01X861082D02*
Y1713782D01*
G01X861492D02*
Y1711772D01*
G01X854028Y1713363D02*
X854110Y1713028D01*
G01X853946Y1715122D02*
X854028Y1714787D01*
G01X853290Y1711856D02*
X852962Y1711772D01*
G01X853700Y1713028D02*
X853536Y1713363D01*
G01X856079Y1713782D02*
X855997Y1713950D01*
G01X857391Y1713782D02*
X857309Y1713950D01*
G01X857637Y1714201D02*
X857801Y1713782D01*
G01X861328Y1714201D02*
X861492Y1713782D01*
G01X852880Y1712191D02*
X853290Y1712274D01*
G01X853864Y1713615D02*
X854028Y1713363D01*
G01X853618Y1714787D02*
X853454Y1715039D01*
G01X859769Y1713782D02*
X859688Y1713950D01*
G01X861082Y1713782D02*
X861000Y1713950D01*
G01X860180Y1711772D02*
X859769D01*
G01X861492D02*
X861082D01*
G01X856489D02*
X856079D01*
G01X857801D02*
X857391D01*
G01X855176D02*
X854766D01*
G01X858867D02*
X858457D01*
G01X859442Y1714117D02*
X859277D01*
G01X860754D02*
X860508D01*
G01X855751D02*
X855586D01*
G01X857063D02*
X856817D01*
G01X856899Y1714452D02*
X857227D01*
G01X855586D02*
X855914D01*
G01X854766D02*
X855176D01*
G01X858457D02*
X858867D01*
G01X860590D02*
X860918D01*
G01X859277D02*
X859605D01*
G01X852716Y1715709D02*
X853290Y1715625D01*
G01Y1713531D02*
X852798Y1713615D01*
G01X853208Y1715206D02*
X852798Y1715290D01*
G01X853618Y1715457D02*
X853946Y1715122D01*
G01X855997Y1713950D02*
X855914Y1714033D01*
G01X856160Y1714369D02*
X856406Y1714117D01*
G01X857309Y1713950D02*
X857227Y1714033D01*
G01X857473Y1714369D02*
X857637Y1714201D01*
G01X859688Y1713950D02*
X859605Y1714033D01*
G01X859851Y1714369D02*
X860097Y1714117D01*
G01X861000Y1713950D02*
X860918Y1714033D01*
G01X861164Y1714369D02*
X861328Y1714201D01*
G01X855914Y1714452D02*
X856160Y1714369D01*
G01X857227Y1714452D02*
X857473Y1714369D01*
G01X859605Y1714452D02*
X859851Y1714369D01*
G01X860918Y1714452D02*
X861164Y1714369D01*
G01X853454Y1713782D02*
X853864Y1713615D01*
G01X855914Y1714033D02*
X855751Y1714117D01*
G01X853290Y1715625D02*
X853618Y1715457D01*
G01X857227Y1714033D02*
X857063Y1714117D01*
G01X859605Y1714033D02*
X859442Y1714117D01*
G01X860918Y1714033D02*
X860754Y1714117D01*
G01X853536Y1713363D02*
X853290Y1713531D01*
G01X853454Y1715039D02*
X853208Y1715206D01*
G01X890944Y1786358D02*
Y1784390D01*
G01Y1781831D02*
Y1783799D01*
G01X892519Y1786654D02*
Y1786063D01*
G01Y1784882D02*
Y1783307D01*
G01Y1782126D02*
Y1781535D01*
G01D02*
X898818D01*
G01X894093Y1781831D02*
X892519D01*
G01D02*
X890944D01*
G01Y1783799D02*
X892519D01*
G01D02*
X894093D01*
G01X890944Y1784390D02*
X892519D01*
G01D02*
X894093D01*
G01Y1786358D02*
X892519D01*
G01D02*
X890944D01*
G01X892519Y1786654D02*
X898818D01*
G01X892519Y1782126D02*
G03Y1783307I0J591D01*
G01Y1784882D02*
G03Y1786063I0J590D01*
G01X898807Y1785261D02*
X898901Y1785373D01*
G01Y1785245D02*
X898807Y1785134D01*
G01X893503Y1786654D02*
Y1781535D01*
G01X893700D02*
Y1786654D01*
G01X894093Y1783799D02*
Y1781831D01*
G01Y1784390D02*
Y1786358D01*
G01X897243Y1783799D02*
Y1781831D01*
G01Y1784390D02*
Y1786358D01*
G01X897637Y1781535D02*
Y1786654D01*
G01X897834D02*
Y1781535D01*
G01X898714Y1785134D02*
Y1785882D01*
G01X898807D02*
Y1785261D01*
G01X898818Y1781535D02*
Y1782126D01*
G01Y1783307D02*
Y1784882D01*
G01Y1786063D02*
Y1786654D01*
G01X898901Y1785373D02*
Y1785245D01*
G01X900393Y1786358D02*
Y1784390D01*
G01Y1781831D02*
Y1783799D01*
G01X897243Y1781831D02*
X898818D01*
G01D02*
X900393D01*
G01X898818Y1783799D02*
X897243D01*
G01X900393D02*
X898818D01*
G01Y1784390D02*
X897243D01*
G01X900393D02*
X898818D01*
G01X898807Y1785134D02*
X898714D01*
G01Y1785882D02*
X898807D01*
G01X897243Y1786358D02*
X898818D01*
G01D02*
X900393D01*
G01X898818Y1783307D02*
G03Y1782126I0J-590D01*
G01Y1786063D02*
G03Y1784882I0J-591D01*
G01X899409Y1801850D02*
G03I-3740J0D01*
G01X870079Y1804941D02*
X881890D01*
G01X936614D02*
X909449D01*
G01X905512Y1803819D02*
X885827D01*
G01Y1802834D02*
X905512D01*
G01X905315Y1802637D02*
X886024D01*
G01X905315Y1801063D02*
X886024D01*
G01X905512Y1800866D02*
X885827D01*
G01Y1799882D02*
X905512D01*
G01X885827Y1797893D02*
X905512D01*
G01X885827Y1795925D02*
X905512D01*
G01X909449Y1791988D02*
X881890D01*
G01X909449Y1804941D02*
Y1791988D01*
G01X905512Y1795925D02*
Y1808878D01*
G01X905315Y1801063D02*
Y1802637D01*
G01X899961D02*
Y1801063D01*
G01X898622Y1802637D02*
Y1802834D01*
G01Y1800866D02*
Y1801063D01*
G01Y1802637D02*
Y1801063D01*
G01X898425Y1802637D02*
Y1801063D01*
G01X896850Y1802637D02*
Y1801063D01*
G01X894488Y1802637D02*
Y1801063D01*
G01X892913D02*
Y1802637D01*
G01X892717D02*
Y1802834D01*
G01Y1801063D02*
Y1802637D01*
G01Y1801063D02*
Y1800866D01*
G01X891378Y1801063D02*
Y1802637D01*
G01X886024D02*
Y1801063D01*
G01X885827Y1795925D02*
Y1808878D01*
G01X881890Y1791988D02*
Y1804941D01*
G01X870079Y1971988D02*
Y1804941D01*
G01X886343Y1817795D02*
X886417D01*
G01X886492Y1809528D02*
X886417Y1809527D01*
G01X888976Y1813661D02*
G03I-2558J0D01*
G01X889764D02*
G03I-3346J0D01*
G01X889921D02*
G03I-3503J0D01*
G01X886492Y1809528D02*
G03X886417Y1817795I-73J4133D01*
G01X886343Y1817794D02*
G03X886417Y1809527I73J-4133D01*
G01X879118Y1881122D02*
X878984Y1881220D01*
G01X885223Y1857749D02*
X885056Y1857847D01*
G01X885994Y1859225D02*
X885859Y1859291D01*
G01X886195Y1858602D02*
X886128Y1858635D01*
G01X885458Y1858930D02*
X885591Y1858865D01*
G01X886094Y1860341D02*
X886262Y1860275D01*
G01X885424Y1860374D02*
X885591Y1860308D01*
G01X885324Y1859193D02*
X885156Y1859258D01*
G01X881890Y1888031D02*
X885039Y1886850D01*
G01X881890Y1883031D02*
X885039Y1881850D01*
G01X881890Y1853031D02*
X885039Y1851850D01*
G01X881890Y1848031D02*
X885039Y1846850D01*
G01X878984Y1881220D02*
X878884Y1881253D01*
G01Y1881056D02*
X878984Y1881023D01*
G01X886128Y1858832D02*
X886228Y1858799D01*
G01X885927Y1858044D02*
X886027Y1858011D01*
G01X885256Y1857946D02*
X885357Y1857913D01*
G01X888976Y1879291D02*
X891339Y1878602D01*
G01X888976Y1876141D02*
X891339Y1875452D01*
G01X888976Y1872992D02*
X891339Y1872303D01*
G01X888976Y1869842D02*
X891339Y1869153D01*
G01X888976Y1866693D02*
X891339Y1866004D01*
G01X888976Y1863543D02*
X891339Y1862854D01*
G01X888976Y1860393D02*
X891339Y1859704D01*
G01X878984Y1881023D02*
X879051Y1880958D01*
G01X886262Y1860275D02*
X886362Y1860177D01*
G01X885859Y1859291D02*
X885759Y1859389D01*
G01X886262Y1858536D02*
X886195Y1858602D01*
G01X885591Y1858865D02*
X885726Y1858733D01*
G01X885156Y1859258D02*
X885056Y1859357D01*
G01X885859Y1857847D02*
X885726Y1857979D01*
G01X885156Y1858044D02*
X885256Y1857946D01*
G01X885424Y1860209D02*
X885558Y1860111D01*
G01X886228Y1858799D02*
X886362Y1858700D01*
G01X885324Y1859357D02*
X885189Y1859455D01*
G01X878945Y1826082D02*
X879079Y1825984D01*
G01X886094Y1860177D02*
X886195Y1860111D01*
G01X886027Y1859389D02*
X885927Y1859455D01*
G01X885524Y1858668D02*
X885424Y1858733D01*
G01X878241Y1825951D02*
X878141Y1826017D01*
G01X877939Y1825032D02*
X877772Y1825131D01*
G01X878911Y1825885D02*
X878844Y1825918D01*
G01X878174Y1826213D02*
X878308Y1826148D01*
G01X881890Y1843031D02*
X885039Y1841850D01*
G01X881890Y1838031D02*
X885039Y1836850D01*
G01X881890Y1833031D02*
X885039Y1831850D01*
G01X881890Y1828031D02*
X885039Y1826850D01*
G01X878844Y1826115D02*
X878945Y1826082D01*
G01X878643Y1825328D02*
X878744Y1825295D01*
G01X877973Y1825229D02*
X878074Y1825196D01*
G01X885994Y1857815D02*
X885859Y1857847D01*
G01X885357Y1857716D02*
X885223Y1857749D01*
G01X878710Y1825098D02*
X878576Y1825131D01*
G01X878074Y1825000D02*
X877939Y1825032D01*
G01X893701Y1886850D02*
X925984D01*
G01X889764D02*
X885039D01*
G01X893701Y1886752D02*
X924223D01*
G01X876457D02*
X893701D01*
G01Y1885177D02*
X876457D01*
G01X924223D02*
X893701D01*
G01Y1885078D02*
X925984D01*
G01X885039D02*
X889764D01*
G01X886811Y1884842D02*
X893701D01*
G01Y1882086D02*
X886811D01*
G01X879252Y1881909D02*
X877677D01*
G01X893701Y1881850D02*
X923032D01*
G01X889764D02*
X885039D01*
G01X893701Y1881752D02*
X924102D01*
G01X875000D02*
X893701D01*
G01X877677Y1881712D02*
X878984D01*
G01X878750Y1881515D02*
X879018D01*
G01X878884Y1881253D02*
X878750D01*
G01X878783Y1881056D02*
X878884D01*
G01X893701Y1880669D02*
X925984D01*
G01X879085Y1880236D02*
X878582D01*
G01X878381D02*
X877677D01*
G01X893701Y1880177D02*
X924102D01*
G01X875000D02*
X893701D01*
G01Y1880078D02*
X923032D01*
G01X885630D02*
X889764D01*
G01X877677Y1880039D02*
X879252D01*
G01X888976Y1879488D02*
X885630D01*
G01X896457Y1878602D02*
X925787D01*
G01X891339D02*
X893701D01*
G01X896457Y1878504D02*
X922561D01*
G01X884449D02*
X896457D01*
G01X905512Y1878228D02*
X924016D01*
G01X884449Y1877322D02*
X896457D01*
G01X922561D02*
X896457D01*
G01Y1877224D02*
X925787D01*
G01X891339D02*
X893701D01*
G01X896457Y1875452D02*
X925787D01*
G01X891339D02*
X893701D01*
G01X896457Y1875354D02*
X922561D01*
G01X884449D02*
X896457D01*
G01X884449Y1874173D02*
X896457D01*
G01X922561D02*
X896457D01*
G01Y1874074D02*
X925787D01*
G01X891339D02*
X893701D01*
G01X896457Y1872303D02*
X925787D01*
G01X891339D02*
X893701D01*
G01X896457Y1872204D02*
X922561D01*
G01X884449D02*
X896457D01*
G01X884449Y1871023D02*
X896457D01*
G01X922561D02*
X896457D01*
G01Y1870925D02*
X925787D01*
G01X891339D02*
X893701D01*
G01X896457Y1869153D02*
X925787D01*
G01X891339D02*
X893701D01*
G01X896457Y1869055D02*
X922561D01*
G01X884449D02*
X896457D01*
G01X884449Y1867874D02*
X896457D01*
G01X922561D02*
X896457D01*
G01Y1867775D02*
X925787D01*
G01X891339D02*
X893701D01*
G01X896457Y1866004D02*
X925787D01*
G01X891339D02*
X893701D01*
G01X896457Y1865905D02*
X922561D01*
G01X884449D02*
X896457D01*
G01X884449Y1864724D02*
X896457D01*
G01X922561D02*
X896457D01*
G01Y1864626D02*
X925787D01*
G01X891339D02*
X893701D01*
G01X896457Y1862854D02*
X925787D01*
G01X891339D02*
X893701D01*
G01X896457Y1862756D02*
X922561D01*
G01X884449D02*
X896457D01*
G01X884449Y1861574D02*
X896457D01*
G01X922561D02*
X896457D01*
G01Y1861476D02*
X925787D01*
G01X891339D02*
X893701D01*
G01X885324Y1860374D02*
X885424D01*
G01X885994Y1860341D02*
X886094D01*
G01X885324Y1860209D02*
X885424D01*
G01X886027Y1860177D02*
X886094D01*
G01X891339Y1859704D02*
X893701D01*
G01X925787D02*
X896457D01*
G01Y1859606D02*
X922561D01*
G01X884449D02*
X896457D01*
G01X886094Y1859389D02*
X886027D01*
G01X885424Y1859357D02*
X885324D01*
G01X886094Y1859225D02*
X885994D01*
G01X885424Y1859193D02*
X885324D01*
G01X885290Y1858930D02*
X885458D01*
G01X885424Y1858733D02*
X885324D01*
G01X924016Y1858700D02*
X905512D01*
G01X884449Y1858425D02*
X896457D01*
G01X922561D02*
X896457D01*
G01X891339Y1858326D02*
X893701D01*
G01X925787D02*
X896457D01*
G01X886027Y1858011D02*
X886094D01*
G01X886128Y1857815D02*
X885994D01*
G01X885630Y1857441D02*
X888976D01*
G01X889764Y1856850D02*
X885630D01*
G01X923032D02*
X893701D01*
G01Y1856752D02*
X924102D01*
G01X876457D02*
X893701D01*
G01Y1856259D02*
X925984D01*
G01X893701Y1855177D02*
X876457D01*
G01X924102D02*
X893701D01*
G01Y1855078D02*
X923032D01*
G01X885039D02*
X889764D01*
G01Y1851850D02*
X885039D01*
G01X925984D02*
X893701D01*
G01Y1851752D02*
X924223D01*
G01X876457D02*
X893701D01*
G01Y1850177D02*
X924223D01*
G01X893701D02*
X876457D01*
G01X893701Y1850078D02*
X925984D01*
G01X885039D02*
X889764D01*
G01X886811Y1849842D02*
X893701D01*
G01Y1847086D02*
X886811D01*
G01X893701Y1846850D02*
X925984D01*
G01X889764D02*
X885039D01*
G01X893701Y1846752D02*
X924223D01*
G01X876457D02*
X893701D01*
G01Y1845177D02*
X924223D01*
G01X893701D02*
X876457D01*
G01X893701Y1845078D02*
X925984D01*
G01X885039D02*
X889764D01*
G01X885591Y1858569D02*
X885524Y1858668D01*
G01X885859Y1858143D02*
X885927Y1858044D01*
G01X879219Y1880991D02*
X879118Y1881122D01*
G01X886195Y1860111D02*
X886295Y1859980D01*
G01X885591Y1860308D02*
X885692Y1860177D01*
G01X885927Y1859455D02*
X885826Y1859586D01*
G01X886362Y1858700D02*
X886463Y1858569D01*
G01X879079Y1825984D02*
X879179Y1825853D01*
G01X878978Y1825820D02*
X878911Y1825885D01*
G01X878308Y1826148D02*
X878442Y1826017D01*
G01X878576Y1825131D02*
X878529Y1825177D01*
G01D02*
X878442Y1825262D01*
G01X877872Y1825328D02*
X877973Y1825229D01*
G01X893701Y1841850D02*
X925984D01*
G01X889764D02*
X885039D01*
G01X893701Y1841752D02*
X924223D01*
G01X876457D02*
X893701D01*
G01Y1840177D02*
X924223D01*
G01X893701D02*
X876457D01*
G01X893701Y1840078D02*
X925984D01*
G01X885039D02*
X889764D01*
G01X893701Y1836850D02*
X925984D01*
G01X889764D02*
X885039D01*
G01X893701Y1836752D02*
X924223D01*
G01X876457D02*
X893701D01*
G01Y1835177D02*
X924223D01*
G01X893701D02*
X876457D01*
G01X893701Y1835078D02*
X925984D01*
G01X885039D02*
X889764D01*
G01X893701Y1831850D02*
X925984D01*
G01X889764D02*
X885039D01*
G01X893701Y1831752D02*
X924223D01*
G01X876457D02*
X893701D01*
G01Y1830177D02*
X924223D01*
G01X893701D02*
X876457D01*
G01X893701Y1830078D02*
X925984D01*
G01X885039D02*
X889764D01*
G01X879213Y1826870D02*
X877638D01*
G01X893701Y1826850D02*
X925984D01*
G01X889764D02*
X885039D01*
G01X893701Y1826752D02*
X924223D01*
G01X876457D02*
X893701D01*
G01X877638Y1826673D02*
X878945D01*
G01X878710Y1826476D02*
X878978D01*
G01X878007Y1826213D02*
X878174D01*
G01X878141Y1826017D02*
X878040D01*
G01X878744Y1825295D02*
X878811D01*
G01X893701Y1825177D02*
X924223D01*
G01X893701D02*
X876457D01*
G01X878844Y1825098D02*
X878710D01*
G01X893701Y1825078D02*
X925984D01*
G01X885039D02*
X889764D01*
G01X896358Y1822145D02*
X924803D01*
G01X893701D02*
X894980D01*
G01X893701D02*
X874016D01*
G01Y1820374D02*
X893701D01*
G01X874016Y1817224D02*
X924016D01*
G01X894488Y1814271D02*
X905512D01*
G01X874016D02*
X894488D01*
G01X927953Y1810059D02*
X894488D01*
G01X927953Y1808878D02*
X874016D01*
G01X885827Y1806909D02*
X905512D01*
G01X885692Y1860177D02*
X885726Y1860111D01*
G01X885558D02*
X885625Y1859980D01*
G01X885759Y1859389D02*
X885726Y1859455D01*
G01Y1858733D02*
X885793Y1858602D01*
G01X885189Y1859455D02*
X885122Y1859586D01*
G01X885726Y1857979D02*
X885659Y1858110D01*
G01X878442Y1826017D02*
X878509Y1825885D01*
G01X878442Y1825262D02*
X878375Y1825393D01*
G01X886362Y1860177D02*
X886463Y1860013D01*
G01X885056Y1859357D02*
X884955Y1859520D01*
G01X885056Y1857847D02*
X884955Y1858011D01*
G01X877772Y1825131D02*
X877744Y1825177D01*
G01D02*
X877671Y1825295D01*
G01X878308Y1825853D02*
X878241Y1825951D01*
G01X878576Y1825426D02*
X878643Y1825328D01*
G01X886262Y1857847D02*
X886128Y1857815D01*
G01X878978Y1825131D02*
X878844Y1825098D01*
G01X879051Y1880958D02*
X879085Y1880859D01*
G01X886295Y1858438D02*
X886262Y1858536D01*
G01X885826Y1858241D02*
X885859Y1858143D01*
G01X886295Y1859980D02*
X886329Y1859849D01*
G01X885821Y1859606D02*
X885793Y1859717D01*
G01X885826Y1859586D02*
X885821Y1859606D01*
G01X885625Y1859980D02*
X885659Y1859849D01*
G01X885625Y1858438D02*
X885591Y1858569D01*
G01X885659Y1858110D02*
X885625Y1858241D01*
G01X885117Y1859606D02*
X885089Y1859717D01*
G01X885122Y1859586D02*
X885117Y1859606D01*
G01X885122Y1858176D02*
X885156Y1858044D01*
G01X878342Y1825721D02*
X878308Y1825853D01*
G01X878375Y1825393D02*
X878342Y1825524D01*
G01X877839Y1825459D02*
X877872Y1825328D01*
G01X879012Y1825721D02*
X878978Y1825820D01*
G01X878543Y1825524D02*
X878576Y1825426D01*
G01X886463Y1860013D02*
X886496Y1859849D01*
G01X886492Y1858425D02*
X886496Y1858405D01*
G01X886463Y1858569D02*
X886492Y1858425D01*
G01X885793Y1858602D02*
X885826Y1858438D01*
G01X884937Y1859606D02*
X884921Y1859685D01*
G01X884955Y1859520D02*
X884937Y1859606D01*
G01X884955Y1858011D02*
X884921Y1858176D01*
G01X879252Y1880826D02*
X879219Y1880991D01*
G01X879179Y1825853D02*
X879213Y1825689D01*
G01X878509Y1825885D02*
X878543Y1825721D01*
G01X877671Y1825295D02*
X877638Y1825459D01*
G01X922561Y1859606D02*
Y1858425D01*
G01Y1862756D02*
Y1861574D01*
G01Y1865905D02*
Y1864724D01*
G01Y1869055D02*
Y1867874D01*
G01Y1872204D02*
Y1871023D01*
G01Y1878504D02*
Y1877322D01*
G01Y1875354D02*
Y1874173D01*
G01X921823Y1877322D02*
Y1878504D01*
G01Y1874173D02*
Y1875354D01*
G01Y1871023D02*
Y1872204D01*
G01Y1864724D02*
Y1865905D01*
G01Y1867874D02*
Y1869055D01*
G01Y1861574D02*
Y1862756D01*
G01Y1858425D02*
Y1859606D01*
G01X919366Y1885177D02*
Y1886752D01*
G01Y1850177D02*
Y1851752D01*
G01Y1845177D02*
Y1846752D01*
G01Y1840177D02*
Y1841752D01*
G01Y1835177D02*
Y1836752D01*
G01Y1830177D02*
Y1831752D01*
G01Y1825177D02*
Y1826752D01*
G01Y1856752D02*
Y1855177D01*
G01Y1881752D02*
Y1880177D01*
G01X919121Y1885177D02*
Y1886752D01*
G01Y1880177D02*
Y1881752D01*
G01Y1855177D02*
Y1856752D01*
G01Y1850177D02*
Y1851752D01*
G01Y1845177D02*
Y1846752D01*
G01Y1840177D02*
Y1841752D01*
G01Y1835177D02*
Y1836752D01*
G01Y1830177D02*
Y1831752D01*
G01Y1825177D02*
Y1826752D01*
G01X918014D02*
Y1825177D01*
G01Y1831752D02*
Y1830177D01*
G01Y1836752D02*
Y1835177D01*
G01Y1841752D02*
Y1840177D01*
G01Y1846752D02*
Y1845177D01*
G01Y1851752D02*
Y1850177D01*
G01Y1856752D02*
Y1855177D01*
G01Y1881752D02*
Y1880177D01*
G01Y1886752D02*
Y1885177D01*
G01X917008Y1874074D02*
Y1875452D01*
G01Y1867775D02*
Y1869153D01*
G01Y1870925D02*
Y1872303D01*
G01Y1864626D02*
Y1866004D01*
G01Y1861476D02*
Y1862854D01*
G01Y1859704D02*
Y1858326D01*
G01Y1878602D02*
Y1877224D01*
G01X916265Y1859606D02*
Y1858425D01*
G01Y1862756D02*
Y1861574D01*
G01Y1865905D02*
Y1864724D01*
G01Y1869055D02*
Y1867874D01*
G01Y1872204D02*
Y1871023D01*
G01Y1875354D02*
Y1874173D01*
G01Y1878504D02*
Y1877322D01*
G01X915767D02*
Y1878504D01*
G01Y1874173D02*
Y1875354D01*
G01Y1871023D02*
Y1872204D01*
G01Y1867874D02*
Y1869055D01*
G01Y1864724D02*
Y1865905D01*
G01Y1861574D02*
Y1862756D01*
G01Y1858425D02*
Y1859606D01*
G01X913528D02*
Y1858425D01*
G01Y1862756D02*
Y1861574D01*
G01Y1865905D02*
Y1864724D01*
G01Y1869055D02*
Y1867874D01*
G01Y1872204D02*
Y1871023D01*
G01Y1878504D02*
Y1877322D01*
G01Y1875354D02*
Y1874173D01*
G01X905512Y1808878D02*
Y1968051D01*
G01X897638Y1954783D02*
Y1822145D01*
G01X896457Y1856259D02*
Y1880669D01*
G01X896358Y1822145D02*
Y1954783D01*
G01X894980D02*
Y1822145D01*
G01X894488Y1808878D02*
Y1817224D01*
G01X893701Y1878504D02*
Y1895177D01*
G01Y1820374D02*
Y1858425D01*
G01Y1859606D02*
Y1858425D01*
G01Y1861574D02*
Y1859606D01*
G01Y1862756D02*
Y1861574D01*
G01Y1864724D02*
Y1862756D01*
G01Y1867874D02*
Y1865905D01*
G01D02*
Y1864724D01*
G01Y1869055D02*
Y1867874D01*
G01Y1871023D02*
Y1869055D01*
G01Y1872204D02*
Y1871023D01*
G01Y1874173D02*
Y1872204D01*
G01Y1877322D02*
Y1875354D01*
G01D02*
Y1874173D01*
G01Y1878504D02*
Y1877322D01*
G01X891811D02*
Y1878504D01*
G01Y1874173D02*
Y1875354D01*
G01Y1871023D02*
Y1872204D01*
G01Y1867874D02*
Y1869055D01*
G01Y1864724D02*
Y1865905D01*
G01Y1861574D02*
Y1862756D01*
G01Y1858425D02*
Y1859606D01*
G01X890236Y1877322D02*
Y1878504D01*
G01Y1874173D02*
Y1875354D01*
G01Y1871023D02*
Y1872204D01*
G01Y1867874D02*
Y1869055D01*
G01Y1864724D02*
Y1865905D01*
G01Y1861574D02*
Y1862756D01*
G01Y1858425D02*
Y1859606D01*
G01X889764Y1886752D02*
Y1886850D01*
G01Y1885078D02*
Y1885177D01*
G01D02*
Y1886752D01*
G01Y1881752D02*
Y1881850D01*
G01Y1880078D02*
Y1880177D01*
G01D02*
Y1881752D01*
G01Y1856752D02*
Y1856850D01*
G01Y1855078D02*
Y1855177D01*
G01D02*
Y1856752D01*
G01Y1851752D02*
Y1851850D01*
G01Y1850177D02*
Y1851752D01*
G01Y1850078D02*
Y1850177D01*
G01Y1846752D02*
Y1846850D01*
G01Y1845177D02*
Y1846752D01*
G01Y1845078D02*
Y1845177D01*
G01Y1841752D02*
Y1841850D01*
G01Y1840177D02*
Y1841752D01*
G01Y1840078D02*
Y1840177D01*
G01Y1836752D02*
Y1836850D01*
G01Y1835177D02*
Y1836752D01*
G01Y1835078D02*
Y1835177D01*
G01Y1831752D02*
Y1831850D01*
G01Y1830177D02*
Y1831752D01*
G01Y1830078D02*
Y1830177D01*
G01Y1826752D02*
Y1826850D01*
G01Y1825078D02*
Y1825177D01*
G01D02*
Y1826752D01*
G01X889449Y1859606D02*
Y1858425D01*
G01Y1862756D02*
Y1861574D01*
G01Y1865905D02*
Y1864724D01*
G01Y1869055D02*
Y1867874D01*
G01Y1872204D02*
Y1871023D01*
G01Y1875354D02*
Y1874173D01*
G01Y1878504D02*
Y1877322D01*
G01X889055Y1859606D02*
Y1858425D01*
G01Y1862756D02*
Y1861574D01*
G01Y1869055D02*
Y1867874D01*
G01Y1865905D02*
Y1864724D01*
G01Y1872204D02*
Y1871023D01*
G01Y1875354D02*
Y1874173D01*
G01Y1878504D02*
Y1877322D01*
G01X888976Y1879291D02*
Y1879488D01*
G01Y1876141D02*
Y1876535D01*
G01Y1869842D02*
Y1870236D01*
G01Y1872992D02*
Y1873385D01*
G01Y1866693D02*
Y1867086D01*
G01Y1860393D02*
Y1860787D01*
G01Y1863543D02*
Y1863937D01*
G01Y1857441D02*
Y1857637D01*
G01X886811Y1849842D02*
Y1847086D01*
G01Y1884842D02*
Y1882086D01*
G01X886496Y1858405D02*
Y1858241D01*
G01Y1859849D02*
Y1859717D01*
G01X886329Y1859849D02*
Y1859717D01*
G01X886295Y1858241D02*
Y1858425D01*
G01D02*
Y1858438D01*
G01X886128Y1858635D02*
Y1858832D01*
G01X885826Y1858425D02*
Y1858241D01*
G01Y1858438D02*
Y1858425D01*
G01X885793Y1859717D02*
Y1859849D01*
G01X885659D02*
Y1859717D01*
G01X885630Y1879488D02*
Y1880078D01*
G01Y1856850D02*
Y1857441D01*
G01X885625Y1858241D02*
Y1858425D01*
G01D02*
Y1858438D01*
G01X885357Y1857913D02*
Y1857716D01*
G01X885122Y1858425D02*
Y1858176D01*
G01Y1858438D02*
Y1858425D01*
G01X885089Y1859717D02*
Y1859849D01*
G01X884921Y1859685D02*
Y1859882D01*
G01Y1858176D02*
Y1858425D01*
G01D02*
Y1858438D01*
G01X884449Y1877322D02*
Y1878504D01*
G01Y1874173D02*
Y1875354D01*
G01Y1871023D02*
Y1872204D01*
G01Y1864724D02*
Y1865905D01*
G01Y1867874D02*
Y1869055D01*
G01Y1861574D02*
Y1862756D01*
G01Y1858425D02*
Y1859606D01*
G01X884134Y1885177D02*
Y1886752D01*
G01Y1880177D02*
Y1881752D01*
G01Y1855177D02*
Y1856752D01*
G01Y1850177D02*
Y1851752D01*
G01Y1845177D02*
Y1846752D01*
G01Y1840177D02*
Y1841752D01*
G01Y1835177D02*
Y1836752D01*
G01Y1830177D02*
Y1831752D01*
G01Y1825177D02*
Y1826752D01*
G01X882559Y1885177D02*
Y1886752D01*
G01Y1880177D02*
Y1881752D01*
G01Y1855177D02*
Y1856752D01*
G01Y1850177D02*
Y1851752D01*
G01Y1845177D02*
Y1846752D01*
G01Y1840177D02*
Y1841752D01*
G01Y1835177D02*
Y1836752D01*
G01Y1830177D02*
Y1831752D01*
G01Y1825177D02*
Y1826752D01*
G01X881890Y1883031D02*
Y1883897D01*
G01Y1853031D02*
Y1853897D01*
G01Y1848031D02*
Y1848897D01*
G01Y1843031D02*
Y1843897D01*
G01Y1838031D02*
Y1838897D01*
G01Y1833031D02*
Y1833897D01*
G01Y1828031D02*
Y1828897D01*
G01Y1822145D02*
Y1823897D01*
G01X881772Y1826752D02*
Y1825177D01*
G01Y1831752D02*
Y1830177D01*
G01Y1836752D02*
Y1835177D01*
G01Y1841752D02*
Y1840177D01*
G01Y1846752D02*
Y1845177D01*
G01Y1851752D02*
Y1850177D01*
G01Y1856752D02*
Y1855177D01*
G01Y1881752D02*
Y1880177D01*
G01Y1886752D02*
Y1885177D01*
G01X881378Y1826752D02*
Y1825177D01*
G01Y1831752D02*
Y1830177D01*
G01Y1836752D02*
Y1835177D01*
G01Y1841752D02*
Y1840177D01*
G01Y1846752D02*
Y1845177D01*
G01Y1851752D02*
Y1850177D01*
G01Y1856752D02*
Y1855177D01*
G01Y1881752D02*
Y1880177D01*
G01Y1886752D02*
Y1885177D01*
G01X879252Y1881752D02*
Y1881909D01*
G01Y1880039D02*
Y1880177D01*
G01Y1881712D02*
Y1881752D01*
G01Y1880177D02*
Y1880826D01*
G01X879213Y1826752D02*
Y1826870D01*
G01Y1826673D02*
Y1826752D01*
G01Y1825689D02*
Y1825524D01*
G01X879085Y1880859D02*
Y1880236D01*
G01X879012Y1825524D02*
Y1825721D01*
G01X878844Y1825918D02*
Y1826115D01*
G01X878582Y1880236D02*
Y1880859D01*
G01X878543Y1825721D02*
Y1825524D01*
G01X878381Y1880826D02*
Y1880236D01*
G01X878342Y1825524D02*
Y1825721D01*
G01X878074Y1825177D02*
Y1825000D01*
G01Y1825196D02*
Y1825177D01*
G01X877839Y1825721D02*
Y1825459D01*
G01X877677Y1881909D02*
Y1881752D01*
G01Y1880177D02*
Y1880039D01*
G01Y1881752D02*
Y1881712D01*
G01Y1880236D02*
Y1880177D01*
G01X877638Y1825459D02*
Y1825721D01*
G01Y1826870D02*
Y1826752D01*
G01D02*
Y1826673D01*
G01X876457Y1885177D02*
Y1886752D01*
G01Y1855177D02*
Y1856752D01*
G01Y1850177D02*
Y1851752D01*
G01Y1845177D02*
Y1846752D01*
G01Y1840177D02*
Y1841752D01*
G01Y1835177D02*
Y1836752D01*
G01Y1830177D02*
Y1831752D01*
G01Y1825177D02*
Y1826752D01*
G01X875000Y1880177D02*
Y1881752D01*
G01X874016Y1808878D02*
Y1822145D01*
G01X886496Y1859717D02*
X886473Y1859606D01*
G01D02*
X886463Y1859554D01*
G01X884921Y1858438D02*
X884955Y1858602D01*
G01X884921Y1859882D02*
X884955Y1860046D01*
G01X877638Y1825721D02*
X877671Y1825885D01*
G01X878415Y1880991D02*
X878381Y1880826D01*
G01X879213Y1825524D02*
X879179Y1825393D01*
G01X886496Y1858241D02*
X886463Y1858110D01*
G01X877872Y1825853D02*
X877839Y1825721D01*
G01X886329Y1859717D02*
X886300Y1859606D01*
G01D02*
X886295Y1859586D01*
G01X885793Y1859849D02*
X885826Y1859980D01*
G01X885659Y1859717D02*
X885630Y1859606D01*
G01D02*
X885625Y1859586D01*
G01X885156Y1858569D02*
X885122Y1858438D01*
G01X885089Y1859849D02*
X885122Y1859980D01*
G01X878978Y1825426D02*
X879012Y1825524D01*
G01X886262Y1858143D02*
X886295Y1858241D01*
G01X878582Y1880859D02*
X878615Y1880958D01*
G01X879179Y1825393D02*
X879112Y1825262D01*
G01X877671Y1825885D02*
X877739Y1826017D01*
G01X886463Y1858110D02*
X886396Y1857979D01*
G01X886463Y1859554D02*
X886362Y1859389D01*
G01X884955Y1860046D02*
X885056Y1860209D01*
G01X885726Y1859455D02*
X885692Y1859389D01*
G01X885625Y1859586D02*
X885558Y1859455D01*
G01X884955Y1858602D02*
X885022Y1858733D01*
G01X885726Y1860111D02*
X885759Y1860177D01*
G01X885122Y1859980D02*
X885189Y1860111D01*
G01X878911Y1825328D02*
X878978Y1825426D01*
G01X877939Y1825951D02*
X877872Y1825853D01*
G01X886195Y1858044D02*
X886262Y1858143D01*
G01X885223Y1858668D02*
X885156Y1858569D01*
G01X886295Y1859586D02*
X886195Y1859455D01*
G01X885692Y1859389D02*
X885591Y1859258D01*
G01X885826Y1859980D02*
X885927Y1860111D01*
G01X878515Y1881122D02*
X878415Y1880991D01*
G01X879025Y1825177D02*
X878978Y1825131D01*
G01X879112Y1825262D02*
X879025Y1825177D01*
G01X877739Y1826017D02*
X877872Y1826148D01*
G01X886396Y1857979D02*
X886262Y1857847D01*
G01X886362Y1859389D02*
X886262Y1859291D01*
G01X885022Y1858733D02*
X885156Y1858865D01*
G01X885759Y1860177D02*
X885859Y1860275D01*
G01X885056Y1860209D02*
X885156Y1860308D01*
G01X878978Y1826476D02*
X879213Y1826673D01*
G01X878945D02*
X878710Y1826476D01*
G01X878615Y1880958D02*
X878683Y1881023D01*
G01X878040Y1826017D02*
X877939Y1825951D01*
G01X885324Y1858733D02*
X885223Y1858668D01*
G01X886195Y1859455D02*
X886094Y1859389D01*
G01X885558Y1859455D02*
X885424Y1859357D01*
G01X885189Y1860111D02*
X885324Y1860209D01*
G01X878649Y1881220D02*
X878515Y1881122D01*
G01X879018Y1881515D02*
X879252Y1881712D01*
G01X878984D02*
X878750Y1881515D01*
G01X877872Y1826148D02*
X878007Y1826213D01*
G01X885927Y1860111D02*
X886027Y1860177D01*
G01X885039Y1825078D02*
X881890Y1823897D01*
G01X885039Y1830078D02*
X881890Y1828897D01*
G01X885039Y1835078D02*
X881890Y1833897D01*
G01X885039Y1840078D02*
X881890Y1838897D01*
G01X885039Y1845078D02*
X881890Y1843897D01*
G01X885039Y1850078D02*
X881890Y1848897D01*
G01X886262Y1859291D02*
X886094Y1859225D01*
G01X885591Y1859258D02*
X885424Y1859193D01*
G01X885156Y1860308D02*
X885324Y1860374D01*
G01X885156Y1858865D02*
X885290Y1858930D01*
G01X885859Y1860275D02*
X885994Y1860341D01*
G01X891339Y1858326D02*
X888976Y1857637D01*
G01X891339Y1861476D02*
X888976Y1860787D01*
G01X891339Y1864626D02*
X888976Y1863937D01*
G01X891339Y1867775D02*
X888976Y1867086D01*
G01X891339Y1870925D02*
X888976Y1870236D01*
G01X891339Y1874074D02*
X888976Y1873385D01*
G01X891339Y1877224D02*
X888976Y1876535D01*
G01X878811Y1825295D02*
X878911Y1825328D01*
G01X886094Y1858011D02*
X886195Y1858044D01*
G01X878683Y1881023D02*
X878783Y1881056D01*
G01X878750Y1881253D02*
X878649Y1881220D01*
G01X885039Y1855078D02*
X881890Y1853897D01*
G01X885039Y1885078D02*
X881890Y1883897D01*
G01X884400Y1964842D02*
G03Y1961693I2017J-1574D01*
G01X888435D02*
G03Y1964842I-2017J1574D01*
G01X888788Y1960905D02*
G03Y1965630I-2370J2362D01*
G01X884047D02*
G03Y1960905I2370J-2362D01*
G01X889921Y1963267D02*
G03I-3503J0D01*
G01X889095Y1960118D02*
G03Y1966417I-2678J3149D01*
G01X883740D02*
G03Y1960118I2678J-3149D01*
G01X881890Y1953031D02*
X885039Y1951850D01*
G01X881890Y1948031D02*
X885039Y1946850D01*
G01X881890Y1943031D02*
X885039Y1941850D01*
G01X881890Y1933031D02*
X885039Y1931850D01*
G01X881890Y1928031D02*
X885039Y1926850D01*
G01X881890Y1923031D02*
X885039Y1921850D01*
G01X881890Y1918031D02*
X885039Y1916850D01*
G01X881890Y1913031D02*
X885039Y1911850D01*
G01X881890Y1908031D02*
X885039Y1906850D01*
G01X881890Y1903031D02*
X885039Y1901850D01*
G01X881890Y1893031D02*
X885039Y1891850D01*
G01X881890Y1938031D02*
X887008Y1936850D01*
G01X881890Y1898031D02*
X887008Y1896850D01*
G01X905512Y1970019D02*
X885827D01*
G01X927953Y1968051D02*
X874016D01*
G01X894488Y1966870D02*
X927953D01*
G01X883740Y1966417D02*
X889095D01*
G01X888788Y1965630D02*
X884047D01*
G01X884400Y1964842D02*
X888435D01*
G01X894488Y1962657D02*
X874016D01*
G01X905512D02*
X894488D01*
G01X884400Y1961693D02*
X888435D01*
G01X884047Y1960905D02*
X888788D01*
G01X889095Y1960118D02*
X883740D01*
G01X924016Y1959704D02*
X874016D01*
G01X893701Y1956555D02*
X874016D01*
G01Y1954783D02*
X893701D01*
G01D02*
X894980D01*
G01X924803D02*
X896358D01*
G01X889764Y1951850D02*
X885039D01*
G01X925984D02*
X893701D01*
G01Y1951752D02*
X924223D01*
G01X876457D02*
X893701D01*
G01Y1950177D02*
X924223D01*
G01X893701D02*
X876457D01*
G01X893701Y1950078D02*
X925984D01*
G01X885039D02*
X889764D01*
G01X893701Y1946850D02*
X925984D01*
G01X889764D02*
X885039D01*
G01X893701Y1946752D02*
X924223D01*
G01X876457D02*
X893701D01*
G01Y1945177D02*
X924223D01*
G01X893701D02*
X876457D01*
G01X893701Y1945078D02*
X925984D01*
G01X885039D02*
X889764D01*
G01X893701Y1941850D02*
X925984D01*
G01X889764D02*
X885039D01*
G01X893701Y1941752D02*
X924223D01*
G01X876457D02*
X893701D01*
G01Y1940177D02*
X924223D01*
G01X893701D02*
X876457D01*
G01X893701Y1940078D02*
X925984D01*
G01X885039D02*
X889764D01*
G01X894882Y1938326D02*
X893701D01*
G01X891732Y1936850D02*
X887008D01*
G01X925984D02*
X894882D01*
G01Y1936752D02*
X924223D01*
G01X875000D02*
X894882D01*
G01Y1935177D02*
X924223D01*
G01X875000D02*
X894882D01*
G01Y1935078D02*
X925984D01*
G01X887008D02*
X891732D01*
G01X886811Y1934842D02*
X893701D01*
G01Y1933602D02*
X894882D01*
G01X893701Y1932086D02*
X886811D01*
G01X893701Y1931850D02*
X925984D01*
G01X889764D02*
X885039D01*
G01X893701Y1931752D02*
X924223D01*
G01X876457D02*
X893701D01*
G01Y1930177D02*
X924223D01*
G01X893701D02*
X876457D01*
G01X893701Y1930078D02*
X925984D01*
G01X885039D02*
X889764D01*
G01X893701Y1926850D02*
X925984D01*
G01X889764D02*
X885039D01*
G01X893701Y1926752D02*
X924223D01*
G01X876457D02*
X893701D01*
G01Y1925177D02*
X924223D01*
G01X893701D02*
X876457D01*
G01X893701Y1925078D02*
X925984D01*
G01X885039D02*
X889764D01*
G01X893701Y1921850D02*
X925984D01*
G01X889764D02*
X885039D01*
G01X893701Y1921752D02*
X924223D01*
G01X876457D02*
X893701D01*
G01Y1920177D02*
X924223D01*
G01X893701D02*
X876457D01*
G01X893701Y1920078D02*
X925984D01*
G01X885039D02*
X889764D01*
G01X893701Y1916850D02*
X925984D01*
G01X889764D02*
X885039D01*
G01X893701Y1916752D02*
X924223D01*
G01X876457D02*
X893701D01*
G01Y1915177D02*
X924223D01*
G01X893701D02*
X876457D01*
G01X893701Y1915078D02*
X925984D01*
G01X885039D02*
X889764D01*
G01X893701Y1911850D02*
X925984D01*
G01X889764D02*
X885039D01*
G01X893701Y1911752D02*
X924223D01*
G01X876457D02*
X893701D01*
G01Y1910177D02*
X924223D01*
G01X893701D02*
X876457D01*
G01X893701Y1910078D02*
X925984D01*
G01X885039D02*
X889764D01*
G01X886811Y1909842D02*
X893701D01*
G01Y1907086D02*
X886811D01*
G01X893701Y1906850D02*
X925984D01*
G01X889764D02*
X885039D01*
G01X893701Y1906752D02*
X924223D01*
G01X876457D02*
X893701D01*
G01Y1905177D02*
X924223D01*
G01X893701D02*
X876457D01*
G01X893701Y1905078D02*
X925984D01*
G01X885039D02*
X889764D01*
G01X893701Y1901850D02*
X925984D01*
G01X889764D02*
X885039D01*
G01X893701Y1901752D02*
X924223D01*
G01X876457D02*
X893701D01*
G01Y1900177D02*
X924223D01*
G01X893701D02*
X876457D01*
G01X893701Y1900078D02*
X925984D01*
G01X885039D02*
X889764D01*
G01X894882Y1898326D02*
X893701D01*
G01X891732Y1896850D02*
X887008D01*
G01X925984D02*
X894882D01*
G01Y1896752D02*
X924223D01*
G01X875000D02*
X894882D01*
G01Y1895177D02*
X924223D01*
G01X875000D02*
X894882D01*
G01Y1895078D02*
X925984D01*
G01X887008D02*
X891732D01*
G01X893701Y1893602D02*
X894882D01*
G01X893701Y1891850D02*
X925984D01*
G01X889764D02*
X885039D01*
G01X893701Y1891752D02*
X924223D01*
G01X876457D02*
X893701D01*
G01Y1890177D02*
X924223D01*
G01X893701D02*
X876457D01*
G01X893701Y1890078D02*
X925984D01*
G01X885039D02*
X889764D01*
G01X887008Y1935078D02*
X881890Y1933897D01*
G01X887008Y1895078D02*
X881890Y1893897D01*
G01X919366Y1950177D02*
Y1951752D01*
G01Y1945177D02*
Y1946752D01*
G01Y1940177D02*
Y1941752D01*
G01Y1935177D02*
Y1936752D01*
G01Y1930177D02*
Y1931752D01*
G01Y1925177D02*
Y1926752D01*
G01Y1920177D02*
Y1921752D01*
G01Y1915177D02*
Y1916752D01*
G01Y1910177D02*
Y1911752D01*
G01Y1905177D02*
Y1906752D01*
G01Y1900177D02*
Y1901752D01*
G01Y1895177D02*
Y1896752D01*
G01Y1890177D02*
Y1891752D01*
G01X919121Y1950177D02*
Y1951752D01*
G01Y1945177D02*
Y1946752D01*
G01Y1940177D02*
Y1941752D01*
G01Y1935177D02*
Y1936752D01*
G01Y1930177D02*
Y1931752D01*
G01Y1925177D02*
Y1926752D01*
G01Y1920177D02*
Y1921752D01*
G01Y1915177D02*
Y1916752D01*
G01Y1910177D02*
Y1911752D01*
G01Y1905177D02*
Y1906752D01*
G01Y1900177D02*
Y1901752D01*
G01Y1895177D02*
Y1896752D01*
G01Y1890177D02*
Y1891752D01*
G01X918014D02*
Y1890177D01*
G01Y1896752D02*
Y1895177D01*
G01Y1901752D02*
Y1900177D01*
G01Y1906752D02*
Y1905177D01*
G01Y1911752D02*
Y1910177D01*
G01Y1916752D02*
Y1915177D01*
G01Y1921752D02*
Y1920177D01*
G01Y1926752D02*
Y1925177D01*
G01Y1931752D02*
Y1930177D01*
G01Y1936752D02*
Y1935177D01*
G01Y1941752D02*
Y1940177D01*
G01Y1946752D02*
Y1945177D01*
G01Y1951752D02*
Y1950177D01*
G01X905512Y1968051D02*
Y1981004D01*
G01X894882Y1933602D02*
Y1938326D01*
G01Y1893602D02*
Y1898326D01*
G01X894488Y1959704D02*
Y1968051D01*
G01X893701Y1936752D02*
Y1956555D01*
G01Y1896752D02*
Y1935177D01*
G01Y1896752D02*
Y1895177D01*
G01Y1936752D02*
Y1935177D01*
G01X891732Y1936752D02*
Y1936850D01*
G01Y1935078D02*
Y1935177D01*
G01D02*
Y1936752D01*
G01Y1896752D02*
Y1896850D01*
G01Y1895078D02*
Y1895177D01*
G01D02*
Y1896752D01*
G01X889764Y1951752D02*
Y1951850D01*
G01Y1950078D02*
Y1950177D01*
G01D02*
Y1951752D01*
G01Y1946752D02*
Y1946850D01*
G01Y1945078D02*
Y1945177D01*
G01D02*
Y1946752D01*
G01Y1941752D02*
Y1941850D01*
G01Y1940078D02*
Y1940177D01*
G01D02*
Y1941752D01*
G01Y1931752D02*
Y1931850D01*
G01Y1930078D02*
Y1930177D01*
G01D02*
Y1931752D01*
G01Y1926752D02*
Y1926850D01*
G01Y1925177D02*
Y1926752D01*
G01Y1925078D02*
Y1925177D01*
G01Y1921752D02*
Y1921850D01*
G01Y1920177D02*
Y1921752D01*
G01Y1920078D02*
Y1920177D01*
G01Y1916752D02*
Y1916850D01*
G01Y1915177D02*
Y1916752D01*
G01Y1915078D02*
Y1915177D01*
G01Y1911752D02*
Y1911850D01*
G01Y1910177D02*
Y1911752D01*
G01Y1910078D02*
Y1910177D01*
G01Y1906752D02*
Y1906850D01*
G01Y1905177D02*
Y1906752D01*
G01Y1905078D02*
Y1905177D01*
G01Y1901752D02*
Y1901850D01*
G01Y1900078D02*
Y1900177D01*
G01D02*
Y1901752D01*
G01Y1891752D02*
Y1891850D01*
G01Y1890078D02*
Y1890177D01*
G01D02*
Y1891752D01*
G01X886811Y1909842D02*
Y1907086D01*
G01Y1934842D02*
Y1932086D01*
G01X885827Y1968051D02*
Y1981004D01*
G01X884134Y1950177D02*
Y1951752D01*
G01Y1945177D02*
Y1946752D01*
G01Y1940177D02*
Y1941752D01*
G01Y1935177D02*
Y1936752D01*
G01Y1930177D02*
Y1931752D01*
G01Y1925177D02*
Y1926752D01*
G01Y1920177D02*
Y1921752D01*
G01Y1915177D02*
Y1916752D01*
G01Y1910177D02*
Y1911752D01*
G01Y1905177D02*
Y1906752D01*
G01Y1900177D02*
Y1901752D01*
G01Y1895177D02*
Y1896752D01*
G01Y1890177D02*
Y1891752D01*
G01X882559Y1950177D02*
Y1951752D01*
G01Y1945177D02*
Y1946752D01*
G01Y1940177D02*
Y1941752D01*
G01Y1935177D02*
Y1936752D01*
G01Y1930177D02*
Y1931752D01*
G01Y1925177D02*
Y1926752D01*
G01Y1920177D02*
Y1921752D01*
G01Y1915177D02*
Y1916752D01*
G01Y1910177D02*
Y1911752D01*
G01Y1905177D02*
Y1906752D01*
G01Y1900177D02*
Y1901752D01*
G01Y1895177D02*
Y1896752D01*
G01Y1890177D02*
Y1891752D01*
G01X881890Y1953031D02*
Y1954783D01*
G01Y1948031D02*
Y1948897D01*
G01Y1943031D02*
Y1943897D01*
G01Y1938031D02*
Y1938897D01*
G01Y1933031D02*
Y1933897D01*
G01Y1928031D02*
Y1928897D01*
G01Y1923031D02*
Y1923897D01*
G01Y1918031D02*
Y1918897D01*
G01Y1913031D02*
Y1913897D01*
G01Y1908031D02*
Y1908897D01*
G01Y1903031D02*
Y1903897D01*
G01Y1898031D02*
Y1898897D01*
G01Y1893031D02*
Y1893897D01*
G01Y1888031D02*
Y1888897D01*
G01X881772Y1891752D02*
Y1890177D01*
G01Y1896752D02*
Y1895177D01*
G01Y1901752D02*
Y1900177D01*
G01Y1906752D02*
Y1905177D01*
G01Y1911752D02*
Y1910177D01*
G01Y1916752D02*
Y1915177D01*
G01Y1921752D02*
Y1920177D01*
G01Y1926752D02*
Y1925177D01*
G01Y1931752D02*
Y1930177D01*
G01Y1936752D02*
Y1935177D01*
G01Y1941752D02*
Y1940177D01*
G01Y1946752D02*
Y1945177D01*
G01Y1951752D02*
Y1950177D01*
G01X881378Y1891752D02*
Y1890177D01*
G01Y1896752D02*
Y1895177D01*
G01Y1901752D02*
Y1900177D01*
G01Y1906752D02*
Y1905177D01*
G01Y1911752D02*
Y1910177D01*
G01Y1916752D02*
Y1915177D01*
G01Y1921752D02*
Y1920177D01*
G01Y1926752D02*
Y1925177D01*
G01Y1931752D02*
Y1930177D01*
G01Y1936752D02*
Y1935177D01*
G01Y1941752D02*
Y1940177D01*
G01Y1946752D02*
Y1945177D01*
G01Y1951752D02*
Y1950177D01*
G01X876457D02*
Y1951752D01*
G01Y1945177D02*
Y1946752D01*
G01Y1940177D02*
Y1941752D01*
G01Y1930177D02*
Y1931752D01*
G01Y1925177D02*
Y1926752D01*
G01Y1920177D02*
Y1921752D01*
G01Y1915177D02*
Y1916752D01*
G01Y1910177D02*
Y1911752D01*
G01Y1905177D02*
Y1906752D01*
G01Y1900177D02*
Y1901752D01*
G01Y1890177D02*
Y1891752D01*
G01X875000Y1935177D02*
Y1936752D01*
G01Y1895177D02*
Y1896752D01*
G01X874016Y1954783D02*
Y1968051D01*
G01X885039Y1890078D02*
X881890Y1888897D01*
G01X885039Y1900078D02*
X881890Y1898897D01*
G01X885039Y1905078D02*
X881890Y1903897D01*
G01X885039Y1910078D02*
X881890Y1908897D01*
G01X885039Y1915078D02*
X881890Y1913897D01*
G01X885039Y1920078D02*
X881890Y1918897D01*
G01X885039Y1925078D02*
X881890Y1923897D01*
G01X885039Y1930078D02*
X881890Y1928897D01*
G01X885039Y1940078D02*
X881890Y1938897D01*
G01X885039Y1945078D02*
X881890Y1943897D01*
G01X885039Y1950078D02*
X881890Y1948897D01*
G01X899409Y1975078D02*
G03I-3740J0D01*
G01X881890Y1984941D02*
X909449D01*
G01X905512Y1981004D02*
X885827D01*
G01X905512Y1979035D02*
X885827D01*
G01X905512Y1977047D02*
X885827D01*
G01Y1976063D02*
X905512D01*
G01X905315Y1975866D02*
X886024D01*
G01X905315Y1974291D02*
X886024D01*
G01X905512Y1974094D02*
X885827D01*
G01Y1973110D02*
X905512D01*
G01X909449Y1971988D02*
X936614D01*
G01X881890D02*
X870079D01*
G01X909449Y1984941D02*
Y1971988D01*
G01X905315Y1974291D02*
Y1975866D01*
G01X899961D02*
Y1974291D01*
G01X898622Y1974094D02*
Y1974291D01*
G01Y1975866D02*
Y1976063D01*
G01Y1975866D02*
Y1974291D01*
G01X898425Y1975866D02*
Y1974291D01*
G01X896850Y1975866D02*
Y1974291D01*
G01X894488Y1975866D02*
Y1974291D01*
G01X892913D02*
Y1975866D01*
G01X892717D02*
Y1976063D01*
G01Y1974291D02*
Y1975866D01*
G01Y1974291D02*
Y1974094D01*
G01X891378Y1974291D02*
Y1975866D01*
G01X886024D02*
Y1974291D01*
G01X881890Y1971988D02*
Y1984941D01*
G01X877601Y2123670D02*
X878599Y2123860D01*
X879740Y2124430D01*
X880453Y2125381D01*
X880738Y2126712D01*
X880453Y2128042D01*
X879597Y2129183D01*
X878314Y2129754D01*
X876888D01*
X876032Y2130134D01*
X875319Y2131084D01*
X875034Y2132415D01*
X875462Y2133746D01*
X876460Y2134697D01*
X877601Y2135077D01*
X878742Y2134697D01*
X879740Y2133746D01*
X880168Y2132415D01*
X879883Y2131084D01*
X879170Y2130134D01*
X878314Y2129754D01*
X876888D01*
X875605Y2129183D01*
X874749Y2128042D01*
X874464Y2126712D01*
X874749Y2125381D01*
X875462Y2124430D01*
X876603Y2123860D01*
X877601Y2123670D01*
G01X986945Y-38936D02*
Y-57873D01*
G01X1009842Y149606D02*
G03I-15748J0D01*
G01X1001082D02*
G03I-6988J0D01*
G01X932677Y191476D02*
X927953Y186830D01*
G01X927957Y187938D02*
X932677Y192580D01*
G01X924016Y195177D02*
X925984Y197145D01*
G01X936614Y182893D02*
Y349941D01*
G01X932677Y191476D02*
Y193208D01*
G01X927953Y195177D02*
Y188011D01*
G01X925984Y195177D02*
Y337657D01*
G01X924803Y200098D02*
Y332736D01*
G01X924223Y228130D02*
Y229704D01*
G01Y223130D02*
Y224704D01*
G01Y218130D02*
Y219704D01*
G01Y213130D02*
Y214704D01*
G01Y208130D02*
Y209704D01*
G01Y203130D02*
Y204704D01*
G01X923541D02*
Y203130D01*
G01Y209704D02*
Y208130D01*
G01Y214704D02*
Y213130D01*
G01Y219704D02*
Y218130D01*
G01Y224704D02*
Y223130D01*
G01Y229704D02*
Y228130D01*
G01X923032Y228031D02*
Y229803D01*
G01Y223031D02*
Y224803D01*
G01Y218031D02*
Y219803D01*
G01Y213031D02*
Y214803D01*
G01Y208031D02*
Y209803D01*
G01Y203031D02*
Y204803D01*
G01X924803Y200098D02*
X925984Y198917D01*
G01X932677Y193208D02*
X929268Y195177D01*
G01X925984D02*
X929268D01*
G01X924016Y256181D02*
X925984Y258149D01*
G01X925787Y255177D02*
Y256555D01*
G01Y237657D02*
Y236279D01*
G01Y243956D02*
Y242578D01*
G01Y240807D02*
Y239429D01*
G01Y247106D02*
Y245728D01*
G01Y253405D02*
Y252027D01*
G01Y250256D02*
Y248878D01*
G01X924223Y313130D02*
Y314704D01*
G01Y308130D02*
Y309704D01*
G01Y303130D02*
Y304704D01*
G01Y298130D02*
Y299704D01*
G01Y293130D02*
Y294704D01*
G01Y288130D02*
Y289704D01*
G01Y283130D02*
Y284704D01*
G01Y278130D02*
Y279704D01*
G01Y273130D02*
Y274704D01*
G01Y268130D02*
Y269704D01*
G01Y263130D02*
Y264704D01*
G01X924102Y258130D02*
Y259704D01*
G01Y233130D02*
Y234704D01*
G01X924016Y258622D02*
Y234212D01*
G01X923541Y264704D02*
Y263130D01*
G01Y269704D02*
Y268130D01*
G01Y274704D02*
Y273130D01*
G01Y279704D02*
Y278130D01*
G01Y284704D02*
Y283130D01*
G01Y289704D02*
Y288130D01*
G01Y294704D02*
Y293130D01*
G01Y299704D02*
Y298130D01*
G01Y304704D02*
Y303130D01*
G01Y309704D02*
Y308130D01*
G01Y314704D02*
Y313130D01*
G01X923114Y234704D02*
Y233130D01*
G01Y259704D02*
Y258130D01*
G01X923032Y313031D02*
Y314803D01*
G01Y308031D02*
Y309803D01*
G01Y303031D02*
Y304803D01*
G01Y298031D02*
Y299803D01*
G01Y293031D02*
Y294803D01*
G01Y288031D02*
Y289803D01*
G01Y283031D02*
Y284803D01*
G01Y278031D02*
Y279803D01*
G01Y273031D02*
Y274803D01*
G01Y268031D02*
Y269803D01*
G01Y263031D02*
Y264803D01*
G01Y258031D02*
Y259803D01*
G01Y233031D02*
Y234803D01*
G01X924016Y236653D02*
X925984Y234685D01*
G01Y256555D02*
X925787D01*
G01Y255177D02*
X925984D01*
G01Y253405D02*
X925787D01*
G01Y252027D02*
X925984D01*
G01Y250256D02*
X925787D01*
G01Y248878D02*
X925984D01*
G01Y247106D02*
X925787D01*
G01Y245728D02*
X925984D01*
G01Y243956D02*
X925787D01*
G01Y242578D02*
X925984D01*
G01Y240807D02*
X925787D01*
G01Y239429D02*
X925984D01*
G01Y237657D02*
X925787D01*
G01Y236279D02*
X925984D01*
G01X929268Y337657D02*
X932677Y339626D01*
G01X924803Y332736D02*
X925984Y333917D01*
G01X932677Y339626D02*
Y341358D01*
G01X927953Y344822D02*
Y337657D01*
G01X924223Y328130D02*
Y329704D01*
G01Y323130D02*
Y324704D01*
G01Y318130D02*
Y319704D01*
G01X923541D02*
Y318130D01*
G01Y324704D02*
Y323130D01*
G01Y329704D02*
Y328130D01*
G01X923032Y328031D02*
Y329803D01*
G01Y323031D02*
Y324803D01*
G01Y318031D02*
Y319803D01*
G01X925984Y335689D02*
X924016Y337657D01*
G01X927953Y346004D02*
X932677Y341358D01*
G01Y340255D02*
X927957Y344896D01*
G01X925984Y337657D02*
X929268D01*
G01X932677Y596988D02*
X927953Y592342D01*
G01X927957Y593450D02*
X932677Y598091D01*
G01X924016Y600689D02*
X925984Y602657D01*
G01X936614Y588405D02*
Y755452D01*
G01X932677Y596988D02*
Y598720D01*
G01X927953Y600689D02*
Y593523D01*
G01X925984Y600689D02*
Y743169D01*
G01X925787Y646319D02*
Y644941D01*
G01Y643169D02*
Y641791D01*
G01X924803Y605610D02*
Y738248D01*
G01X924223Y633641D02*
Y635216D01*
G01Y628641D02*
Y630216D01*
G01Y623641D02*
Y625216D01*
G01Y618641D02*
Y620216D01*
G01Y613641D02*
Y615216D01*
G01Y608641D02*
Y610216D01*
G01X924102Y638641D02*
Y640216D01*
G01X924016Y664133D02*
Y639724D01*
G01X923541Y610216D02*
Y608641D01*
G01Y615216D02*
Y613641D01*
G01Y620216D02*
Y618641D01*
G01Y625216D02*
Y623641D01*
G01Y630216D02*
Y628641D01*
G01Y635216D02*
Y633641D01*
G01X923114Y640216D02*
Y638641D01*
G01X923032Y638543D02*
Y640315D01*
G01Y633543D02*
Y635315D01*
G01Y628543D02*
Y630315D01*
G01Y623543D02*
Y625315D01*
G01Y618543D02*
Y620315D01*
G01Y613543D02*
Y615315D01*
G01Y608543D02*
Y610315D01*
G01X924016Y642165D02*
X925984Y640196D01*
G01X924803Y605610D02*
X925984Y604429D01*
G01X932677Y598720D02*
X929268Y600689D01*
G01X925787Y644941D02*
X925984D01*
G01Y643169D02*
X925787D01*
G01Y641791D02*
X925984D01*
G01Y600689D02*
X929268D01*
G01X1009842Y673228D02*
G03I-15748J0D01*
G01X1001082D02*
G03I-6988J0D01*
G01X924016Y661693D02*
X925984Y663661D01*
G01X925787Y660689D02*
Y662067D01*
G01Y649468D02*
Y648090D01*
G01Y655767D02*
Y654389D01*
G01Y652618D02*
Y651240D01*
G01Y658917D02*
Y657539D01*
G01X924223Y728641D02*
Y730216D01*
G01Y723641D02*
Y725216D01*
G01Y718641D02*
Y720216D01*
G01Y713641D02*
Y715216D01*
G01Y708641D02*
Y710216D01*
G01Y703641D02*
Y705216D01*
G01Y698641D02*
Y700216D01*
G01Y693641D02*
Y695216D01*
G01Y688641D02*
Y690216D01*
G01Y683641D02*
Y685216D01*
G01Y678641D02*
Y680216D01*
G01Y673641D02*
Y675216D01*
G01Y668641D02*
Y670216D01*
G01X924102Y663641D02*
Y665216D01*
G01X923541Y670216D02*
Y668641D01*
G01Y675216D02*
Y673641D01*
G01Y680216D02*
Y678641D01*
G01Y685216D02*
Y683641D01*
G01Y690216D02*
Y688641D01*
G01Y695216D02*
Y693641D01*
G01Y700216D02*
Y698641D01*
G01Y705216D02*
Y703641D01*
G01Y710216D02*
Y708641D01*
G01Y715216D02*
Y713641D01*
G01Y720216D02*
Y718641D01*
G01Y725216D02*
Y723641D01*
G01Y730216D02*
Y728641D01*
G01X923114Y665216D02*
Y663641D01*
G01X923032Y728543D02*
Y730315D01*
G01Y723543D02*
Y725315D01*
G01Y718543D02*
Y720315D01*
G01Y713543D02*
Y715315D01*
G01Y708543D02*
Y710315D01*
G01Y703543D02*
Y705315D01*
G01Y698543D02*
Y700315D01*
G01Y693543D02*
Y695315D01*
G01Y688543D02*
Y690315D01*
G01Y683543D02*
Y685315D01*
G01Y678543D02*
Y680315D01*
G01Y673543D02*
Y675315D01*
G01Y668543D02*
Y670315D01*
G01Y663543D02*
Y665315D01*
G01X925984Y662067D02*
X925787D01*
G01Y660689D02*
X925984D01*
G01Y658917D02*
X925787D01*
G01Y657539D02*
X925984D01*
G01Y655767D02*
X925787D01*
G01Y654389D02*
X925984D01*
G01Y652618D02*
X925787D01*
G01Y651240D02*
X925984D01*
G01Y649468D02*
X925787D01*
G01Y648090D02*
X925984D01*
G01Y646319D02*
X925787D01*
G01X924803Y738248D02*
X925984Y739429D01*
G01X929268Y743169D02*
X932677Y745137D01*
G01D02*
Y746870D01*
G01X927953Y750334D02*
Y743169D01*
G01X924223Y733641D02*
Y735216D01*
G01X923541D02*
Y733641D01*
G01X923032Y733543D02*
Y735315D01*
G01X925984Y741200D02*
X924016Y743169D01*
G01X927953Y751515D02*
X932677Y746870D01*
G01Y745767D02*
X927957Y750408D01*
G01X925984Y743169D02*
X929268D01*
G01X1009842Y1068898D02*
G03I-15748J0D01*
G01X936614Y993917D02*
Y1160964D01*
G01X932677Y1002500D02*
Y1004232D01*
G01X927953Y1006200D02*
Y999035D01*
G01X925984Y1006200D02*
Y1148681D01*
G01X925787Y1048681D02*
Y1047303D01*
G01Y1051830D02*
Y1050452D01*
G01Y1058130D02*
Y1056752D01*
G01Y1054980D02*
Y1053602D01*
G01Y1061279D02*
Y1059901D01*
G01X924803Y1011122D02*
Y1143759D01*
G01X924223Y1039153D02*
Y1040728D01*
G01Y1034153D02*
Y1035728D01*
G01Y1029153D02*
Y1030728D01*
G01Y1024153D02*
Y1025728D01*
G01Y1019153D02*
Y1020728D01*
G01Y1014153D02*
Y1015728D01*
G01X924102Y1044153D02*
Y1045728D01*
G01X924016Y1069645D02*
Y1045236D01*
G01X923541Y1015728D02*
Y1014153D01*
G01Y1020728D02*
Y1019153D01*
G01Y1025728D02*
Y1024153D01*
G01Y1030728D02*
Y1029153D01*
G01Y1035728D02*
Y1034153D01*
G01Y1040728D02*
Y1039153D01*
G01X923114Y1045728D02*
Y1044153D01*
G01X923032Y1044055D02*
Y1045826D01*
G01Y1039055D02*
Y1040826D01*
G01Y1034055D02*
Y1035826D01*
G01Y1029055D02*
Y1030826D01*
G01Y1024055D02*
Y1025826D01*
G01Y1019055D02*
Y1020826D01*
G01Y1014055D02*
Y1015826D01*
G01X925984Y1045708D02*
X924016Y1047677D01*
G01X924803Y1011122D02*
X925984Y1009941D01*
G01X932677Y1002500D02*
X927953Y997854D01*
G01X927957Y998961D02*
X932677Y1003603D01*
G01X924016Y1006200D02*
X925984Y1008169D01*
G01X932677Y1004232D02*
X929268Y1006200D01*
G01X925787Y1059901D02*
X925984D01*
G01Y1058130D02*
X925787D01*
G01Y1056752D02*
X925984D01*
G01Y1054980D02*
X925787D01*
G01Y1053602D02*
X925984D01*
G01Y1051830D02*
X925787D01*
G01Y1050452D02*
X925984D01*
G01Y1048681D02*
X925787D01*
G01Y1047303D02*
X925984D01*
G01Y1006200D02*
X929268D01*
G01X1001082Y1068898D02*
G03I-6988J0D01*
G01X925787Y1066200D02*
Y1067578D01*
G01Y1064429D02*
Y1063051D01*
G01X924223Y1139153D02*
Y1140728D01*
G01Y1134153D02*
Y1135728D01*
G01Y1129153D02*
Y1130728D01*
G01Y1124153D02*
Y1125728D01*
G01Y1119153D02*
Y1120728D01*
G01Y1114153D02*
Y1115728D01*
G01Y1109153D02*
Y1110728D01*
G01Y1104153D02*
Y1105728D01*
G01Y1099153D02*
Y1100728D01*
G01Y1094153D02*
Y1095728D01*
G01Y1089153D02*
Y1090728D01*
G01Y1084153D02*
Y1085728D01*
G01Y1079153D02*
Y1080728D01*
G01Y1074153D02*
Y1075728D01*
G01X924102Y1069153D02*
Y1070728D01*
G01X923541Y1075728D02*
Y1074153D01*
G01Y1080728D02*
Y1079153D01*
G01Y1085728D02*
Y1084153D01*
G01Y1090728D02*
Y1089153D01*
G01Y1095728D02*
Y1094153D01*
G01Y1100728D02*
Y1099153D01*
G01Y1105728D02*
Y1104153D01*
G01Y1110728D02*
Y1109153D01*
G01Y1115728D02*
Y1114153D01*
G01Y1120728D02*
Y1119153D01*
G01Y1125728D02*
Y1124153D01*
G01Y1130728D02*
Y1129153D01*
G01Y1135728D02*
Y1134153D01*
G01Y1140728D02*
Y1139153D01*
G01X923114Y1070728D02*
Y1069153D01*
G01X923032Y1139055D02*
Y1140826D01*
G01Y1134055D02*
Y1135826D01*
G01Y1129055D02*
Y1130826D01*
G01Y1124055D02*
Y1125826D01*
G01Y1119055D02*
Y1120826D01*
G01Y1114055D02*
Y1115826D01*
G01Y1109055D02*
Y1110826D01*
G01Y1104055D02*
Y1105826D01*
G01Y1099055D02*
Y1100826D01*
G01Y1094055D02*
Y1095826D01*
G01Y1089055D02*
Y1090826D01*
G01Y1084055D02*
Y1085826D01*
G01Y1079055D02*
Y1080826D01*
G01Y1074055D02*
Y1075826D01*
G01Y1069055D02*
Y1070826D01*
G01X924016Y1067204D02*
X925984Y1069173D01*
G01Y1067578D02*
X925787D01*
G01Y1066200D02*
X925984D01*
G01Y1064429D02*
X925787D01*
G01Y1063051D02*
X925984D01*
G01Y1061279D02*
X925787D01*
G01X925984Y1146712D02*
X924016Y1148681D01*
G01X927953Y1157027D02*
X932677Y1152382D01*
G01Y1151278D02*
X927957Y1155920D01*
G01X932677Y1150649D02*
Y1152382D01*
G01X927953Y1155846D02*
Y1148681D01*
G01X924803Y1143759D02*
X925984Y1144941D01*
G01Y1148681D02*
X929268D01*
G01D02*
X932677Y1150649D01*
G01X990736Y1436748D02*
X990988Y1436830D01*
G01Y1436337D02*
X990736Y1436256D01*
G01X991323Y1436583D02*
X990988Y1436337D01*
G01Y1436830D02*
X991155Y1436994D01*
G01X991574Y1436911D02*
X991323Y1436583D01*
G01X991155Y1436994D02*
X991239Y1437240D01*
G01X991658Y1437322D02*
X991574Y1436911D01*
G01X991658Y1434615D02*
X987721D01*
G01Y1435107D02*
X990988D01*
G01X990401Y1435599D02*
X991071D01*
G01X992716Y1436181D02*
X993897D01*
G01X990736Y1436256D02*
X990401D01*
G01X990485Y1436748D02*
X990736D01*
G01X993897Y1438465D02*
X992716D01*
G01X991239Y1438798D02*
X989982D01*
G01X989480D02*
X987721D01*
G01Y1439290D02*
X991658D01*
G01X992716Y1446181D02*
X993897D01*
G01Y1448465D02*
X992716D01*
G01X987721Y1434615D02*
Y1435107D01*
G01Y1438798D02*
Y1439290D01*
G01X989480Y1437322D02*
Y1438798D01*
G01X989982D02*
Y1437240D01*
G01X991239D02*
Y1438798D01*
G01X991658Y1439290D02*
Y1437322D01*
G01Y1435107D02*
Y1434615D01*
G01X992716Y1448465D02*
Y1446181D01*
G01Y1438465D02*
Y1436181D01*
G01X990401Y1436256D02*
X990150Y1436337D01*
G01X990234Y1436830D02*
X990485Y1436748D01*
G01X989982Y1437240D02*
X990066Y1436994D01*
G01X989564Y1436911D02*
X989480Y1437322D01*
G01X990150Y1436337D02*
X989815Y1436583D01*
G01X990988Y1435107D02*
X990401Y1435599D01*
G01X991071D02*
X991658Y1435107D01*
G01X990066Y1436994D02*
X990234Y1436830D01*
G01X989815Y1436583D02*
X989564Y1436911D01*
G01X992716Y1456181D02*
X993897D01*
G01Y1458465D02*
X992716D01*
G01Y1468465D02*
Y1466181D01*
G01Y1458465D02*
Y1456181D01*
G01Y1466181D02*
X993897D01*
G01Y1468465D02*
X992716D01*
G01X1004487Y1428819D02*
Y1403228D01*
G01D02*
G03X1006456Y1401260I1969J1D01*
G01Y1430787D02*
G03X1004487Y1428819I-1J-1968D01*
G01X993568Y1435197D02*
X1019290D01*
G01Y1439449D02*
X993568D01*
G01Y1445197D02*
X1019290D01*
G01Y1449449D02*
X993568D01*
G01X993897Y1448465D02*
Y1446181D01*
G01Y1438465D02*
Y1436181D01*
G01X998424Y1449449D02*
Y1445197D01*
G01Y1439449D02*
Y1435197D01*
G01X999605D02*
Y1439449D01*
G01Y1445197D02*
Y1449449D01*
G01X1000795D02*
Y1445197D01*
G01Y1439449D02*
Y1435197D01*
G01X1001398Y1449449D02*
Y1445197D01*
G01Y1439449D02*
Y1435197D01*
G01X993568Y1455197D02*
X1019290D01*
G01Y1459449D02*
X993568D01*
G01X993897Y1468465D02*
Y1466181D01*
G01Y1458465D02*
Y1456181D01*
G01X998424Y1469449D02*
Y1465197D01*
G01Y1459449D02*
Y1455197D01*
G01X999605D02*
Y1459449D01*
G01Y1465197D02*
Y1469449D01*
G01X1000795D02*
Y1465197D01*
G01Y1459449D02*
Y1455197D01*
G01X1001398Y1469449D02*
Y1465197D01*
G01Y1459449D02*
Y1455197D01*
G01X993568Y1465197D02*
X1019290D01*
G01Y1469449D02*
X993568D01*
G01X925984Y1451220D02*
X924016Y1453189D01*
G01X924803Y1416633D02*
X925984Y1415452D01*
G01X932677Y1409744D02*
X929268Y1411712D01*
G01X925984Y1473090D02*
X925787D01*
G01Y1471712D02*
X925984D01*
G01Y1469941D02*
X925787D01*
G01Y1468563D02*
X925984D01*
G01Y1466791D02*
X925787D01*
G01Y1465413D02*
X925984D01*
G01Y1463641D02*
X925787D01*
G01Y1462263D02*
X925984D01*
G01Y1460492D02*
X925787D01*
G01Y1459114D02*
X925984D01*
G01Y1457342D02*
X925787D01*
G01Y1455964D02*
X925984D01*
G01Y1454193D02*
X925787D01*
G01Y1452815D02*
X925984D01*
G01Y1411712D02*
X929268D01*
G01X936614Y1399429D02*
Y1566476D01*
G01X932677Y1408011D02*
Y1409744D01*
G01X927953Y1411712D02*
Y1404547D01*
G01X925984Y1411712D02*
Y1554193D01*
G01X925787Y1471712D02*
Y1473090D01*
G01Y1454193D02*
Y1452815D01*
G01Y1460492D02*
Y1459114D01*
G01Y1457342D02*
Y1455964D01*
G01Y1463641D02*
Y1462263D01*
G01Y1469941D02*
Y1468563D01*
G01Y1466791D02*
Y1465413D01*
G01X924803Y1416633D02*
Y1549271D01*
G01X924223Y1444665D02*
Y1446240D01*
G01Y1439665D02*
Y1441240D01*
G01Y1434665D02*
Y1436240D01*
G01Y1429665D02*
Y1431240D01*
G01Y1424665D02*
Y1426240D01*
G01Y1419665D02*
Y1421240D01*
G01X924102Y1449665D02*
Y1451240D01*
G01X924016Y1475157D02*
Y1450748D01*
G01X923541Y1421240D02*
Y1419665D01*
G01Y1426240D02*
Y1424665D01*
G01Y1431240D02*
Y1429665D01*
G01Y1436240D02*
Y1434665D01*
G01Y1441240D02*
Y1439665D01*
G01Y1446240D02*
Y1444665D01*
G01X923114Y1451240D02*
Y1449665D01*
G01X923032Y1449567D02*
Y1451338D01*
G01Y1444567D02*
Y1446338D01*
G01Y1439567D02*
Y1441338D01*
G01Y1434567D02*
Y1436338D01*
G01Y1429567D02*
Y1431338D01*
G01Y1424567D02*
Y1426338D01*
G01Y1419567D02*
Y1421338D01*
G01X932677Y1408011D02*
X927953Y1403366D01*
G01X927957Y1404473D02*
X932677Y1409115D01*
G01X924016Y1411712D02*
X925984Y1413681D01*
G01X924016Y1472716D02*
X925984Y1474685D01*
G01X992716Y1488465D02*
Y1486181D01*
G01Y1478465D02*
Y1476181D01*
G01D02*
X993897D01*
G01Y1478465D02*
X992716D01*
G01Y1486181D02*
X993897D01*
G01Y1488465D02*
X992716D01*
G01Y1508465D02*
Y1506181D01*
G01Y1498465D02*
Y1496181D01*
G01D02*
X993897D01*
G01Y1498465D02*
X992716D01*
G01Y1506181D02*
X993897D01*
G01Y1508465D02*
X992716D01*
G01Y1528465D02*
Y1526181D01*
G01Y1518465D02*
Y1516181D01*
G01D02*
X993897D01*
G01Y1518465D02*
X992716D01*
G01Y1526181D02*
X993897D01*
G01Y1528465D02*
X992716D01*
G01Y1548465D02*
Y1546181D01*
G01Y1538465D02*
Y1536181D01*
G01D02*
X993897D01*
G01Y1538465D02*
X992716D01*
G01Y1546181D02*
X993897D01*
G01Y1548465D02*
X992716D01*
G01Y1558465D02*
Y1556181D01*
G01D02*
X993897D01*
G01Y1488465D02*
Y1486181D01*
G01Y1478465D02*
Y1476181D01*
G01X998424Y1489449D02*
Y1485197D01*
G01Y1479449D02*
Y1475197D01*
G01X999605D02*
Y1479449D01*
G01Y1485197D02*
Y1489449D01*
G01X1000795D02*
Y1485197D01*
G01Y1479449D02*
Y1475197D01*
G01X1001398Y1489449D02*
Y1485197D01*
G01Y1479449D02*
Y1475197D01*
G01X993568D02*
X1019290D01*
G01Y1479449D02*
X993568D01*
G01Y1485197D02*
X1019290D01*
G01Y1489449D02*
X993568D01*
G01X993897Y1508465D02*
Y1506181D01*
G01Y1498465D02*
Y1496181D01*
G01X998424Y1509449D02*
Y1505197D01*
G01Y1499449D02*
Y1495197D01*
G01X999605D02*
Y1499449D01*
G01Y1505197D02*
Y1509449D01*
G01X1000795D02*
Y1505197D01*
G01Y1499449D02*
Y1495197D01*
G01X1001398Y1509449D02*
Y1505197D01*
G01Y1499449D02*
Y1495197D01*
G01X993568D02*
X1019290D01*
G01Y1499449D02*
X993568D01*
G01Y1505197D02*
X1019290D01*
G01Y1509449D02*
X993568D01*
G01X993897Y1528465D02*
Y1526181D01*
G01Y1518465D02*
Y1516181D01*
G01X998424Y1529449D02*
Y1525197D01*
G01Y1519449D02*
Y1515197D01*
G01X999605D02*
Y1519449D01*
G01Y1525197D02*
Y1529449D01*
G01X1000795D02*
Y1525197D01*
G01Y1519449D02*
Y1515197D01*
G01X1001398Y1529449D02*
Y1525197D01*
G01Y1519449D02*
Y1515197D01*
G01X993568D02*
X1019290D01*
G01Y1519449D02*
X993568D01*
G01Y1525197D02*
X1019290D01*
G01Y1529449D02*
X993568D01*
G01X993897Y1548465D02*
Y1546181D01*
G01Y1538465D02*
Y1536181D01*
G01X998424Y1549449D02*
Y1545197D01*
G01Y1539449D02*
Y1535197D01*
G01X999605D02*
Y1539449D01*
G01Y1545197D02*
Y1549449D01*
G01X1000795D02*
Y1545197D01*
G01Y1539449D02*
Y1535197D01*
G01X1001398Y1549449D02*
Y1545197D01*
G01Y1539449D02*
Y1535197D01*
G01X993568D02*
X1019290D01*
G01Y1539449D02*
X993568D01*
G01Y1545197D02*
X1019290D01*
G01Y1549449D02*
X993568D01*
G01X993897Y1558465D02*
Y1556181D01*
G01X998424Y1559449D02*
Y1555197D01*
G01X999605D02*
Y1559449D01*
G01X1000795D02*
Y1555197D01*
G01X1001398Y1559449D02*
Y1555197D01*
G01X993568D02*
X1019290D01*
G01X925984Y1552224D02*
X924016Y1554193D01*
G01X925984D02*
X929268D01*
G01X932677Y1556161D02*
Y1557893D01*
G01X927953Y1561358D02*
Y1554193D01*
G01X924223Y1544665D02*
Y1546240D01*
G01Y1539665D02*
Y1541240D01*
G01Y1534665D02*
Y1536240D01*
G01Y1529665D02*
Y1531240D01*
G01Y1524665D02*
Y1526240D01*
G01Y1519665D02*
Y1521240D01*
G01Y1514665D02*
Y1516240D01*
G01Y1509665D02*
Y1511240D01*
G01Y1504665D02*
Y1506240D01*
G01Y1499665D02*
Y1501240D01*
G01Y1494665D02*
Y1496240D01*
G01Y1489665D02*
Y1491240D01*
G01Y1484665D02*
Y1486240D01*
G01Y1479665D02*
Y1481240D01*
G01X924102Y1474665D02*
Y1476240D01*
G01X923541Y1481240D02*
Y1479665D01*
G01Y1486240D02*
Y1484665D01*
G01Y1491240D02*
Y1489665D01*
G01Y1496240D02*
Y1494665D01*
G01Y1501240D02*
Y1499665D01*
G01Y1506240D02*
Y1504665D01*
G01Y1511240D02*
Y1509665D01*
G01Y1516240D02*
Y1514665D01*
G01Y1521240D02*
Y1519665D01*
G01Y1526240D02*
Y1524665D01*
G01Y1531240D02*
Y1529665D01*
G01Y1536240D02*
Y1534665D01*
G01Y1541240D02*
Y1539665D01*
G01Y1546240D02*
Y1544665D01*
G01X923114Y1476240D02*
Y1474665D01*
G01X923032Y1544567D02*
Y1546338D01*
G01Y1539567D02*
Y1541338D01*
G01Y1534567D02*
Y1536338D01*
G01Y1529567D02*
Y1531338D01*
G01Y1524567D02*
Y1526338D01*
G01Y1519567D02*
Y1521338D01*
G01Y1514567D02*
Y1516338D01*
G01Y1509567D02*
Y1511338D01*
G01Y1504567D02*
Y1506338D01*
G01Y1499567D02*
Y1501338D01*
G01Y1494567D02*
Y1496338D01*
G01Y1489567D02*
Y1491338D01*
G01Y1484567D02*
Y1486338D01*
G01Y1479567D02*
Y1481338D01*
G01Y1474567D02*
Y1476338D01*
G01X924803Y1549271D02*
X925984Y1550452D01*
G01X929268Y1554193D02*
X932677Y1556161D01*
G01X992716Y1568465D02*
Y1566181D01*
G01X993897Y1558465D02*
X992716D01*
G01Y1566181D02*
X993897D01*
G01Y1568465D02*
X992716D01*
G01Y1588465D02*
Y1586181D01*
G01Y1578465D02*
Y1576181D01*
G01D02*
X993897D01*
G01Y1578465D02*
X992716D01*
G01Y1586181D02*
X993897D01*
G01Y1588465D02*
X992716D01*
G01X991731Y1617756D02*
Y1610197D01*
G01X992716Y1608465D02*
Y1606181D01*
G01Y1598465D02*
Y1596181D01*
G01Y1610197D02*
Y1615394D01*
G01Y1596181D02*
X993897D01*
G01Y1598465D02*
X992716D01*
G01Y1606181D02*
X993897D01*
G01Y1608465D02*
X992716D01*
G01X991731Y1610197D02*
X1015353D01*
G01X991731Y1614803D02*
X992716Y1615787D01*
G01X992952Y1631890D02*
Y1630315D01*
G01Y1626890D02*
Y1625315D01*
G01Y1621890D02*
Y1620315D01*
G01X991731Y1611358D02*
X1039920D01*
G01X991731Y1611870D02*
X1015353D01*
G01X989743D02*
X991731D01*
G01X992716Y1612165D02*
X1019290D01*
G01X991731Y1615394D02*
X1029527D01*
G01X1019290Y1615787D02*
X992716D01*
G01X1015353Y1616083D02*
X991731D01*
G01D02*
X989743D01*
G01X1029527Y1617756D02*
X991731D01*
G01X992952Y1620315D02*
X999015D01*
G01X992952Y1621890D02*
X999015D01*
G01X992952Y1625315D02*
X999015D01*
G01Y1626890D02*
X992952D01*
G01Y1630315D02*
X999015D01*
G01X991731Y1613150D02*
X992716Y1612165D01*
G01X989743Y1616083D02*
G03Y1611870I0J-2107D01*
G01X992952Y1636890D02*
Y1635315D01*
G01X999015Y1631890D02*
X992952D01*
G01Y1635315D02*
X999015D01*
G01Y1636890D02*
X992952D01*
G01X993897Y1568465D02*
Y1566181D01*
G01X998424Y1569449D02*
Y1565197D01*
G01X999605D02*
Y1569449D01*
G01X1000795D02*
Y1565197D01*
G01X1001398Y1569449D02*
Y1565197D01*
G01X1019290Y1559449D02*
X993568D01*
G01Y1565197D02*
X1019290D01*
G01Y1569449D02*
X993568D01*
G01X993897Y1588465D02*
Y1586181D01*
G01Y1578465D02*
Y1576181D01*
G01X998424Y1589449D02*
Y1585197D01*
G01Y1579449D02*
Y1575197D01*
G01X999605D02*
Y1579449D01*
G01Y1585197D02*
Y1589449D01*
G01X1000795D02*
Y1585197D01*
G01Y1579449D02*
Y1575197D01*
G01X1001398Y1589449D02*
Y1585197D01*
G01Y1579449D02*
Y1575197D01*
G01X993568D02*
X1019290D01*
G01Y1579449D02*
X993568D01*
G01Y1585197D02*
X1019290D01*
G01Y1589449D02*
X993568D01*
G01X993897Y1608465D02*
Y1606181D01*
G01Y1598465D02*
Y1596181D01*
G01X998424Y1609449D02*
Y1605197D01*
G01Y1599449D02*
Y1595197D01*
G01X999605D02*
Y1599449D01*
G01Y1605197D02*
Y1609449D01*
G01X1000795D02*
Y1605197D01*
G01Y1599449D02*
Y1595197D01*
G01X1001398Y1609449D02*
Y1605197D01*
G01Y1599449D02*
Y1595197D01*
G01X993568D02*
X1019290D01*
G01Y1599449D02*
X993568D01*
G01Y1605197D02*
X1019290D01*
G01X1017610Y1609449D02*
X993568D01*
G01X1003901Y1626890D02*
X1004094Y1627087D01*
G01X1004338D02*
X1004145Y1626890D01*
G01X1003901Y1621890D02*
X1004094Y1622087D01*
G01X1004338D02*
X1004145Y1621890D01*
G01X993542Y1620315D02*
Y1621890D01*
G01Y1625315D02*
Y1626890D01*
G01Y1630315D02*
Y1631890D01*
G01X995241Y1611358D02*
Y1610965D01*
G01X995668Y1612165D02*
Y1610965D01*
G01Y1617756D02*
Y1615787D01*
G01X998424Y1631890D02*
Y1630315D01*
G01Y1626890D02*
Y1625315D01*
G01Y1621890D02*
Y1620315D01*
G01X999015Y1631890D02*
Y1630315D01*
G01Y1626890D02*
Y1625315D01*
G01Y1621890D02*
Y1620315D01*
G01X1000961Y1631890D02*
Y1630315D01*
G01Y1626890D02*
Y1625315D01*
G01Y1621890D02*
Y1620315D01*
G01X1001205Y1631890D02*
Y1630315D01*
G01Y1626890D02*
Y1625315D01*
G01Y1621890D02*
Y1620315D01*
G01X995241Y1610965D02*
X1072854D01*
G01X1004094Y1620118D02*
X1029527D01*
G01X999015Y1620315D02*
X1004145D01*
G01Y1621890D02*
X999015D01*
G01X1004094Y1622087D02*
X1029527D01*
G01X1004094Y1625118D02*
X1029527D01*
G01X999015Y1625315D02*
X1000961D01*
G01D02*
X1003901D01*
G01D02*
X1004145D01*
G01Y1626890D02*
X999015D01*
G01X1029527Y1627087D02*
X1004094D01*
G01Y1630118D02*
X1029527D01*
G01X999015Y1630315D02*
X1000961D01*
G01D02*
X1003901D01*
G01D02*
X1004145D01*
G01X1004094Y1620118D02*
X1003901Y1620315D01*
G01X1004145D02*
X1004338Y1620118D01*
G01X1004094Y1625118D02*
X1003901Y1625315D01*
G01X1004145D02*
X1004338Y1625118D01*
G01X1004094Y1630118D02*
X1003901Y1630315D01*
G01X1004145D02*
X1004338Y1630118D01*
G01X1003901Y1636890D02*
X1004094Y1637087D01*
G01X1004338D02*
X1004145Y1636890D01*
G01X1003901Y1631890D02*
X1004094Y1632087D01*
G01X1004338D02*
X1004145Y1631890D01*
G01X993542Y1635315D02*
Y1636890D01*
G01X998424D02*
Y1635315D01*
G01X999015Y1636890D02*
Y1635315D01*
G01X1000961Y1636890D02*
Y1635315D01*
G01X1001205Y1636890D02*
Y1635315D01*
G01X1004145Y1631890D02*
X999015D01*
G01X1029527Y1632087D02*
X1004094D01*
G01Y1635118D02*
X1029527D01*
G01X999015Y1635315D02*
X1000961D01*
G01D02*
X1003901D01*
G01D02*
X1004145D01*
G01Y1636890D02*
X999015D01*
G01X1029527Y1637087D02*
X1004094D01*
G01Y1635118D02*
X1003901Y1635315D01*
G01X1004145D02*
X1004338Y1635118D01*
G01X927953Y1562539D02*
X932677Y1557893D01*
G01Y1556790D02*
X927957Y1561432D01*
G01X992952Y1651890D02*
Y1650315D01*
G01Y1646890D02*
Y1645315D01*
G01Y1641890D02*
Y1640315D01*
G01D02*
X999015D01*
G01Y1641890D02*
X992952D01*
G01Y1645315D02*
X999015D01*
G01X992952Y1646890D02*
X999015D01*
G01X992952Y1650315D02*
X999015D01*
G01X992952Y1671890D02*
Y1670315D01*
G01Y1666890D02*
Y1665315D01*
G01Y1661890D02*
Y1660315D01*
G01Y1656890D02*
Y1655315D01*
G01X999015Y1651890D02*
X992952D01*
G01Y1655315D02*
X999015D01*
G01X992952Y1656890D02*
X999015D01*
G01X992952Y1660315D02*
X999015D01*
G01Y1661890D02*
X992952D01*
G01Y1665315D02*
X999015D01*
G01X992952Y1666890D02*
X999015D01*
G01X992952Y1670315D02*
X999015D01*
G01X992952Y1676890D02*
Y1675315D01*
G01X999015Y1671890D02*
X992952D01*
G01Y1675315D02*
X999015D01*
G01X992952Y1676890D02*
X999015D01*
G01X1003901Y1646890D02*
X1004094Y1647087D01*
G01X1004338D02*
X1004145Y1646890D01*
G01X1003901Y1641890D02*
X1004094Y1642087D01*
G01X1004338D02*
X1004145Y1641890D01*
G01X993542Y1640315D02*
Y1641890D01*
G01Y1645315D02*
Y1646890D01*
G01Y1650315D02*
Y1651890D01*
G01X998424D02*
Y1650315D01*
G01Y1646890D02*
Y1645315D01*
G01Y1641890D02*
Y1640315D01*
G01X999015Y1651890D02*
Y1650315D01*
G01Y1646890D02*
Y1645315D01*
G01Y1641890D02*
Y1640315D01*
G01X1000961Y1651890D02*
Y1650315D01*
G01Y1646890D02*
Y1645315D01*
G01Y1641890D02*
Y1640315D01*
G01X1001205Y1651890D02*
Y1650315D01*
G01Y1646890D02*
Y1645315D01*
G01Y1641890D02*
Y1640315D01*
G01X1004094Y1640118D02*
X1029527D01*
G01X999015Y1640315D02*
X1000961D01*
G01D02*
X1003901D01*
G01D02*
X1004145D01*
G01Y1641890D02*
X999015D01*
G01X1029527Y1642087D02*
X1004094D01*
G01Y1645118D02*
X1029527D01*
G01X999015Y1645315D02*
X1004145D01*
G01Y1646890D02*
X999015D01*
G01X1004094Y1647087D02*
X1029527D01*
G01X1004094Y1650118D02*
X1029527D01*
G01X999015Y1650315D02*
X1000961D01*
G01D02*
X1003901D01*
G01D02*
X1004145D01*
G01X1004094Y1640118D02*
X1003901Y1640315D01*
G01X1004145D02*
X1004338Y1640118D01*
G01X1004094Y1645118D02*
X1003901Y1645315D01*
G01X1004145D02*
X1004338Y1645118D01*
G01X1004094Y1650118D02*
X1003901Y1650315D01*
G01X1004145D02*
X1004338Y1650118D01*
G01X1003901Y1666890D02*
X1004094Y1667087D01*
G01X1004338D02*
X1004145Y1666890D01*
G01X1003901Y1661890D02*
X1004094Y1662087D01*
G01X1004338D02*
X1004145Y1661890D01*
G01X1003901Y1656890D02*
X1004094Y1657087D01*
G01X1004338D02*
X1004145Y1656890D01*
G01X1003901Y1651890D02*
X1004094Y1652087D01*
G01X1004338D02*
X1004145Y1651890D01*
G01X993542Y1655315D02*
Y1656890D01*
G01Y1660315D02*
Y1661890D01*
G01Y1665315D02*
Y1666890D01*
G01Y1670315D02*
Y1671890D01*
G01X998424D02*
Y1670315D01*
G01Y1666890D02*
Y1665315D01*
G01Y1661890D02*
Y1660315D01*
G01Y1656890D02*
Y1655315D01*
G01X999015Y1671890D02*
Y1670315D01*
G01Y1666890D02*
Y1665315D01*
G01Y1661890D02*
Y1660315D01*
G01Y1656890D02*
Y1655315D01*
G01X1000961Y1671890D02*
Y1670315D01*
G01Y1666890D02*
Y1665315D01*
G01Y1661890D02*
Y1660315D01*
G01Y1656890D02*
Y1655315D01*
G01X1001205Y1671890D02*
Y1670315D01*
G01Y1666890D02*
Y1665315D01*
G01Y1661890D02*
Y1660315D01*
G01Y1656890D02*
Y1655315D01*
G01X1004145Y1651890D02*
X999015D01*
G01X1029527Y1652087D02*
X1004094D01*
G01Y1655118D02*
X1029527D01*
G01X999015Y1655315D02*
X1004145D01*
G01Y1656890D02*
X999015D01*
G01X1004094Y1657087D02*
X1029527D01*
G01X1004094Y1660118D02*
X1029527D01*
G01X999015Y1660315D02*
X1000961D01*
G01D02*
X1003901D01*
G01D02*
X1004145D01*
G01Y1661890D02*
X999015D01*
G01X1029527Y1662087D02*
X1004094D01*
G01Y1665118D02*
X1029527D01*
G01X999015Y1665315D02*
X1004145D01*
G01Y1666890D02*
X999015D01*
G01X1004094Y1667087D02*
X1029527D01*
G01X1004094Y1670118D02*
X1029527D01*
G01X999015Y1670315D02*
X1000961D01*
G01D02*
X1003901D01*
G01D02*
X1004145D01*
G01X1004094Y1655118D02*
X1003901Y1655315D01*
G01X1004145D02*
X1004338Y1655118D01*
G01X1004094Y1660118D02*
X1003901Y1660315D01*
G01X1004145D02*
X1004338Y1660118D01*
G01X1004094Y1665118D02*
X1003901Y1665315D01*
G01X1004145D02*
X1004338Y1665118D01*
G01X1004094Y1670118D02*
X1003901Y1670315D01*
G01X1004145D02*
X1004338Y1670118D01*
G01X1003901Y1676890D02*
X1004094Y1677087D01*
G01X1004338D02*
X1004145Y1676890D01*
G01X1003901Y1671890D02*
X1004094Y1672087D01*
G01X1004338D02*
X1004145Y1671890D01*
G01X993542Y1675315D02*
Y1676890D01*
G01X998424D02*
Y1675315D01*
G01X999015Y1676890D02*
Y1675315D01*
G01X1000961Y1676890D02*
Y1675315D01*
G01X1001205Y1676890D02*
Y1675315D01*
G01X1004487Y1707008D02*
Y1681417D01*
G01X1004145Y1671890D02*
X999015D01*
G01X1029527Y1672087D02*
X1004094D01*
G01Y1675118D02*
X1029527D01*
G01X999015Y1675315D02*
X1004145D01*
G01Y1676890D02*
X999015D01*
G01X1004094Y1677087D02*
X1029527D01*
G01X1004487Y1681811D02*
X1029527D01*
G01X1004094Y1675118D02*
X1003901Y1675315D01*
G01X1004145D02*
X1004338Y1675118D01*
G01X1004487Y1681417D02*
G03X1006456Y1679449I1969J1D01*
G01Y1708976D02*
G03X1004487Y1707008I-1J-1968D01*
G01X936614Y1804941D02*
Y1971988D01*
G01X1009842Y1889764D02*
G03I-15748J0D01*
G01X1001968D02*
G03I-7874J0D01*
G01X925984Y1856732D02*
X924016Y1858700D01*
G01X924803Y1822145D02*
X925984Y1820964D01*
G01X932677Y1815256D02*
X929268Y1817224D01*
G01X925984Y1878602D02*
X925787D01*
G01Y1877224D02*
X925984D01*
G01Y1875452D02*
X925787D01*
G01Y1874074D02*
X925984D01*
G01Y1872303D02*
X925787D01*
G01Y1870925D02*
X925984D01*
G01Y1869153D02*
X925787D01*
G01Y1867775D02*
X925984D01*
G01Y1866004D02*
X925787D01*
G01Y1864626D02*
X925984D01*
G01Y1862854D02*
X925787D01*
G01Y1861476D02*
X925984D01*
G01Y1859704D02*
X925787D01*
G01Y1858326D02*
X925984D01*
G01Y1817224D02*
X929268D01*
G01X932677Y1813523D02*
Y1815256D01*
G01X927953Y1817224D02*
Y1810059D01*
G01X925984Y1817224D02*
Y1959704D01*
G01X925787Y1877224D02*
Y1878602D01*
G01Y1859704D02*
Y1858326D01*
G01Y1862854D02*
Y1861476D01*
G01Y1866004D02*
Y1864626D01*
G01Y1872303D02*
Y1870925D01*
G01Y1869153D02*
Y1867775D01*
G01Y1875452D02*
Y1874074D01*
G01X924803Y1822145D02*
Y1954783D01*
G01X924223Y1885177D02*
Y1886752D01*
G01Y1850177D02*
Y1851752D01*
G01Y1845177D02*
Y1846752D01*
G01Y1840177D02*
Y1841752D01*
G01Y1835177D02*
Y1836752D01*
G01Y1830177D02*
Y1831752D01*
G01Y1825177D02*
Y1826752D01*
G01X924102Y1880177D02*
Y1881752D01*
G01Y1855177D02*
Y1856752D01*
G01X924016Y1880669D02*
Y1856259D01*
G01X923541Y1826752D02*
Y1825177D01*
G01Y1831752D02*
Y1830177D01*
G01Y1836752D02*
Y1835177D01*
G01Y1841752D02*
Y1840177D01*
G01Y1846752D02*
Y1845177D01*
G01Y1851752D02*
Y1850177D01*
G01Y1886752D02*
Y1885177D01*
G01X923114Y1856752D02*
Y1855177D01*
G01Y1881752D02*
Y1880177D01*
G01X923032Y1885078D02*
Y1886850D01*
G01Y1880078D02*
Y1881850D01*
G01Y1855078D02*
Y1856850D01*
G01Y1850078D02*
Y1851850D01*
G01Y1845078D02*
Y1846850D01*
G01Y1840078D02*
Y1841850D01*
G01Y1835078D02*
Y1836850D01*
G01Y1830078D02*
Y1831850D01*
G01Y1825078D02*
Y1826850D01*
G01X932677Y1813523D02*
X927953Y1808878D01*
G01X927957Y1809985D02*
X932677Y1814627D01*
G01X924016Y1817224D02*
X925984Y1819193D01*
G01X924016Y1878228D02*
X925984Y1880196D01*
G01Y1957736D02*
X924016Y1959704D01*
G01X927953Y1968051D02*
X932677Y1963405D01*
G01Y1962302D02*
X927957Y1966943D01*
G01X925984Y1959704D02*
X929268D01*
G01X932677Y1961673D02*
Y1963405D01*
G01X927953Y1966870D02*
Y1959704D01*
G01X924223Y1950177D02*
Y1951752D01*
G01Y1945177D02*
Y1946752D01*
G01Y1940177D02*
Y1941752D01*
G01Y1935177D02*
Y1936752D01*
G01Y1930177D02*
Y1931752D01*
G01Y1925177D02*
Y1926752D01*
G01Y1920177D02*
Y1921752D01*
G01Y1915177D02*
Y1916752D01*
G01Y1910177D02*
Y1911752D01*
G01Y1905177D02*
Y1906752D01*
G01Y1900177D02*
Y1901752D01*
G01Y1895177D02*
Y1896752D01*
G01Y1890177D02*
Y1891752D01*
G01X923541D02*
Y1890177D01*
G01Y1896752D02*
Y1895177D01*
G01Y1901752D02*
Y1900177D01*
G01Y1906752D02*
Y1905177D01*
G01Y1911752D02*
Y1910177D01*
G01Y1916752D02*
Y1915177D01*
G01Y1921752D02*
Y1920177D01*
G01Y1926752D02*
Y1925177D01*
G01Y1931752D02*
Y1930177D01*
G01Y1936752D02*
Y1935177D01*
G01Y1941752D02*
Y1940177D01*
G01Y1946752D02*
Y1945177D01*
G01Y1951752D02*
Y1950177D01*
G01X923032Y1950078D02*
Y1951850D01*
G01Y1945078D02*
Y1946850D01*
G01Y1940078D02*
Y1941850D01*
G01Y1935078D02*
Y1936850D01*
G01Y1930078D02*
Y1931850D01*
G01Y1925078D02*
Y1926850D01*
G01Y1920078D02*
Y1921850D01*
G01Y1915078D02*
Y1916850D01*
G01Y1910078D02*
Y1911850D01*
G01Y1905078D02*
Y1906850D01*
G01Y1900078D02*
Y1901850D01*
G01Y1895078D02*
Y1896850D01*
G01Y1890078D02*
Y1891850D01*
G01X924803Y1954783D02*
X925984Y1955964D01*
G01X929268Y1959704D02*
X932677Y1961673D01*
G01X986945Y2138820D02*
Y2119883D01*
G01X1076224Y32075D02*
G03I-4292J0D01*
G01X1065334Y58022D02*
Y42022D01*
G01D02*
X1081334D01*
G01X1070834Y50022D02*
X1075834D01*
G01X1073334Y52522D02*
Y47522D01*
G01X1075834Y52522D02*
Y47522D01*
G01X1070834D02*
Y52522D01*
G01X1075834D02*
X1070834D01*
G01Y47522D02*
X1075834D01*
G01X1065334Y58022D02*
X1081334D01*
G01Y42022D02*
Y58022D01*
G01X1029527Y0D02*
G03X1033464Y3937I0J3937D01*
G01Y1424882D02*
Y3937D01*
G01X1041337Y24677D02*
Y0D01*
G01Y217343D02*
Y48297D01*
G01Y0D02*
X1097204D01*
G01X1033463Y48297D02*
G03X1041337I3937J0D01*
G01Y24677D02*
G03X1033463I-3937J0D01*
G01Y48297D02*
G03X1041337I3937J0D01*
G01Y24677D02*
G03X1033463I-3937J0D01*
G01X1041337Y217343D02*
G03X1033463I-3937J0D01*
G01X1041337D02*
G03X1033463I-3937J0D01*
G01X1041337Y445039D02*
Y240963D01*
G01X1033463D02*
G03X1041337I3937J0D01*
G01X1033463D02*
G03X1041337I3937J0D01*
G01Y697474D02*
Y468601D01*
G01X1033463Y468659D02*
G03X1041337I3937J0D01*
G01Y445039D02*
G03X1033463I-3937J0D01*
G01Y468659D02*
G03X1041337I3937J0D01*
G01Y445039D02*
G03X1033463I-3937J0D01*
G01X1041337Y996851D02*
Y721093D01*
G01X1033463D02*
G03X1041337I3937J0D01*
G01Y697474D02*
G03X1033463I-3937J-1D01*
G01Y721093D02*
G03X1041337I3937J0D01*
G01Y697474D02*
G03X1033463I-3937J-1D01*
G01X1041337Y1344059D02*
Y1020472D01*
G01X1033463D02*
G03X1041337I3937J0D01*
G01Y996851D02*
G03X1033463I-3937J1D01*
G01Y1020472D02*
G03X1041337I3937J0D01*
G01Y996851D02*
G03X1033463I-3937J1D01*
G01X1079105Y1348052D02*
G03I-4292J0D01*
G01X1041337Y1367679D02*
Y1393701D01*
G01X1033463Y1367679D02*
G03X1041337I3937J0D01*
G01Y1344059D02*
G03X1033463I-3937J0D01*
G01Y1367679D02*
G03X1041337I3937J0D01*
G01Y1344059D02*
G03X1033463I-3937J0D01*
G01X1006456Y1401260D02*
X1032046D01*
G01X1008424D02*
Y1430787D01*
G01X1026968Y1416024D02*
G03I-7678J0D01*
G01X1026574D02*
G03I-7284J0D01*
G01X1006456Y1430787D02*
X1019290D01*
G01X1010519Y1435197D02*
Y1439449D01*
G01Y1445197D02*
Y1449449D01*
G01X1011123D02*
Y1445197D01*
G01Y1439449D02*
Y1435197D01*
G01X1011725Y1449449D02*
Y1445197D01*
G01Y1439449D02*
Y1435197D01*
G01X1010519Y1455197D02*
Y1459449D01*
G01Y1465197D02*
Y1469449D01*
G01X1011123D02*
Y1465197D01*
G01Y1459449D02*
Y1455197D01*
G01X1011725Y1469449D02*
Y1465197D01*
G01Y1459449D02*
Y1455197D01*
G01X1032046Y1401260D02*
G03X1033480Y1401880I0J1968D01*
G01D02*
G03X1034015Y1403228I-1433J1349D01*
G01X1029527Y1428819D02*
X1024212D01*
G01X1033464Y1424882D02*
X1029527Y1428819D01*
G01X1019359Y1432922D02*
G03X1024212Y1428819I4853J818D01*
G01X1019290Y1432894D02*
X1019684Y1433287D01*
G01X1035983Y1433681D02*
X1032046Y1433287D01*
G01X1034015Y1430787D02*
X1021259D01*
G01X1019684Y1433287D02*
X1039920D01*
G01X1019290Y1433681D02*
X1072854D01*
G01X1039920Y1434449D02*
X1019290D01*
G01Y1435197D02*
X1022440D01*
G01X1019290Y1437402D02*
X1035786D01*
G01X1019290Y1439370D02*
X1027164D01*
G01D02*
X1030921D01*
G01X1022440Y1439449D02*
X1019290D01*
G01Y1441161D02*
X1039920D01*
G01Y1443484D02*
X1019290D01*
G01Y1445197D02*
X1022440D01*
G01X1030921Y1445276D02*
X1027164D01*
G01X1019290D02*
X1027164D01*
G01X1035786Y1447244D02*
X1019290D01*
G01X1022440Y1449449D02*
X1019290D01*
G01X1015662Y1435197D02*
Y1439449D01*
G01Y1445197D02*
Y1449449D01*
G01X1016843D02*
Y1445197D01*
G01Y1439449D02*
Y1435197D01*
G01X1018025Y1449449D02*
Y1445197D01*
G01Y1439449D02*
Y1435197D01*
G01X1019290Y1432756D02*
Y1430787D01*
G01Y1432756D02*
Y1606260D01*
G01X1019684Y1433287D02*
Y1434449D01*
G01X1020471Y1449449D02*
Y1445197D01*
G01Y1439449D02*
Y1435197D01*
G01X1021653Y1449449D02*
Y1445197D01*
G01Y1439449D02*
Y1435197D01*
G01X1022440D02*
Y1433287D01*
G01Y1439449D02*
Y1445197D01*
G01Y1449449D02*
Y1455197D01*
G01X1023227Y1443484D02*
Y1441161D01*
G01X1025196Y1445276D02*
Y1439370D01*
G01X1027164Y1438386D02*
Y1446260D01*
G01X1027558Y1445276D02*
Y1439370D01*
G01X1028362D02*
Y1445276D01*
G01X1030117D02*
Y1439370D01*
G01X1030921D02*
Y1445276D01*
G01X1021259Y1430787D02*
X1019290Y1432756D01*
G01Y1433740D02*
G03X1019359Y1432922I4921J3D01*
G01X1027164Y1438386D02*
G03X1028149Y1437402I984J0D01*
G01Y1447244D02*
G03X1027164Y1446260I-1J-984D01*
G01X1039920Y1450197D02*
X1019290D01*
G01X1039920Y1451161D02*
X1019290D01*
G01X1039920Y1453484D02*
X1019290D01*
G01Y1454449D02*
X1039920D01*
G01X1019290Y1455197D02*
X1022440D01*
G01X1019290Y1457402D02*
X1035786D01*
G01X1019290Y1459370D02*
X1027164D01*
G01D02*
X1030921D01*
G01X1022440Y1459449D02*
X1019290D01*
G01Y1461161D02*
X1039920D01*
G01X1015662Y1455197D02*
Y1459449D01*
G01Y1465197D02*
Y1469449D01*
G01X1016843D02*
Y1465197D01*
G01Y1459449D02*
Y1455197D01*
G01X1018025Y1469449D02*
Y1465197D01*
G01Y1459449D02*
Y1455197D01*
G01X1020471Y1469449D02*
Y1465197D01*
G01Y1459449D02*
Y1455197D01*
G01X1021653Y1469449D02*
Y1465197D01*
G01Y1459449D02*
Y1455197D01*
G01X1022440Y1471358D02*
Y1469449D01*
G01Y1459449D02*
Y1465197D01*
G01X1023227Y1463484D02*
Y1461161D01*
G01Y1453484D02*
Y1451161D01*
G01X1025196Y1465276D02*
Y1459370D01*
G01X1027164Y1458386D02*
Y1466260D01*
G01X1027558Y1465276D02*
Y1459370D01*
G01X1028362Y1465276D02*
Y1459370D01*
G01X1030117Y1465276D02*
Y1459370D01*
G01X1030921D02*
Y1465276D01*
G01X1039920Y1463484D02*
X1019290D01*
G01Y1465197D02*
X1022440D01*
G01X1030921Y1465276D02*
X1027164D01*
G01X1019290D02*
X1027164D01*
G01X1035786Y1467244D02*
X1019290D01*
G01Y1469449D02*
X1022440D01*
G01X1028149Y1467244D02*
G03X1027164Y1466260I-1J-984D01*
G01Y1458386D02*
G03X1028149Y1457402I984J0D01*
G01X1019290Y1472894D02*
X1019684Y1473287D01*
G01X1035983Y1473681D02*
X1032046Y1473287D01*
G01X1019684Y1471358D02*
Y1470197D01*
G01Y1473287D02*
Y1474449D01*
G01X1022440Y1475197D02*
Y1473287D01*
G01X1039920Y1470197D02*
X1019290D01*
G01Y1470965D02*
X1072854D01*
G01X1039920Y1471358D02*
X1019684D01*
G01Y1473287D02*
X1039920D01*
G01X1019290Y1473681D02*
X1072854D01*
G01X1032046Y1471358D02*
X1035983Y1470965D01*
G01X1019290Y1471752D02*
X1019684Y1471358D01*
G01X1034015Y1403228D02*
Y1430787D01*
G01X1079290Y1421339D02*
X1034015D01*
G01Y1423307D02*
X1079290D01*
G01X1039920Y1429213D02*
X1074566D01*
G01X1039920D02*
Y1685433D01*
G01X1079290Y1433248D02*
X1039920D01*
G01Y1439370D02*
X1036771D01*
G01X1037114Y1440965D02*
X1072854D01*
G01X1037164Y1441398D02*
X1079290D01*
G01X1036677Y1441555D02*
X1036527D01*
G01X1036677Y1443091D02*
X1036527D01*
G01X1079290Y1443248D02*
X1037164D01*
G01X1037114Y1443681D02*
X1072854D01*
G01X1039920Y1445276D02*
X1036771D01*
G01X1035983Y1437441D02*
Y1433681D01*
G01Y1457441D02*
Y1447205D01*
G01Y1437441D02*
Y1447205D01*
G01X1036110Y1451161D02*
Y1443484D01*
G01Y1441161D02*
Y1433681D01*
G01X1036263Y1447103D02*
Y1437543D01*
G01D02*
Y1433681D01*
G01Y1447103D02*
Y1457543D01*
G01X1036527Y1443091D02*
Y1441555D01*
G01X1036677D02*
Y1443091D01*
G01X1036771Y1438386D02*
Y1446260D01*
G01X1040708Y1441398D02*
Y1443248D01*
G01X1035786Y1437402D02*
G03X1036771Y1438386I1J984D01*
G01Y1446260D02*
G03X1035786Y1447244I-984J0D01*
G01X1036768Y1443569D02*
G03X1036674Y1443484I349J-481D01*
G01Y1441161D02*
G03X1036768Y1441077I440J398D01*
G01X1036762Y1441250D02*
G03X1036830Y1441158I509J305D01*
G01X1036850Y1443508D02*
G03X1036762Y1443396I419J-420D01*
G01X1037114Y1443681D02*
G03X1036951Y1443658I0J-592D01*
G01X1037266Y1443681D02*
G03X1037117Y1443662I0J-592D01*
G01X1036951Y1443658D02*
G03X1036800Y1443591I161J-567D01*
G01X1037117Y1443662D02*
G03X1037039Y1443635I153J-569D01*
G01X1036800Y1443591D02*
G03X1036768Y1443569I317J-496D01*
G01X1036723Y1441328D02*
G03X1036762Y1441250I544J223D01*
G01Y1443396D02*
G03X1036723Y1443318I505J-301D01*
G01X1037164Y1443248D02*
G03X1036771Y1442854I1J-394D01*
G01Y1441791D02*
G03X1037164Y1441398I394J1D01*
G01X1037114Y1450965D02*
X1072854D01*
G01X1037164Y1451398D02*
X1079290D01*
G01X1036677Y1451555D02*
X1036527D01*
G01X1036677Y1453091D02*
X1036527D01*
G01X1079290Y1453248D02*
X1037164D01*
G01X1037114Y1453681D02*
X1072854D01*
G01X1039920Y1459370D02*
X1036771D01*
G01X1037114Y1460965D02*
X1072854D01*
G01X1037164Y1461398D02*
X1079290D01*
G01X1036677Y1461555D02*
X1036527D01*
G01X1036677Y1463091D02*
X1036527D01*
G01X1079290Y1463248D02*
X1037164D01*
G01X1035983Y1470965D02*
Y1467205D01*
G01Y1457441D02*
Y1467205D01*
G01X1036110Y1470965D02*
Y1463484D01*
G01Y1461161D02*
Y1453484D01*
G01X1036263Y1467103D02*
Y1457543D01*
G01Y1467103D02*
Y1470965D01*
G01X1036527Y1463091D02*
Y1461555D01*
G01Y1453091D02*
Y1451555D01*
G01X1036677Y1463091D02*
Y1461555D01*
G01Y1453091D02*
Y1451555D01*
G01X1036771Y1451791D02*
Y1452854D01*
G01Y1458386D02*
Y1466260D01*
G01X1040708Y1453248D02*
Y1451398D01*
G01Y1461398D02*
Y1463248D01*
G01X1037114Y1463681D02*
X1072854D01*
G01X1036771Y1465276D02*
X1039920D01*
G01X1035786Y1457402D02*
G03X1036771Y1458386I1J984D01*
G01Y1466260D02*
G03X1035786Y1467244I-984J0D01*
G01X1036800Y1453591D02*
G03X1036675Y1453484I320J-501D01*
G01X1036768Y1463569D02*
G03X1036674Y1463484I349J-481D01*
G01Y1461161D02*
G03X1036768Y1461077I440J398D01*
G01X1036762Y1461250D02*
G03X1036850Y1461137I509J305D01*
G01Y1463508D02*
G03X1036762Y1463396I419J-420D01*
G01X1037114Y1463681D02*
G03X1036951Y1463658I0J-592D01*
G01X1037114Y1453681D02*
G03X1036951Y1453658I0J-592D01*
G01X1037266Y1453681D02*
G03X1037117Y1453662I0J-592D01*
G01X1037266Y1463681D02*
G03X1037117Y1463662I0J-592D01*
G01X1036951Y1463658D02*
G03X1036800Y1463591I161J-567D01*
G01X1036951Y1453658D02*
G03X1036800Y1453591I161J-567D01*
G01X1037117Y1453662D02*
G03X1037039Y1453635I153J-569D01*
G01X1037117Y1463662D02*
G03X1037039Y1463635I153J-569D01*
G01X1036800Y1463591D02*
G03X1036768Y1463569I317J-496D01*
G01X1036723Y1461328D02*
G03X1036762Y1461250I544J223D01*
G01Y1463396D02*
G03X1036723Y1463318I505J-301D01*
G01X1037164Y1453248D02*
G03X1036771Y1452854I1J-394D01*
G01Y1451791D02*
G03X1037164Y1451398I394J1D01*
G01Y1463248D02*
G03X1036771Y1462854I1J-394D01*
G01Y1461791D02*
G03X1037164Y1461398I394J1D01*
G01X1035983Y1477441D02*
Y1473681D01*
G01X1036110Y1481161D02*
Y1473681D01*
G01X1036263Y1477543D02*
Y1473681D01*
G01X1039920Y1471398D02*
X1079290D01*
G01Y1473248D02*
X1039920D01*
G01X1071416Y1428425D02*
X1079290D01*
G01X1071416Y1686220D02*
Y1428425D01*
G01X1073779Y1434665D02*
X1073375D01*
G01X1054684Y1434862D02*
X1068464D01*
G01Y1439783D02*
X1054684D01*
G01X1073779Y1439980D02*
X1073375D01*
G01X1073779Y1444665D02*
X1073375D01*
G01X1054684Y1444862D02*
X1068464D01*
G01Y1449783D02*
X1054684D01*
G01X1053700Y1448799D02*
Y1445846D01*
G01Y1438799D02*
Y1435846D01*
G01X1066319Y1450965D02*
Y1443681D01*
G01Y1440965D02*
Y1433681D01*
G01X1066472Y1450965D02*
Y1449783D01*
G01Y1444862D02*
Y1443681D01*
G01Y1440965D02*
Y1439783D01*
G01Y1434862D02*
Y1433681D01*
G01Y1434862D02*
Y1439783D01*
G01Y1444862D02*
Y1449783D01*
G01X1067112D02*
Y1444862D01*
G01D02*
Y1443681D01*
G01Y1439783D02*
Y1434862D01*
G01D02*
Y1433681D01*
G01Y1439783D02*
Y1440965D01*
G01Y1449783D02*
Y1450965D01*
G01X1067479Y1451398D02*
Y1449783D01*
G01Y1444862D02*
Y1443248D01*
G01Y1441398D02*
Y1439783D01*
G01Y1434862D02*
Y1433248D01*
G01X1067921Y1450965D02*
Y1443681D01*
G01Y1440965D02*
Y1433681D01*
G01X1068464Y1451398D02*
Y1449783D01*
G01Y1444862D02*
Y1443248D01*
G01Y1441398D02*
Y1439783D01*
G01Y1434862D02*
Y1433248D01*
G01X1069448Y1435846D02*
Y1438799D01*
G01Y1445846D02*
Y1448799D01*
G01X1069921Y1450965D02*
Y1443681D01*
G01Y1433681D02*
Y1440965D01*
G01X1073375Y1449980D02*
Y1444665D01*
G01Y1434665D02*
Y1439980D01*
G01X1053700Y1445846D02*
G03X1054684Y1444862I984J0D01*
G01X1068464D02*
G03X1069448Y1445846I0J984D01*
G01X1053700Y1435846D02*
G03X1054684Y1434862I984J0D01*
G01X1068464D02*
G03X1069448Y1435846I0J984D01*
G01Y1438799D02*
G03X1068464Y1439783I-984J0D01*
G01X1054684D02*
G03X1053700Y1438799I0J-984D01*
G01X1069448Y1448799D02*
G03X1068464Y1449783I-984J0D01*
G01X1054684D02*
G03X1053700Y1448799I0J-984D01*
G01X1073779Y1449980D02*
X1073375D01*
G01X1073779Y1454665D02*
X1073375D01*
G01X1054684Y1454862D02*
X1068464D01*
G01Y1459783D02*
X1054684D01*
G01X1073779Y1459980D02*
X1073375D01*
G01X1053700Y1468799D02*
Y1465846D01*
G01Y1458799D02*
Y1455846D01*
G01X1073779Y1464665D02*
X1073375D01*
G01X1054684Y1464862D02*
X1068464D01*
G01Y1469783D02*
X1054684D01*
G01X1066319Y1470965D02*
Y1463681D01*
G01Y1460965D02*
Y1453681D01*
G01X1066472Y1470965D02*
Y1469783D01*
G01Y1464862D02*
Y1463681D01*
G01Y1460965D02*
Y1459783D01*
G01Y1454862D02*
Y1453681D01*
G01Y1454862D02*
Y1459783D01*
G01Y1464862D02*
Y1469783D01*
G01X1067112D02*
Y1464862D01*
G01D02*
Y1463681D01*
G01Y1459783D02*
Y1454862D01*
G01D02*
Y1453681D01*
G01Y1459783D02*
Y1460965D01*
G01Y1469783D02*
Y1470965D01*
G01X1067479Y1471398D02*
Y1469783D01*
G01Y1464862D02*
Y1463248D01*
G01Y1461398D02*
Y1459783D01*
G01Y1454862D02*
Y1453248D01*
G01X1067921Y1470965D02*
Y1463681D01*
G01Y1460965D02*
Y1453681D01*
G01X1068464Y1471398D02*
Y1469783D01*
G01Y1461398D02*
Y1459783D01*
G01Y1454862D02*
Y1453248D01*
G01Y1463248D02*
Y1464862D01*
G01X1069448Y1455846D02*
Y1458799D01*
G01Y1465846D02*
Y1468799D01*
G01X1069921Y1470965D02*
Y1463681D01*
G01Y1453681D02*
Y1460965D01*
G01X1073375Y1469980D02*
Y1464665D01*
G01Y1454665D02*
Y1459980D01*
G01X1053700Y1465846D02*
G03X1054684Y1464862I984J0D01*
G01X1068464D02*
G03X1069448Y1465846I0J984D01*
G01Y1468799D02*
G03X1068464Y1469783I-984J0D01*
G01X1054684D02*
G03X1053700Y1468799I0J-984D01*
G01Y1455846D02*
G03X1054684Y1454862I984J0D01*
G01X1068464D02*
G03X1069448Y1455846I0J984D01*
G01Y1458799D02*
G03X1068464Y1459783I-984J0D01*
G01X1054684D02*
G03X1053700Y1458799I0J-984D01*
G01X1073779Y1469980D02*
X1073375D01*
G01X1066319Y1480965D02*
Y1473681D01*
G01X1066472Y1474862D02*
Y1473681D01*
G01X1067112Y1474862D02*
Y1473681D01*
G01X1067479Y1474862D02*
Y1473248D01*
G01X1067921Y1480965D02*
Y1473681D01*
G01X1068464Y1474862D02*
Y1473248D01*
G01X1069921Y1473681D02*
Y1480965D01*
G01X1075944Y1427835D02*
Y1433248D01*
G01X1078714D02*
Y1425065D01*
G01X1079290Y1421339D02*
Y1693307D01*
G01Y1424488D02*
X1074566Y1429213D01*
G01X1073779Y1449980D02*
Y1444665D01*
G01Y1439980D02*
Y1434665D01*
G01X1076731Y1443248D02*
Y1441398D01*
G01X1078714Y1443248D02*
Y1441398D01*
G01X1073779Y1469980D02*
Y1464665D01*
G01Y1454665D02*
Y1459980D01*
G01X1076731Y1463248D02*
Y1461398D01*
G01Y1453248D02*
Y1451398D01*
G01X1078714Y1463248D02*
Y1461398D01*
G01Y1453248D02*
Y1451398D01*
G01X1075944Y1473248D02*
Y1471398D01*
G01X1078714Y1473248D02*
Y1471398D01*
G01X1041337Y1393701D02*
X1097204D01*
G01X1010519Y1475197D02*
Y1479449D01*
G01Y1485197D02*
Y1489449D01*
G01X1011123D02*
Y1485197D01*
G01Y1479449D02*
Y1475197D01*
G01X1011725Y1489449D02*
Y1485197D01*
G01Y1479449D02*
Y1475197D01*
G01X1010519Y1495197D02*
Y1499449D01*
G01Y1505197D02*
Y1509449D01*
G01X1011123D02*
Y1505197D01*
G01Y1499449D02*
Y1495197D01*
G01X1011725Y1509449D02*
Y1505197D01*
G01Y1499449D02*
Y1495197D01*
G01X1010519Y1515197D02*
Y1519449D01*
G01Y1525197D02*
Y1529449D01*
G01X1011123D02*
Y1525197D01*
G01Y1519449D02*
Y1515197D01*
G01X1011725Y1529449D02*
Y1525197D01*
G01Y1519449D02*
Y1515197D01*
G01X1010519Y1535197D02*
Y1539449D01*
G01Y1545197D02*
Y1549449D01*
G01X1011123D02*
Y1545197D01*
G01Y1539449D02*
Y1535197D01*
G01X1011725Y1549449D02*
Y1545197D01*
G01Y1539449D02*
Y1535197D01*
G01X1010519Y1555197D02*
Y1559449D01*
G01X1011123D02*
Y1555197D01*
G01X1011725Y1559449D02*
Y1555197D01*
G01X1015662Y1475197D02*
Y1479449D01*
G01Y1485197D02*
Y1489449D01*
G01X1016843D02*
Y1485197D01*
G01Y1479449D02*
Y1475197D01*
G01X1018025Y1489449D02*
Y1485197D01*
G01Y1479449D02*
Y1475197D01*
G01X1020471Y1489449D02*
Y1485197D01*
G01Y1479449D02*
Y1475197D01*
G01X1021653Y1489449D02*
Y1485197D01*
G01Y1479449D02*
Y1475197D01*
G01X1022440Y1479449D02*
Y1485197D01*
G01Y1489449D02*
Y1495197D01*
G01X1023227Y1483484D02*
Y1481161D01*
G01X1025196Y1485276D02*
Y1479370D01*
G01X1027164Y1478386D02*
Y1486260D01*
G01X1027558Y1485276D02*
Y1479370D01*
G01X1028362D02*
Y1485276D01*
G01X1030117D02*
Y1479370D01*
G01X1030921D02*
Y1485276D01*
G01X1039920Y1474449D02*
X1019290D01*
G01Y1475197D02*
X1022440D01*
G01X1019290Y1477402D02*
X1035786D01*
G01X1019290Y1479370D02*
X1027164D01*
G01D02*
X1030921D01*
G01X1022440Y1479449D02*
X1019290D01*
G01Y1481161D02*
X1039920D01*
G01Y1483484D02*
X1019290D01*
G01Y1485197D02*
X1022440D01*
G01X1030921Y1485276D02*
X1027164D01*
G01X1019290D02*
X1027164D01*
G01X1035786Y1487244D02*
X1019290D01*
G01X1022440Y1489449D02*
X1019290D01*
G01X1028149Y1487244D02*
G03X1027164Y1486260I-1J-984D01*
G01Y1478386D02*
G03X1028149Y1477402I984J0D01*
G01X1015662Y1495197D02*
Y1499449D01*
G01Y1505197D02*
Y1509449D01*
G01X1016843D02*
Y1505197D01*
G01Y1499449D02*
Y1495197D01*
G01X1018025Y1509449D02*
Y1505197D01*
G01Y1499449D02*
Y1495197D01*
G01X1020471Y1509449D02*
Y1505197D01*
G01Y1499449D02*
Y1495197D01*
G01X1021653Y1509449D02*
Y1505197D01*
G01Y1499449D02*
Y1495197D01*
G01X1022440Y1511358D02*
Y1509449D01*
G01Y1499449D02*
Y1505197D01*
G01X1023227Y1503484D02*
Y1501161D01*
G01Y1493484D02*
Y1491161D01*
G01X1025196Y1505276D02*
Y1499370D01*
G01X1027164Y1498386D02*
Y1506260D01*
G01X1027558Y1505276D02*
Y1499370D01*
G01X1028362Y1505276D02*
Y1499370D01*
G01X1030117Y1505276D02*
Y1499370D01*
G01X1030921D02*
Y1505276D01*
G01X1039920Y1490197D02*
X1019290D01*
G01Y1491161D02*
X1039920D01*
G01X1019290Y1493484D02*
X1039920D01*
G01X1019290Y1494449D02*
X1039920D01*
G01X1019290Y1495197D02*
X1022440D01*
G01X1019290Y1497402D02*
X1035786D01*
G01X1019290Y1499370D02*
X1027164D01*
G01D02*
X1030921D01*
G01X1022440Y1499449D02*
X1019290D01*
G01Y1501161D02*
X1039920D01*
G01Y1503484D02*
X1019290D01*
G01Y1505197D02*
X1022440D01*
G01X1030921Y1505276D02*
X1027164D01*
G01X1019290D02*
X1027164D01*
G01X1035786Y1507244D02*
X1019290D01*
G01Y1509449D02*
X1022440D01*
G01X1028149Y1507244D02*
G03X1027164Y1506260I-1J-984D01*
G01Y1498386D02*
G03X1028149Y1497402I984J0D01*
G01X1019684Y1513287D02*
X1019290Y1512894D01*
G01X1035983Y1513681D02*
X1032046Y1513287D01*
G01X1015662Y1515197D02*
Y1519449D01*
G01Y1525197D02*
Y1529449D01*
G01X1016843D02*
Y1525197D01*
G01Y1519449D02*
Y1515197D01*
G01X1018025Y1529449D02*
Y1525197D01*
G01Y1519449D02*
Y1515197D01*
G01X1019684Y1511358D02*
Y1510197D01*
G01Y1513287D02*
Y1514449D01*
G01X1020471Y1529449D02*
Y1525197D01*
G01Y1519449D02*
Y1515197D01*
G01X1021653Y1529449D02*
Y1525197D01*
G01Y1519449D02*
Y1515197D01*
G01X1022440Y1513287D02*
Y1515197D01*
G01Y1519449D02*
Y1525197D01*
G01Y1529449D02*
Y1535197D01*
G01X1023227Y1523484D02*
Y1521161D01*
G01X1025196Y1525276D02*
Y1519370D01*
G01X1027164Y1518386D02*
Y1526260D01*
G01X1027558Y1525276D02*
Y1519370D01*
G01X1028362Y1525276D02*
Y1519370D01*
G01X1030117Y1525276D02*
Y1519370D01*
G01X1030921Y1525276D02*
Y1519370D01*
G01X1039920Y1510197D02*
X1019290D01*
G01Y1510965D02*
X1072854D01*
G01X1039920Y1511358D02*
X1019684D01*
G01X1039920Y1513287D02*
X1019684D01*
G01X1019290Y1513681D02*
X1072854D01*
G01X1039920Y1514449D02*
X1019290D01*
G01Y1515197D02*
X1022440D01*
G01X1019290Y1517402D02*
X1035786D01*
G01X1019290Y1519370D02*
X1027164D01*
G01D02*
X1030921D01*
G01X1022440Y1519449D02*
X1019290D01*
G01Y1521161D02*
X1039920D01*
G01Y1523484D02*
X1019290D01*
G01Y1525197D02*
X1022440D01*
G01X1030921Y1525276D02*
X1027164D01*
G01X1019290D02*
X1027164D01*
G01X1035786Y1527244D02*
X1019290D01*
G01X1022440Y1529449D02*
X1019290D01*
G01X1039920Y1530197D02*
X1019290D01*
G01X1032046Y1511358D02*
X1035983Y1510965D01*
G01X1019290Y1511752D02*
X1019684Y1511358D01*
G01X1028149Y1527244D02*
G03X1027164Y1526260I-1J-984D01*
G01Y1518386D02*
G03X1028149Y1517402I984J0D01*
G01X1015662Y1535197D02*
Y1539449D01*
G01Y1545197D02*
Y1549449D01*
G01X1016843D02*
Y1545197D01*
G01Y1539449D02*
Y1535197D01*
G01X1018025Y1549449D02*
Y1545197D01*
G01Y1539449D02*
Y1535197D01*
G01X1019684Y1551358D02*
Y1550197D01*
G01X1020471Y1549449D02*
Y1545197D01*
G01Y1539449D02*
Y1535197D01*
G01X1021653Y1549449D02*
Y1545197D01*
G01Y1539449D02*
Y1535197D01*
G01X1022440Y1551358D02*
Y1549449D01*
G01Y1539449D02*
Y1545197D01*
G01X1023227Y1543484D02*
Y1541161D01*
G01Y1533484D02*
Y1531161D01*
G01X1025196Y1545276D02*
Y1539370D01*
G01X1027164Y1546260D02*
Y1538386D01*
G01X1027558Y1545276D02*
Y1539370D01*
G01X1028362Y1545276D02*
Y1539370D01*
G01X1030117Y1545276D02*
Y1539370D01*
G01X1030921D02*
Y1545276D01*
G01X1019290Y1531161D02*
X1039920D01*
G01X1019290Y1533484D02*
X1039920D01*
G01X1019290Y1534449D02*
X1039920D01*
G01X1019290Y1535197D02*
X1022440D01*
G01X1019290Y1537402D02*
X1035786D01*
G01X1019290Y1539370D02*
X1027164D01*
G01D02*
X1030921D01*
G01X1022440Y1539449D02*
X1019290D01*
G01Y1541161D02*
X1039920D01*
G01Y1543484D02*
X1019290D01*
G01Y1545197D02*
X1022440D01*
G01X1030921Y1545276D02*
X1027164D01*
G01X1019290D02*
X1027164D01*
G01X1035786Y1547244D02*
X1019290D01*
G01Y1549449D02*
X1022440D01*
G01X1039920Y1550197D02*
X1019290D01*
G01X1028149Y1547244D02*
G03X1027164Y1546260I-1J-984D01*
G01Y1538386D02*
G03X1028149Y1537402I984J0D01*
G01X1019290Y1552894D02*
X1019684Y1553287D01*
G01X1015662Y1555197D02*
Y1559449D01*
G01X1016843D02*
Y1555197D01*
G01X1018025Y1559449D02*
Y1555197D01*
G01X1019684Y1554449D02*
Y1553287D01*
G01X1020471Y1559449D02*
Y1555197D01*
G01X1021653Y1559449D02*
Y1555197D01*
G01X1022440D02*
Y1553287D01*
G01X1035983Y1553681D02*
X1032046Y1553287D01*
G01X1019290Y1550965D02*
X1072854D01*
G01X1039920Y1551358D02*
X1019684D01*
G01Y1553287D02*
X1039920D01*
G01X1019290Y1553681D02*
X1072854D01*
G01X1039920Y1554449D02*
X1019290D01*
G01Y1555197D02*
X1022440D01*
G01X1032046Y1551358D02*
X1035983Y1550965D01*
G01X1019290Y1551752D02*
X1019684Y1551358D01*
G01X1035983Y1497441D02*
Y1487205D01*
G01Y1477441D02*
Y1487205D01*
G01X1036110Y1491161D02*
Y1483484D01*
G01X1036263Y1487103D02*
Y1477543D01*
G01Y1487103D02*
Y1497543D01*
G01X1036527Y1483091D02*
Y1481555D01*
G01X1036677D02*
Y1483091D01*
G01X1036771Y1478386D02*
Y1486260D01*
G01X1040708Y1481398D02*
Y1483248D01*
G01X1039920Y1479370D02*
X1036771D01*
G01X1037114Y1480965D02*
X1072854D01*
G01X1037164Y1481398D02*
X1079290D01*
G01X1036677Y1481555D02*
X1036527D01*
G01X1036677Y1483091D02*
X1036527D01*
G01X1079290Y1483248D02*
X1037164D01*
G01X1037114Y1483681D02*
X1072854D01*
G01X1039920Y1485276D02*
X1036771D01*
G01X1035786Y1477402D02*
G03X1036771Y1478386I1J984D01*
G01Y1486260D02*
G03X1035786Y1487244I-984J0D01*
G01X1036768Y1483569D02*
G03X1036674Y1483484I349J-481D01*
G01Y1481161D02*
G03X1036768Y1481077I440J398D01*
G01X1036762Y1481250D02*
G03X1036830Y1481158I509J305D01*
G01X1036850Y1483508D02*
G03X1036762Y1483396I419J-420D01*
G01X1037114Y1483681D02*
G03X1036951Y1483658I0J-592D01*
G01X1037266Y1483681D02*
G03X1037117Y1483662I0J-592D01*
G01X1036951Y1483658D02*
G03X1036800Y1483591I161J-567D01*
G01X1037117Y1483662D02*
G03X1037039Y1483635I153J-569D01*
G01X1036800Y1483591D02*
G03X1036768Y1483569I317J-496D01*
G01X1036723Y1481328D02*
G03X1036762Y1481250I544J223D01*
G01Y1483396D02*
G03X1036723Y1483318I505J-301D01*
G01X1036771Y1481791D02*
G03X1037164Y1481398I394J1D01*
G01Y1483248D02*
G03X1036771Y1482854I1J-394D01*
G01X1035983Y1510965D02*
Y1507205D01*
G01Y1497441D02*
Y1507205D01*
G01X1036110Y1510965D02*
Y1503484D01*
G01Y1501161D02*
Y1493484D01*
G01X1036263Y1507103D02*
Y1497543D01*
G01Y1507103D02*
Y1510965D01*
G01X1036527Y1503091D02*
Y1501555D01*
G01Y1491555D02*
Y1493091D01*
G01X1036677Y1503091D02*
Y1501555D01*
G01Y1493091D02*
Y1491555D01*
G01X1036771Y1491791D02*
Y1492854D01*
G01Y1498386D02*
Y1506260D01*
G01X1040708Y1493248D02*
Y1491398D01*
G01Y1501398D02*
Y1503248D01*
G01X1037114Y1490965D02*
X1072854D01*
G01X1037164Y1491398D02*
X1079290D01*
G01X1036677Y1491555D02*
X1036527D01*
G01X1036677Y1493091D02*
X1036527D01*
G01X1079290Y1493248D02*
X1037164D01*
G01X1037114Y1493681D02*
X1072854D01*
G01X1039920Y1499370D02*
X1036771D01*
G01X1037114Y1500965D02*
X1072854D01*
G01X1037164Y1501398D02*
X1079290D01*
G01X1036677Y1501555D02*
X1036527D01*
G01X1036677Y1503091D02*
X1036527D01*
G01X1079290Y1503248D02*
X1037164D01*
G01X1037114Y1503681D02*
X1072854D01*
G01X1036771Y1505276D02*
X1039920D01*
G01X1036800Y1493591D02*
G03X1036675Y1493484I320J-501D01*
G01X1037114Y1493681D02*
G03X1036951Y1493658I0J-592D01*
G01X1037266Y1493681D02*
G03X1037117Y1493662I0J-592D01*
G01X1036951Y1493658D02*
G03X1036800Y1493591I161J-567D01*
G01X1037117Y1493662D02*
G03X1037039Y1493635I153J-569D01*
G01X1036771Y1491791D02*
G03X1037164Y1491398I394J1D01*
G01Y1493248D02*
G03X1036771Y1492854I1J-394D01*
G01X1035786Y1497402D02*
G03X1036771Y1498386I1J984D01*
G01Y1506260D02*
G03X1035786Y1507244I-984J0D01*
G01X1036768Y1503569D02*
G03X1036674Y1503484I349J-481D01*
G01Y1501161D02*
G03X1036768Y1501077I440J398D01*
G01X1037114Y1503681D02*
G03X1036951Y1503658I0J-592D01*
G01D02*
G03X1036800Y1503591I161J-567D01*
G01D02*
G03X1036768Y1503569I317J-496D01*
G01X1036771Y1501791D02*
G03X1037164Y1501398I394J1D01*
G01Y1503248D02*
G03X1036771Y1502854I1J-394D01*
G01X1036762Y1501250D02*
G03X1036850Y1501137I509J305D01*
G01Y1503508D02*
G03X1036762Y1503396I419J-420D01*
G01X1037266Y1503681D02*
G03X1037117Y1503662I0J-592D01*
G01D02*
G03X1037039Y1503635I153J-569D01*
G01X1036723Y1501328D02*
G03X1036762Y1501250I544J223D01*
G01Y1503396D02*
G03X1036723Y1503318I505J-301D01*
G01X1035983Y1517441D02*
Y1513681D01*
G01Y1537441D02*
Y1527205D01*
G01Y1517441D02*
Y1527205D01*
G01X1036110Y1531161D02*
Y1523484D01*
G01Y1521161D02*
Y1513681D01*
G01X1036263Y1527103D02*
Y1517543D01*
G01D02*
Y1513681D01*
G01Y1527103D02*
Y1537543D01*
G01X1036527Y1523091D02*
Y1521555D01*
G01X1036677Y1523091D02*
Y1521555D01*
G01X1036771Y1518386D02*
Y1526260D01*
G01X1040708Y1521398D02*
Y1523248D01*
G01X1039920Y1511398D02*
X1079290D01*
G01Y1513248D02*
X1039920D01*
G01Y1519370D02*
X1036771D01*
G01X1037114Y1520965D02*
X1072854D01*
G01X1037164Y1521398D02*
X1079290D01*
G01X1036677Y1521555D02*
X1036527D01*
G01X1036677Y1523091D02*
X1036527D01*
G01X1079290Y1523248D02*
X1037164D01*
G01X1037114Y1523681D02*
X1072854D01*
G01X1039920Y1525276D02*
X1036771D01*
G01X1035786Y1517402D02*
G03X1036771Y1518386I1J984D01*
G01Y1526260D02*
G03X1035786Y1527244I-984J0D01*
G01X1036674Y1521161D02*
G03X1036768Y1521077I440J398D01*
G01X1036771Y1521791D02*
G03X1037164Y1521398I394J1D01*
G01X1036768Y1523569D02*
G03X1036674Y1523484I349J-481D01*
G01X1037114Y1523681D02*
G03X1036951Y1523658I0J-592D01*
G01D02*
G03X1036800Y1523591I161J-567D01*
G01D02*
G03X1036768Y1523569I317J-496D01*
G01X1037164Y1523248D02*
G03X1036771Y1522854I1J-394D01*
G01X1036762Y1521250D02*
G03X1036830Y1521158I509J305D01*
G01X1036723Y1521328D02*
G03X1036762Y1521250I544J223D01*
G01X1036850Y1523508D02*
G03X1036762Y1523396I419J-420D01*
G01X1037266Y1523681D02*
G03X1037117Y1523662I0J-592D01*
G01D02*
G03X1037039Y1523635I153J-569D01*
G01X1036762Y1523396D02*
G03X1036723Y1523318I505J-301D01*
G01X1035983Y1550965D02*
Y1547205D01*
G01Y1537441D02*
Y1547205D01*
G01X1036110Y1550965D02*
Y1543484D01*
G01Y1541161D02*
Y1533484D01*
G01X1036263Y1547103D02*
Y1537543D01*
G01Y1547103D02*
Y1550965D01*
G01X1036527Y1543091D02*
Y1541555D01*
G01Y1533091D02*
Y1531555D01*
G01X1036677Y1543091D02*
Y1541555D01*
G01Y1533091D02*
Y1531555D01*
G01X1036771Y1531791D02*
Y1532854D01*
G01Y1538386D02*
Y1546260D01*
G01X1040708Y1533248D02*
Y1531398D01*
G01Y1541398D02*
Y1543248D01*
G01X1037114Y1530965D02*
X1072854D01*
G01X1037164Y1531398D02*
X1079290D01*
G01X1036677Y1531555D02*
X1036527D01*
G01X1036677Y1533091D02*
X1036527D01*
G01X1079290Y1533248D02*
X1037164D01*
G01X1037114Y1533681D02*
X1072854D01*
G01X1039920Y1539370D02*
X1036771D01*
G01X1037114Y1540965D02*
X1072854D01*
G01X1037164Y1541398D02*
X1079290D01*
G01X1036677Y1541555D02*
X1036527D01*
G01X1036677Y1543091D02*
X1036527D01*
G01X1079290Y1543248D02*
X1037164D01*
G01X1037114Y1543681D02*
X1072854D01*
G01X1036771Y1545276D02*
X1039920D01*
G01X1035786Y1537402D02*
G03X1036771Y1538386I1J984D01*
G01Y1546260D02*
G03X1035786Y1547244I-984J0D01*
G01X1036800Y1533591D02*
G03X1036675Y1533484I320J-501D01*
G01X1036768Y1543569D02*
G03X1036674Y1543484I349J-481D01*
G01Y1541161D02*
G03X1036768Y1541077I440J398D01*
G01X1037114Y1543681D02*
G03X1036951Y1543658I0J-592D01*
G01X1037114Y1533681D02*
G03X1036951Y1533658I0J-592D01*
G01Y1543658D02*
G03X1036800Y1543591I161J-567D01*
G01X1036951Y1533658D02*
G03X1036800Y1533591I161J-567D01*
G01Y1543591D02*
G03X1036768Y1543569I317J-496D01*
G01X1036771Y1541791D02*
G03X1037164Y1541398I394J1D01*
G01Y1543248D02*
G03X1036771Y1542854I1J-394D01*
G01Y1531791D02*
G03X1037164Y1531398I394J1D01*
G01Y1533248D02*
G03X1036771Y1532854I1J-394D01*
G01X1036762Y1541250D02*
G03X1036830Y1541158I509J305D01*
G01X1036850Y1543508D02*
G03X1036762Y1543396I419J-420D01*
G01X1037117Y1530984D02*
G03X1037266Y1530965I149J573D01*
G01Y1543681D02*
G03X1037117Y1543662I0J-592D01*
G01X1037266Y1533681D02*
G03X1037117Y1533662I0J-592D01*
G01Y1543662D02*
G03X1037039Y1543635I153J-569D01*
G01X1037117Y1533662D02*
G03X1037039Y1533635I153J-569D01*
G01X1036723Y1541328D02*
G03X1036762Y1541250I544J223D01*
G01Y1543396D02*
G03X1036723Y1543318I505J-301D01*
G01X1035983Y1557441D02*
Y1553681D01*
G01X1036110Y1561161D02*
Y1553681D01*
G01X1036263Y1557543D02*
Y1553681D01*
G01X1039920Y1551398D02*
X1079290D01*
G01Y1553248D02*
X1039920D01*
G01X1053700Y1488799D02*
Y1485846D01*
G01Y1478799D02*
Y1475846D01*
G01X1073779Y1474665D02*
X1073375D01*
G01X1054684Y1474862D02*
X1068464D01*
G01Y1479783D02*
X1054684D01*
G01X1073779Y1479980D02*
X1073375D01*
G01X1073779Y1484665D02*
X1073375D01*
G01X1054684Y1484862D02*
X1068464D01*
G01Y1489783D02*
X1054684D01*
G01X1073779Y1489980D02*
X1073375D01*
G01X1066319Y1490965D02*
Y1483681D01*
G01X1066472Y1490965D02*
Y1489783D01*
G01Y1484862D02*
Y1483681D01*
G01Y1480965D02*
Y1479783D01*
G01Y1474862D02*
Y1479783D01*
G01Y1484862D02*
Y1489783D01*
G01X1067112D02*
Y1484862D01*
G01D02*
Y1483681D01*
G01Y1479783D02*
Y1474862D01*
G01Y1479783D02*
Y1480965D01*
G01Y1489783D02*
Y1490965D01*
G01X1067479Y1491398D02*
Y1489783D01*
G01Y1481398D02*
Y1479783D01*
G01Y1484862D02*
Y1483248D01*
G01X1067921Y1490965D02*
Y1483681D01*
G01X1068464Y1491398D02*
Y1489783D01*
G01Y1481398D02*
Y1479783D01*
G01Y1484862D02*
Y1483248D01*
G01X1069448Y1475846D02*
Y1478799D01*
G01Y1485846D02*
Y1488799D01*
G01X1069921Y1490965D02*
Y1483681D01*
G01X1073375Y1489980D02*
Y1484665D01*
G01Y1474665D02*
Y1479980D01*
G01X1053700Y1485846D02*
G03X1054684Y1484862I984J0D01*
G01X1068464D02*
G03X1069448Y1485846I0J984D01*
G01Y1488799D02*
G03X1068464Y1489783I-984J0D01*
G01X1054684D02*
G03X1053700Y1488799I0J-984D01*
G01Y1475846D02*
G03X1054684Y1474862I984J0D01*
G01X1068464D02*
G03X1069448Y1475846I0J984D01*
G01Y1478799D02*
G03X1068464Y1479783I-984J0D01*
G01X1054684D02*
G03X1053700Y1478799I0J-984D01*
G01Y1508799D02*
Y1505846D01*
G01Y1498799D02*
Y1495846D01*
G01X1073779Y1494665D02*
X1073375D01*
G01X1054684Y1494862D02*
X1068464D01*
G01Y1499783D02*
X1054684D01*
G01X1073779Y1499980D02*
X1073375D01*
G01X1073779Y1504665D02*
X1073375D01*
G01X1054684Y1504862D02*
X1068464D01*
G01Y1509783D02*
X1054684D01*
G01X1073779Y1509980D02*
X1073375D01*
G01X1066319Y1510965D02*
Y1503681D01*
G01Y1500965D02*
Y1493681D01*
G01X1066472Y1510965D02*
Y1509783D01*
G01Y1504862D02*
Y1503681D01*
G01Y1500965D02*
Y1499783D01*
G01Y1494862D02*
Y1493681D01*
G01Y1494862D02*
Y1499783D01*
G01Y1504862D02*
Y1509783D01*
G01X1067112D02*
Y1504862D01*
G01D02*
Y1503681D01*
G01Y1499783D02*
Y1494862D01*
G01D02*
Y1493681D01*
G01Y1499783D02*
Y1500965D01*
G01Y1509783D02*
Y1510965D01*
G01X1067479Y1511398D02*
Y1509783D01*
G01Y1504862D02*
Y1503248D01*
G01Y1501398D02*
Y1499783D01*
G01Y1494862D02*
Y1493248D01*
G01X1067921Y1510965D02*
Y1503681D01*
G01Y1500965D02*
Y1493681D01*
G01X1068464Y1511398D02*
Y1509783D01*
G01Y1501398D02*
Y1499783D01*
G01Y1494862D02*
Y1493248D01*
G01Y1503248D02*
Y1504862D01*
G01X1069448Y1495846D02*
Y1498799D01*
G01Y1505846D02*
Y1508799D01*
G01X1069921Y1510965D02*
Y1503681D01*
G01Y1493681D02*
Y1500965D01*
G01X1073375Y1509980D02*
Y1504665D01*
G01Y1494665D02*
Y1499980D01*
G01X1053700Y1505846D02*
G03X1054684Y1504862I984J0D01*
G01Y1509783D02*
G03X1053700Y1508799I0J-984D01*
G01Y1495846D02*
G03X1054684Y1494862I984J0D01*
G01Y1499783D02*
G03X1053700Y1498799I0J-984D01*
G01X1068464Y1504862D02*
G03X1069448Y1505846I0J984D01*
G01Y1508799D02*
G03X1068464Y1509783I-984J0D01*
G01Y1494862D02*
G03X1069448Y1495846I0J984D01*
G01Y1498799D02*
G03X1068464Y1499783I-984J0D01*
G01X1053700Y1528799D02*
Y1525846D01*
G01Y1518799D02*
Y1515846D01*
G01X1073779Y1514665D02*
X1073375D01*
G01X1054684Y1514862D02*
X1068464D01*
G01Y1519783D02*
X1054684D01*
G01X1073779Y1519980D02*
X1073375D01*
G01X1073779Y1524665D02*
X1073375D01*
G01X1054684Y1524862D02*
X1068464D01*
G01Y1529783D02*
X1054684D01*
G01X1073779Y1529980D02*
X1073375D01*
G01X1066319Y1530965D02*
Y1523681D01*
G01Y1520965D02*
Y1513681D01*
G01X1066472Y1530965D02*
Y1529783D01*
G01Y1524862D02*
Y1523681D01*
G01Y1520965D02*
Y1519783D01*
G01Y1514862D02*
Y1513681D01*
G01Y1514862D02*
Y1519783D01*
G01Y1524862D02*
Y1529783D01*
G01X1067112D02*
Y1524862D01*
G01D02*
Y1523681D01*
G01Y1519783D02*
Y1514862D01*
G01D02*
Y1513681D01*
G01Y1519783D02*
Y1520965D01*
G01Y1529783D02*
Y1530965D01*
G01X1067479Y1531398D02*
Y1529783D01*
G01Y1524862D02*
Y1523248D01*
G01Y1521398D02*
Y1519783D01*
G01Y1514862D02*
Y1513248D01*
G01X1067921Y1530965D02*
Y1523681D01*
G01Y1520965D02*
Y1513681D01*
G01X1068464Y1531398D02*
Y1529783D01*
G01Y1524862D02*
Y1523248D01*
G01Y1521398D02*
Y1519783D01*
G01Y1514862D02*
Y1513248D01*
G01X1069448Y1515846D02*
Y1518799D01*
G01Y1525846D02*
Y1528799D01*
G01X1069921Y1530965D02*
Y1523681D01*
G01Y1513681D02*
Y1520965D01*
G01X1073375Y1529980D02*
Y1524665D01*
G01Y1514665D02*
Y1519980D01*
G01X1053700Y1525846D02*
G03X1054684Y1524862I984J0D01*
G01Y1529783D02*
G03X1053700Y1528799I0J-984D01*
G01Y1515846D02*
G03X1054684Y1514862I984J0D01*
G01Y1519783D02*
G03X1053700Y1518799I0J-984D01*
G01X1068464Y1524862D02*
G03X1069448Y1525846I0J984D01*
G01Y1528799D02*
G03X1068464Y1529783I-984J0D01*
G01Y1514862D02*
G03X1069448Y1515846I0J984D01*
G01Y1518799D02*
G03X1068464Y1519783I-984J0D01*
G01X1053700Y1548799D02*
Y1545846D01*
G01Y1538799D02*
Y1535846D01*
G01X1073779Y1534665D02*
X1073375D01*
G01X1054684Y1534862D02*
X1068464D01*
G01X1066319Y1550965D02*
Y1543681D01*
G01Y1540965D02*
Y1533681D01*
G01X1066472Y1550965D02*
Y1549783D01*
G01Y1544862D02*
Y1543681D01*
G01Y1540965D02*
Y1539783D01*
G01Y1534862D02*
Y1533681D01*
G01Y1534862D02*
Y1539783D01*
G01Y1544862D02*
Y1549783D01*
G01X1067112D02*
Y1544862D01*
G01D02*
Y1543681D01*
G01Y1539783D02*
Y1534862D01*
G01D02*
Y1533681D01*
G01Y1539783D02*
Y1540965D01*
G01Y1549783D02*
Y1550965D01*
G01X1067479Y1551398D02*
Y1549783D01*
G01Y1544862D02*
Y1543248D01*
G01Y1541398D02*
Y1539783D01*
G01Y1534862D02*
Y1533248D01*
G01X1067921Y1550965D02*
Y1543681D01*
G01Y1540965D02*
Y1533681D01*
G01X1068464Y1551398D02*
Y1549783D01*
G01Y1541398D02*
Y1539783D01*
G01Y1534862D02*
Y1533248D01*
G01Y1543248D02*
Y1544862D01*
G01X1069448Y1535846D02*
Y1538799D01*
G01Y1545846D02*
Y1548799D01*
G01X1069921Y1550965D02*
Y1543681D01*
G01Y1533681D02*
Y1540965D01*
G01X1073375Y1549980D02*
Y1544665D01*
G01Y1534665D02*
Y1539980D01*
G01X1068464Y1539783D02*
X1054684D01*
G01X1073779Y1539980D02*
X1073375D01*
G01X1073779Y1544665D02*
X1073375D01*
G01X1054684Y1544862D02*
X1068464D01*
G01Y1549783D02*
X1054684D01*
G01X1073779Y1549980D02*
X1073375D01*
G01X1053700Y1545846D02*
G03X1054684Y1544862I984J0D01*
G01X1053700Y1535846D02*
G03X1054684Y1534862I984J0D01*
G01Y1539783D02*
G03X1053700Y1538799I0J-984D01*
G01X1054684Y1549783D02*
G03X1053700Y1548799I0J-984D01*
G01X1068464Y1544862D02*
G03X1069448Y1545846I0J984D01*
G01X1068464Y1534862D02*
G03X1069448Y1535846I0J984D01*
G01Y1538799D02*
G03X1068464Y1539783I-984J0D01*
G01X1069448Y1548799D02*
G03X1068464Y1549783I-984J0D01*
G01X1053700Y1558799D02*
Y1555846D01*
G01X1066319Y1560965D02*
Y1553681D01*
G01X1066472Y1554862D02*
Y1553681D01*
G01Y1554862D02*
Y1559783D01*
G01X1067112D02*
Y1554862D01*
G01D02*
Y1553681D01*
G01X1067479Y1554862D02*
Y1553248D01*
G01X1067921Y1560965D02*
Y1553681D01*
G01X1068464Y1554862D02*
Y1553248D01*
G01X1069448Y1555846D02*
Y1558799D01*
G01X1069921Y1553681D02*
Y1560965D01*
G01X1073375Y1554665D02*
Y1559980D01*
G01X1073779Y1554665D02*
X1073375D01*
G01X1054684Y1554862D02*
X1068464D01*
G01X1053700Y1555846D02*
G03X1054684Y1554862I984J0D01*
G01X1068464D02*
G03X1069448Y1555846I0J984D01*
G01X1073779Y1489980D02*
Y1484665D01*
G01Y1479980D02*
Y1474665D01*
G01X1076731Y1483248D02*
Y1481398D01*
G01X1078714Y1483248D02*
Y1481398D01*
G01X1073779Y1509980D02*
Y1504665D01*
G01Y1494665D02*
Y1499980D01*
G01X1076731Y1503248D02*
Y1501398D01*
G01Y1493248D02*
Y1491398D01*
G01X1078714Y1503248D02*
Y1501398D01*
G01Y1493248D02*
Y1491398D01*
G01X1073779Y1529980D02*
Y1524665D01*
G01Y1519980D02*
Y1514665D01*
G01X1075944Y1513248D02*
Y1511398D01*
G01X1076731Y1523248D02*
Y1521398D01*
G01X1078714Y1523248D02*
Y1521398D01*
G01Y1513248D02*
Y1511398D01*
G01X1073779Y1549980D02*
Y1544665D01*
G01Y1534665D02*
Y1539980D01*
G01X1076731Y1543248D02*
Y1541398D01*
G01Y1533248D02*
Y1531398D01*
G01X1078714Y1543248D02*
Y1541398D01*
G01Y1533248D02*
Y1531398D01*
G01X1073779Y1559980D02*
Y1554665D01*
G01X1075944Y1553248D02*
Y1551398D01*
G01X1078714Y1553248D02*
Y1551398D01*
G01X1010519Y1565197D02*
Y1569449D01*
G01X1011123D02*
Y1565197D01*
G01X1011725Y1569449D02*
Y1565197D01*
G01X1010519Y1575197D02*
Y1579449D01*
G01Y1585197D02*
Y1589449D01*
G01X1011123D02*
Y1585197D01*
G01Y1579449D02*
Y1575197D01*
G01X1011725Y1589449D02*
Y1585197D01*
G01Y1579449D02*
Y1575197D01*
G01X1010519Y1595197D02*
Y1599449D01*
G01Y1605197D02*
Y1609449D01*
G01X1011123D02*
Y1605197D01*
G01Y1599449D02*
Y1595197D01*
G01X1011725Y1609449D02*
Y1605197D01*
G01Y1599449D02*
Y1595197D01*
G01X1015662Y1565197D02*
Y1569449D01*
G01X1016843D02*
Y1565197D01*
G01X1018025Y1569449D02*
Y1565197D01*
G01X1020471Y1569449D02*
Y1565197D01*
G01X1021653Y1569449D02*
Y1565197D01*
G01X1022440Y1559449D02*
Y1565197D01*
G01Y1569449D02*
Y1575197D01*
G01X1023227Y1563484D02*
Y1561161D01*
G01X1025196Y1565276D02*
Y1559370D01*
G01X1027164Y1558386D02*
Y1566260D01*
G01X1027558Y1565276D02*
Y1559370D01*
G01X1028362D02*
Y1565276D01*
G01X1030117D02*
Y1559370D01*
G01X1030921D02*
Y1565276D01*
G01X1019290Y1557402D02*
X1035786D01*
G01X1019290Y1559370D02*
X1027164D01*
G01D02*
X1030921D01*
G01X1022440Y1559449D02*
X1019290D01*
G01X1039920Y1561161D02*
X1019290D01*
G01Y1563484D02*
X1039920D01*
G01X1019290Y1565197D02*
X1022440D01*
G01X1030921Y1565276D02*
X1027164D01*
G01X1019290D02*
X1027164D01*
G01X1035786Y1567244D02*
X1019290D01*
G01X1022440Y1569449D02*
X1019290D01*
G01X1039920Y1570197D02*
X1019290D01*
G01X1028149Y1567244D02*
G03X1027164Y1566260I-1J-984D01*
G01Y1558386D02*
G03X1028149Y1557402I984J0D01*
G01X1015662Y1575197D02*
Y1579449D01*
G01Y1585197D02*
Y1589449D01*
G01X1016843D02*
Y1585197D01*
G01Y1579449D02*
Y1575197D01*
G01X1018025Y1589449D02*
Y1585197D01*
G01Y1579449D02*
Y1575197D01*
G01X1019684Y1591358D02*
Y1590197D01*
G01X1020471Y1589449D02*
Y1585197D01*
G01Y1579449D02*
Y1575197D01*
G01X1021653Y1589449D02*
Y1585197D01*
G01Y1579449D02*
Y1575197D01*
G01X1022440Y1591358D02*
Y1589449D01*
G01Y1579449D02*
Y1585197D01*
G01X1023227Y1583484D02*
Y1581161D01*
G01Y1573484D02*
Y1571161D01*
G01X1025196Y1585276D02*
Y1579370D01*
G01X1027164Y1578386D02*
Y1586260D01*
G01X1027558Y1585276D02*
Y1579370D01*
G01X1028362Y1585276D02*
Y1579370D01*
G01X1030117Y1585276D02*
Y1579370D01*
G01X1030921D02*
Y1585276D01*
G01X1019290Y1571161D02*
X1039920D01*
G01Y1573484D02*
X1019290D01*
G01Y1574449D02*
X1039920D01*
G01X1019290Y1575197D02*
X1022440D01*
G01X1019290Y1577402D02*
X1035786D01*
G01X1019290Y1579370D02*
X1027164D01*
G01D02*
X1030921D01*
G01X1022440Y1579449D02*
X1019290D01*
G01Y1581161D02*
X1039920D01*
G01Y1583484D02*
X1019290D01*
G01Y1585197D02*
X1022440D01*
G01X1030921Y1585276D02*
X1027164D01*
G01X1019290D02*
X1027164D01*
G01X1035786Y1587244D02*
X1019290D01*
G01Y1589449D02*
X1022440D01*
G01X1019290Y1590197D02*
X1039920D01*
G01X1028149Y1587244D02*
G03X1027164Y1586260I-1J-984D01*
G01Y1578386D02*
G03X1028149Y1577402I984J0D01*
G01X1019290Y1592894D02*
X1019684Y1593287D01*
G01X1015662Y1595197D02*
Y1599449D01*
G01Y1605197D02*
Y1609449D01*
G01X1016843D02*
Y1605197D01*
G01Y1599449D02*
Y1595197D01*
G01X1017762Y1609449D02*
Y1609374D01*
G01X1018025Y1609128D02*
Y1605197D01*
G01Y1599449D02*
Y1595197D01*
G01Y1609128D02*
Y1609449D01*
G01X1019290Y1607933D02*
Y1606260D01*
G01Y1612165D02*
Y1607933D01*
G01X1019684Y1593287D02*
Y1594449D01*
G01X1020471Y1609449D02*
Y1605197D01*
G01Y1599449D02*
Y1595197D01*
G01X1021653Y1609449D02*
Y1605197D01*
G01Y1599449D02*
Y1595197D01*
G01X1022440D02*
Y1593287D01*
G01Y1599449D02*
Y1605197D01*
G01Y1609449D02*
Y1611358D01*
G01X1023227Y1603484D02*
Y1601161D01*
G01X1025196Y1605276D02*
Y1599370D01*
G01X1027164Y1598386D02*
Y1606260D01*
G01X1027558Y1605276D02*
Y1599370D01*
G01X1028362D02*
Y1605276D01*
G01X1030117D02*
Y1599370D01*
G01X1030921D02*
Y1605276D01*
G01X1035983Y1593681D02*
X1032046Y1593287D01*
G01X1019290Y1590965D02*
X1072854D01*
G01X1019684Y1591358D02*
X1039920D01*
G01Y1593287D02*
X1019684D01*
G01X1019290Y1593681D02*
X1072854D01*
G01X1039920Y1594449D02*
X1019290D01*
G01Y1595197D02*
X1022440D01*
G01X1019290Y1597402D02*
X1035786D01*
G01X1019290Y1599370D02*
X1027164D01*
G01D02*
X1030921D01*
G01X1022440Y1599449D02*
X1019290D01*
G01X1039920Y1601161D02*
X1019290D01*
G01X1039920Y1603484D02*
X1019290D01*
G01Y1605197D02*
X1022440D01*
G01X1030921Y1605276D02*
X1027164D01*
G01D02*
X1019290D01*
G01X1035786Y1607244D02*
X1019166D01*
G01X1022440Y1609449D02*
X1017610D01*
G01X1015353Y1610197D02*
X1039920D01*
G01X1032046Y1591358D02*
X1035983Y1590965D01*
G01X1019290Y1591752D02*
X1019684Y1591358D01*
G01X1015353Y1611870D02*
X1019290Y1607933D01*
G01X1027164Y1598386D02*
G03X1028149Y1597402I984J0D01*
G01X1019290Y1606260D02*
G03X1015353Y1610197I-3937J0D01*
G01X1028149Y1607244D02*
G03X1027164Y1606260I-1J-984D01*
G01X1034508Y1630236D02*
X1033281Y1629528D01*
G01X1034508Y1625236D02*
X1033281Y1624528D01*
G01X1034508Y1620236D02*
X1033281Y1619528D01*
G01X1017027Y1617756D02*
X1015353Y1616083D01*
G01X1017027Y1617756D02*
X1019290Y1620020D01*
G01X1029527Y1629134D02*
X1030511Y1630118D01*
G01Y1629528D02*
X1029586Y1628602D01*
G01X1030511Y1625118D02*
X1029527Y1624134D01*
G01X1029586Y1623602D02*
X1030511Y1624528D01*
G01Y1620118D02*
X1029527Y1619134D01*
G01Y1618543D02*
X1030511Y1619528D01*
G01X1019290Y1632087D02*
Y1630118D01*
G01Y1627087D02*
Y1625118D01*
G01Y1622087D02*
Y1620020D01*
G01Y1630118D02*
Y1627087D01*
G01Y1625118D02*
Y1622087D01*
G01Y1617756D02*
Y1615787D01*
G01X1028484Y1620118D02*
Y1622087D01*
G01Y1625118D02*
Y1627087D01*
G01Y1630118D02*
Y1632087D01*
G01X1028727D02*
Y1630118D01*
G01Y1627087D02*
Y1625118D01*
G01Y1622087D02*
Y1620118D01*
G01X1029133Y1632087D02*
Y1630118D01*
G01Y1627087D02*
Y1625118D01*
G01Y1622087D02*
Y1620118D01*
G01X1029527Y1615394D02*
Y1679449D01*
G01X1030511Y1632677D02*
Y1629528D01*
G01Y1627677D02*
Y1624528D01*
G01Y1622677D02*
Y1619528D01*
G01X1030314Y1619331D02*
X1029527D01*
G01X1048030Y1619528D02*
X1030511D01*
G01X1079290Y1620118D02*
X1030511D01*
G01Y1622087D02*
X1079290D01*
G01X1048030Y1622677D02*
X1030511D01*
G01X1030314Y1622874D02*
X1029527D01*
G01X1030314Y1624331D02*
X1029527D01*
G01X1048030Y1624528D02*
X1030511D01*
G01X1079290Y1625118D02*
X1030511D01*
G01Y1627087D02*
X1079290D01*
G01X1048030Y1627677D02*
X1030511D01*
G01X1029527Y1627874D02*
X1030314D01*
G01Y1629331D02*
X1029527D01*
G01X1030511Y1629528D02*
X1048030D01*
G01X1030511Y1630118D02*
X1079290D01*
G01X1032046Y1611358D02*
X1035983Y1610965D01*
G01X1033281Y1622677D02*
X1034508Y1621969D01*
G01X1033281Y1627677D02*
X1034508Y1626969D01*
G01X1030511Y1622087D02*
X1029527Y1623071D01*
G01X1029586Y1623602D02*
X1030511Y1622677D01*
G01X1029527Y1628071D02*
X1030511Y1627087D01*
G01X1029586Y1628602D02*
X1030511Y1627677D01*
G01X1034508Y1635236D02*
X1033281Y1634528D01*
G01X1030511Y1640118D02*
X1029527Y1639134D01*
G01X1030511Y1639528D02*
X1029586Y1638602D01*
G01X1030511Y1635118D02*
X1029527Y1634134D01*
G01X1029586Y1633602D02*
X1030511Y1634528D01*
G01X1019290Y1637087D02*
Y1635118D01*
G01Y1640118D02*
Y1637087D01*
G01Y1635118D02*
Y1632087D01*
G01X1028484Y1635118D02*
Y1637087D01*
G01X1028727D02*
Y1635118D01*
G01X1029133Y1637087D02*
Y1635118D01*
G01X1030511Y1637677D02*
Y1634528D01*
G01Y1632087D02*
X1079290D01*
G01X1030511Y1632677D02*
X1048030D01*
G01X1030314Y1632874D02*
X1029527D01*
G01X1030314Y1634331D02*
X1029527D01*
G01X1048030Y1634528D02*
X1030511D01*
G01X1079290Y1635118D02*
X1030511D01*
G01Y1637087D02*
X1079290D01*
G01X1048030Y1637677D02*
X1030511D01*
G01X1029527Y1637874D02*
X1030314D01*
G01Y1639331D02*
X1029527D01*
G01X1033281Y1632677D02*
X1034508Y1631969D01*
G01X1033281Y1637677D02*
X1034508Y1636969D01*
G01X1029527Y1633071D02*
X1030511Y1632087D01*
G01X1029586Y1633602D02*
X1030511Y1632677D01*
G01X1029527Y1638071D02*
X1030511Y1637087D01*
G01X1029586Y1638602D02*
X1030511Y1637677D01*
G01X1035983Y1577441D02*
Y1567205D01*
G01Y1557441D02*
Y1567205D01*
G01X1036110Y1571161D02*
Y1563484D01*
G01X1036263Y1567103D02*
Y1557543D01*
G01Y1567103D02*
Y1577543D01*
G01X1036527Y1563091D02*
Y1561555D01*
G01X1036677Y1563091D02*
Y1561555D01*
G01X1036771Y1558386D02*
Y1566260D01*
G01X1040708Y1561398D02*
Y1563248D01*
G01X1039920Y1559370D02*
X1036771D01*
G01X1037114Y1560965D02*
X1072854D01*
G01X1037164Y1561398D02*
X1079290D01*
G01X1036677Y1561555D02*
X1036527D01*
G01X1036677Y1563091D02*
X1036527D01*
G01X1079290Y1563248D02*
X1037164D01*
G01X1037114Y1563681D02*
X1072854D01*
G01X1039920Y1565276D02*
X1036771D01*
G01X1035786Y1557402D02*
G03X1036771Y1558386I1J984D01*
G01Y1566260D02*
G03X1035786Y1567244I-984J0D01*
G01X1036768Y1563569D02*
G03X1036674Y1563484I349J-481D01*
G01Y1561161D02*
G03X1036768Y1561077I440J398D01*
G01X1037114Y1563681D02*
G03X1036951Y1563658I0J-592D01*
G01D02*
G03X1036800Y1563591I161J-567D01*
G01D02*
G03X1036768Y1563569I317J-496D01*
G01X1036771Y1561791D02*
G03X1037164Y1561398I394J1D01*
G01Y1563248D02*
G03X1036771Y1562854I1J-394D01*
G01X1036762Y1561250D02*
G03X1036850Y1561137I509J305D01*
G01Y1563508D02*
G03X1036762Y1563396I419J-420D01*
G01X1037266Y1563681D02*
G03X1037117Y1563662I0J-592D01*
G01D02*
G03X1037039Y1563635I153J-569D01*
G01X1036723Y1561328D02*
G03X1036762Y1561250I544J223D01*
G01Y1563396D02*
G03X1036723Y1563318I505J-301D01*
G01X1035983Y1590965D02*
Y1587205D01*
G01Y1577441D02*
Y1587205D01*
G01X1036110Y1590965D02*
Y1583484D01*
G01Y1581161D02*
Y1573484D01*
G01X1036263Y1587103D02*
Y1577543D01*
G01Y1587103D02*
Y1590965D01*
G01X1036527Y1583091D02*
Y1581555D01*
G01Y1573091D02*
Y1571555D01*
G01X1036677Y1583091D02*
Y1581555D01*
G01Y1573091D02*
Y1571555D01*
G01X1036771Y1571791D02*
Y1572854D01*
G01Y1578386D02*
Y1586260D01*
G01X1040708Y1571398D02*
Y1573248D01*
G01Y1581398D02*
Y1583248D01*
G01X1037114Y1570965D02*
X1072854D01*
G01X1037164Y1571398D02*
X1079290D01*
G01X1036677Y1571555D02*
X1036527D01*
G01X1036677Y1573091D02*
X1036527D01*
G01X1037164Y1573248D02*
X1079290D01*
G01X1037114Y1573681D02*
X1072854D01*
G01X1039920Y1579370D02*
X1036771D01*
G01X1037114Y1580965D02*
X1072854D01*
G01X1037164Y1581398D02*
X1079290D01*
G01X1036677Y1581555D02*
X1036527D01*
G01X1036677Y1583091D02*
X1036527D01*
G01X1079290Y1583248D02*
X1037164D01*
G01X1037114Y1583681D02*
X1072854D01*
G01X1036771Y1585276D02*
X1039920D01*
G01X1035786Y1577402D02*
G03X1036771Y1578386I1J984D01*
G01Y1586260D02*
G03X1035786Y1587244I-984J0D01*
G01X1036771Y1571791D02*
G03X1037164Y1571398I394J1D01*
G01X1036800Y1573591D02*
G03X1036675Y1573484I320J-501D01*
G01X1036768Y1583569D02*
G03X1036674Y1583484I349J-481D01*
G01Y1581161D02*
G03X1036768Y1581077I440J398D01*
G01X1037114Y1573681D02*
G03X1036951Y1573658I0J-592D01*
G01X1037114Y1583681D02*
G03X1036951Y1583658I0J-592D01*
G01Y1573658D02*
G03X1036800Y1573591I161J-567D01*
G01X1036951Y1583658D02*
G03X1036800Y1583591I161J-567D01*
G01D02*
G03X1036768Y1583569I317J-496D01*
G01X1036771Y1581791D02*
G03X1037164Y1581398I394J1D01*
G01Y1583248D02*
G03X1036771Y1582854I1J-394D01*
G01X1037164Y1573248D02*
G03X1036771Y1572854I1J-394D01*
G01X1036762Y1581250D02*
G03X1036850Y1581137I509J305D01*
G01Y1583508D02*
G03X1036762Y1583396I419J-420D01*
G01X1037266Y1583681D02*
G03X1037117Y1583662I0J-592D01*
G01X1037266Y1573681D02*
G03X1037117Y1573662I0J-592D01*
G01Y1583662D02*
G03X1037039Y1583635I153J-569D01*
G01X1037117Y1573662D02*
G03X1037039Y1573635I153J-569D01*
G01X1036723Y1581328D02*
G03X1036762Y1581250I544J223D01*
G01Y1583396D02*
G03X1036723Y1583318I505J-301D01*
G01X1035983Y1610965D02*
Y1607205D01*
G01Y1597441D02*
Y1593681D01*
G01Y1597441D02*
Y1607205D01*
G01X1036110Y1610965D02*
Y1603484D01*
G01Y1601161D02*
Y1593681D01*
G01X1036263Y1607103D02*
Y1597543D01*
G01D02*
Y1593681D01*
G01Y1607103D02*
Y1610965D01*
G01X1036527Y1603091D02*
Y1601555D01*
G01X1036677D02*
Y1603091D01*
G01X1036771Y1598386D02*
Y1606260D01*
G01X1040708Y1601398D02*
Y1603248D01*
G01X1039920Y1591398D02*
X1079290D01*
G01Y1593248D02*
X1039920D01*
G01Y1599370D02*
X1036771D01*
G01X1037114Y1600965D02*
X1072854D01*
G01X1037164Y1601398D02*
X1079290D01*
G01X1036677Y1601555D02*
X1036527D01*
G01X1036677Y1603091D02*
X1036527D01*
G01X1079290Y1603248D02*
X1037164D01*
G01X1037114Y1603681D02*
X1072854D01*
G01X1039920Y1605276D02*
X1036771D01*
G01X1035786Y1597402D02*
G03X1036771Y1598386I1J984D01*
G01Y1606260D02*
G03X1035786Y1607244I-984J0D01*
G01X1036768Y1603569D02*
G03X1036674Y1603484I349J-481D01*
G01Y1601161D02*
G03X1036768Y1601077I440J398D01*
G01X1036830Y1603488D02*
G03X1036762Y1603396I441J-397D01*
G01Y1601250D02*
G03X1036850Y1601137I509J305D01*
G01X1037114Y1603681D02*
G03X1036951Y1603658I0J-592D01*
G01X1037266Y1603681D02*
G03X1037117Y1603662I0J-592D01*
G01X1036951Y1603658D02*
G03X1036800Y1603591I161J-567D01*
G01X1037117Y1603662D02*
G03X1037039Y1603635I153J-569D01*
G01X1036800Y1603591D02*
G03X1036768Y1603569I317J-496D01*
G01X1036723Y1601328D02*
G03X1036762Y1601250I544J223D01*
G01Y1603396D02*
G03X1036723Y1603318I505J-301D01*
G01X1036771Y1601791D02*
G03X1037164Y1601398I394J1D01*
G01Y1603248D02*
G03X1036771Y1602854I1J-394D01*
G01X1041201Y1630295D02*
X1040145Y1629685D01*
G01X1041201Y1625295D02*
X1040145Y1624685D01*
G01X1041201Y1620295D02*
X1040145Y1619685D01*
G01X1035826Y1619606D02*
Y1619724D01*
G01Y1624606D02*
Y1624724D01*
G01Y1622480D02*
Y1622598D01*
G01Y1627480D02*
Y1627598D01*
G01Y1629606D02*
Y1629724D01*
G01X1043267Y1631831D02*
Y1630374D01*
G01Y1626831D02*
Y1625374D01*
G01Y1621831D02*
Y1620374D01*
G01X1044204Y1631831D02*
Y1630374D01*
G01Y1626831D02*
Y1625374D01*
G01Y1621831D02*
Y1620374D01*
G01X1044766Y1631831D02*
Y1630374D01*
G01Y1626831D02*
Y1625374D01*
G01Y1621831D02*
Y1620374D01*
G01X1048030Y1632677D02*
Y1629528D01*
G01Y1619528D02*
Y1622677D01*
G01Y1624528D02*
Y1627677D01*
G01X1049999Y1632087D02*
Y1630118D01*
G01Y1627087D02*
Y1625118D01*
G01Y1622087D02*
Y1620118D01*
G01X1078306Y1611398D02*
X1039920D01*
G01X1039850Y1619606D02*
X1035826D01*
G01X1035235Y1620315D02*
X1034803D01*
G01X1041496Y1620374D02*
X1075994D01*
G01X1041496Y1621831D02*
X1075994D01*
G01X1034803Y1621890D02*
X1035235D01*
G01X1035826Y1622598D02*
X1039850D01*
G01Y1624606D02*
X1035826D01*
G01X1035235Y1625315D02*
X1034803D01*
G01X1041496Y1625374D02*
X1075994D01*
G01X1041496Y1626831D02*
X1075994D01*
G01X1034803Y1626890D02*
X1035235D01*
G01X1035826Y1627598D02*
X1039850D01*
G01Y1629606D02*
X1035826D01*
G01X1035235Y1630315D02*
X1034803D01*
G01X1041496Y1630374D02*
X1075994D01*
G01X1040145Y1622519D02*
X1041201Y1621910D01*
G01X1040145Y1627519D02*
X1041201Y1626910D01*
G01X1034803Y1625315D02*
G03X1034508Y1625236I0J-591D01*
G01X1035826Y1624724D02*
G03X1035235Y1625315I-591J0D01*
G01Y1626890D02*
G03X1035826Y1627480I0J591D01*
G01X1034508Y1626969D02*
G03X1034803Y1626890I295J511D01*
G01Y1620315D02*
G03X1034508Y1620236I0J-591D01*
G01X1035826Y1619724D02*
G03X1035235Y1620315I-591J0D01*
G01Y1621890D02*
G03X1035826Y1622480I0J591D01*
G01X1034508Y1621969D02*
G03X1034803Y1621890I295J511D01*
G01Y1630315D02*
G03X1034508Y1630236I0J-591D01*
G01X1035826Y1629724D02*
G03X1035235Y1630315I-591J0D01*
G01X1039850Y1624606D02*
G03X1040145Y1624685I0J591D01*
G01X1041496Y1625374D02*
G03X1041201Y1625295I0J-590D01*
G01X1039850Y1619606D02*
G03X1040145Y1619685I0J591D01*
G01X1041496Y1620374D02*
G03X1041201Y1620295I0J-590D01*
G01Y1621910D02*
G03X1041496Y1621831I295J511D01*
G01X1040145Y1622519D02*
G03X1039850Y1622598I-295J-511D01*
G01Y1629606D02*
G03X1040145Y1629685I0J591D01*
G01Y1627519D02*
G03X1039850Y1627598I-295J-511D01*
G01X1041496Y1630374D02*
G03X1041201Y1630295I0J-590D01*
G01Y1626910D02*
G03X1041496Y1626831I295J511D01*
G01X1041201Y1635295D02*
X1040145Y1634685D01*
G01X1035826Y1632480D02*
Y1632598D01*
G01Y1634606D02*
Y1634724D01*
G01Y1637480D02*
Y1637598D01*
G01X1043267Y1636831D02*
Y1635374D01*
G01X1044204Y1636831D02*
Y1635374D01*
G01X1044766Y1636831D02*
Y1635374D01*
G01X1048030Y1634528D02*
Y1637677D01*
G01X1049999Y1637087D02*
Y1635118D01*
G01X1041496Y1631831D02*
X1075994D01*
G01X1034803Y1631890D02*
X1035235D01*
G01X1035826Y1632598D02*
X1039850D01*
G01Y1634606D02*
X1035826D01*
G01X1035235Y1635315D02*
X1034803D01*
G01X1041496Y1635374D02*
X1075994D01*
G01X1041496Y1636831D02*
X1075994D01*
G01X1034803Y1636890D02*
X1035235D01*
G01X1035826Y1637598D02*
X1039850D01*
G01X1040145Y1632519D02*
X1041201Y1631910D01*
G01X1040145Y1637519D02*
X1041201Y1636910D01*
G01X1034803Y1635315D02*
G03X1034508Y1635236I0J-591D01*
G01Y1636969D02*
G03X1034803Y1636890I295J511D01*
G01X1034508Y1631969D02*
G03X1034803Y1631890I295J511D01*
G01X1035826Y1634724D02*
G03X1035235Y1635315I-591J0D01*
G01Y1636890D02*
G03X1035826Y1637480I0J591D01*
G01X1035235Y1631890D02*
G03X1035826Y1632480I0J591D01*
G01X1039850Y1634606D02*
G03X1040145Y1634685I0J591D01*
G01Y1637519D02*
G03X1039850Y1637598I-295J-511D01*
G01X1040145Y1632519D02*
G03X1039850Y1632598I-295J-511D01*
G01X1041496Y1635374D02*
G03X1041201Y1635295I0J-590D01*
G01Y1636910D02*
G03X1041496Y1636831I295J511D01*
G01X1041201Y1631910D02*
G03X1041496Y1631831I295J511D01*
G01X1053700Y1568799D02*
Y1565846D01*
G01X1066319Y1570965D02*
Y1563681D01*
G01X1066472Y1570965D02*
Y1569783D01*
G01Y1564862D02*
Y1563681D01*
G01Y1560965D02*
Y1559783D01*
G01Y1564862D02*
Y1569783D01*
G01X1067112D02*
Y1564862D01*
G01D02*
Y1563681D01*
G01Y1559783D02*
Y1560965D01*
G01Y1569783D02*
Y1570965D01*
G01X1067479Y1571398D02*
Y1569783D01*
G01Y1564862D02*
Y1563248D01*
G01Y1561398D02*
Y1559783D01*
G01X1067921Y1570965D02*
Y1563681D01*
G01X1068464Y1571398D02*
Y1569783D01*
G01Y1561398D02*
Y1559783D01*
G01Y1563248D02*
Y1564862D01*
G01X1069448Y1565846D02*
Y1568799D01*
G01X1069921Y1570965D02*
Y1563681D01*
G01X1073375Y1569980D02*
Y1564665D01*
G01X1068464Y1559783D02*
X1054684D01*
G01X1073779Y1559980D02*
X1073375D01*
G01X1073779Y1564665D02*
X1073375D01*
G01X1054684Y1564862D02*
X1068464D01*
G01Y1569783D02*
X1054684D01*
G01X1073779Y1569980D02*
X1073375D01*
G01X1053700Y1565846D02*
G03X1054684Y1564862I984J0D01*
G01Y1569783D02*
G03X1053700Y1568799I0J-984D01*
G01X1054684Y1559783D02*
G03X1053700Y1558799I0J-984D01*
G01X1068464Y1564862D02*
G03X1069448Y1565846I0J984D01*
G01Y1568799D02*
G03X1068464Y1569783I-984J0D01*
G01X1069448Y1558799D02*
G03X1068464Y1559783I-984J0D01*
G01X1053700Y1588799D02*
Y1585846D01*
G01Y1578799D02*
Y1575846D01*
G01X1066319Y1590965D02*
Y1583681D01*
G01Y1580965D02*
Y1573681D01*
G01X1066472Y1590965D02*
Y1589783D01*
G01Y1584862D02*
Y1583681D01*
G01Y1580965D02*
Y1579783D01*
G01Y1574862D02*
Y1573681D01*
G01Y1574862D02*
Y1579783D01*
G01Y1584862D02*
Y1589783D01*
G01X1067112D02*
Y1584862D01*
G01D02*
Y1583681D01*
G01Y1579783D02*
Y1574862D01*
G01D02*
Y1573681D01*
G01Y1579783D02*
Y1580965D01*
G01Y1589783D02*
Y1590965D01*
G01X1067479Y1591398D02*
Y1589783D01*
G01Y1584862D02*
Y1583248D01*
G01Y1581398D02*
Y1579783D01*
G01Y1574862D02*
Y1573248D01*
G01X1067921Y1590965D02*
Y1583681D01*
G01Y1580965D02*
Y1573681D01*
G01X1068464Y1591398D02*
Y1589783D01*
G01Y1581398D02*
Y1579783D01*
G01Y1574862D02*
Y1573248D01*
G01Y1583248D02*
Y1584862D01*
G01X1069448Y1575846D02*
Y1578799D01*
G01Y1585846D02*
Y1588799D01*
G01X1069921Y1590965D02*
Y1583681D01*
G01Y1580965D02*
Y1573681D01*
G01X1073375Y1589980D02*
Y1584665D01*
G01Y1579980D02*
Y1574665D01*
G01X1073779D02*
X1073375D01*
G01X1054684Y1574862D02*
X1068464D01*
G01Y1579783D02*
X1054684D01*
G01X1073779Y1579980D02*
X1073375D01*
G01X1073779Y1584665D02*
X1073375D01*
G01X1054684Y1584862D02*
X1068464D01*
G01Y1589783D02*
X1054684D01*
G01X1073779Y1589980D02*
X1073375D01*
G01X1053700Y1585846D02*
G03X1054684Y1584862I984J0D01*
G01Y1589783D02*
G03X1053700Y1588799I0J-984D01*
G01Y1575846D02*
G03X1054684Y1574862I984J0D01*
G01Y1579783D02*
G03X1053700Y1578799I0J-984D01*
G01X1068464Y1584862D02*
G03X1069448Y1585846I0J984D01*
G01Y1588799D02*
G03X1068464Y1589783I-984J0D01*
G01Y1574862D02*
G03X1069448Y1575846I0J984D01*
G01Y1578799D02*
G03X1068464Y1579783I-984J0D01*
G01X1053700Y1608799D02*
Y1605846D01*
G01Y1598799D02*
Y1595846D01*
G01X1066319Y1610965D02*
Y1603681D01*
G01Y1600965D02*
Y1593681D01*
G01X1066472Y1610965D02*
Y1609783D01*
G01Y1604862D02*
Y1603681D01*
G01Y1600965D02*
Y1599783D01*
G01Y1594862D02*
Y1593681D01*
G01Y1594862D02*
Y1599783D01*
G01Y1604862D02*
Y1609783D01*
G01X1067112D02*
Y1604862D01*
G01D02*
Y1603681D01*
G01Y1599783D02*
Y1594862D01*
G01D02*
Y1593681D01*
G01Y1599783D02*
Y1600965D01*
G01Y1609783D02*
Y1610965D01*
G01X1067479Y1611398D02*
Y1609783D01*
G01Y1604862D02*
Y1603248D01*
G01Y1601398D02*
Y1599783D01*
G01Y1594862D02*
Y1593248D01*
G01X1067921Y1610965D02*
Y1603681D01*
G01Y1600965D02*
Y1593681D01*
G01X1068464Y1611398D02*
Y1609783D01*
G01Y1604862D02*
Y1603248D01*
G01Y1601398D02*
Y1599783D01*
G01Y1594862D02*
Y1593248D01*
G01X1069448Y1595846D02*
Y1598799D01*
G01Y1605846D02*
Y1608799D01*
G01X1069921Y1610965D02*
Y1603681D01*
G01Y1593681D02*
Y1600965D01*
G01X1073375Y1609980D02*
Y1604665D01*
G01Y1594665D02*
Y1599980D01*
G01X1073779Y1594665D02*
X1073375D01*
G01X1054684Y1594862D02*
X1068464D01*
G01Y1599783D02*
X1054684D01*
G01X1073779Y1599980D02*
X1073375D01*
G01X1073779Y1604665D02*
X1073375D01*
G01X1054684Y1604862D02*
X1068464D01*
G01Y1609783D02*
X1054684D01*
G01X1073779Y1609980D02*
X1073375D01*
G01X1053700Y1595846D02*
G03X1054684Y1594862I984J0D01*
G01Y1599783D02*
G03X1053700Y1598799I0J-984D01*
G01X1068464Y1594862D02*
G03X1069448Y1595846I0J984D01*
G01Y1598799D02*
G03X1068464Y1599783I-984J0D01*
G01X1053700Y1605846D02*
G03X1054684Y1604862I984J0D01*
G01X1068464D02*
G03X1069448Y1605846I0J984D01*
G01Y1608799D02*
G03X1068464Y1609783I-984J0D01*
G01X1054684D02*
G03X1053700Y1608799I0J-984D01*
G01X1054078Y1631831D02*
Y1630374D01*
G01Y1626831D02*
Y1625374D01*
G01Y1621831D02*
Y1620374D01*
G01X1054640Y1631831D02*
Y1630374D01*
G01Y1626831D02*
Y1625374D01*
G01Y1621831D02*
Y1620374D01*
G01X1068857Y1631831D02*
Y1630374D01*
G01Y1626831D02*
Y1625374D01*
G01Y1621831D02*
Y1620374D01*
G01X1069448Y1631831D02*
Y1630374D01*
G01Y1626831D02*
Y1625374D01*
G01Y1621831D02*
Y1620374D01*
G01X1071225Y1631831D02*
Y1630374D01*
G01Y1626831D02*
Y1625374D01*
G01Y1621831D02*
Y1620374D01*
G01X1071815Y1631831D02*
Y1630374D01*
G01Y1626831D02*
Y1625374D01*
G01Y1621831D02*
Y1620374D01*
G01X1072799Y1631831D02*
Y1630374D01*
G01Y1626831D02*
Y1625374D01*
G01Y1621831D02*
Y1620374D01*
G01X1054078Y1636831D02*
Y1635374D01*
G01X1054640Y1636831D02*
Y1635374D01*
G01X1068857Y1636831D02*
Y1635374D01*
G01X1069448Y1636831D02*
Y1635374D01*
G01X1071225Y1636831D02*
Y1635374D01*
G01X1071815Y1636831D02*
Y1635374D01*
G01X1072799Y1636831D02*
Y1635374D01*
G01X1073779Y1569980D02*
Y1564665D01*
G01X1076731Y1563248D02*
Y1561398D01*
G01X1078714Y1563248D02*
Y1561398D01*
G01X1073779Y1589980D02*
Y1584665D01*
G01Y1579980D02*
Y1574665D01*
G01X1076731Y1583248D02*
Y1581398D01*
G01Y1573248D02*
Y1571398D01*
G01X1078714Y1583248D02*
Y1581398D01*
G01Y1573248D02*
Y1571398D01*
G01X1073779Y1609980D02*
Y1604665D01*
G01Y1594665D02*
Y1599980D01*
G01X1075944Y1593248D02*
Y1591398D01*
G01X1076731Y1603248D02*
Y1601398D01*
G01X1078714Y1603248D02*
Y1601398D01*
G01Y1593248D02*
Y1591398D01*
G01X1076534Y1630571D02*
X1075994Y1630374D01*
G01X1076534Y1625571D02*
X1075994Y1625374D01*
G01X1076534Y1620571D02*
X1075994Y1620374D01*
G01X1079290Y1612382D02*
X1078306Y1611398D01*
G01X1073779Y1620118D02*
Y1622087D01*
G01Y1625118D02*
Y1627087D01*
G01Y1630118D02*
Y1632087D01*
G01X1075156D02*
Y1630118D01*
G01Y1622087D02*
Y1620118D01*
G01Y1625118D02*
Y1627087D01*
G01X1075944Y1614744D02*
Y1686811D01*
G01X1076534Y1631634D02*
Y1630571D01*
G01Y1626634D02*
Y1625571D01*
G01Y1621634D02*
Y1620571D01*
G01X1078306Y1632087D02*
Y1630118D01*
G01Y1627087D02*
Y1625118D01*
G01Y1622087D02*
Y1620118D01*
G01X1078714Y1630118D02*
Y1627087D01*
G01Y1625118D02*
Y1622087D01*
G01Y1620118D02*
Y1614337D01*
G01X1078306Y1614744D02*
X1075944D01*
G01X1075994Y1621831D02*
X1076534Y1621634D01*
G01X1075994Y1626831D02*
X1076534Y1626634D01*
G01X1078306Y1614744D02*
X1079290Y1613760D01*
G01X1076534Y1635571D02*
X1075994Y1635374D01*
G01X1073779Y1635118D02*
Y1637087D01*
G01X1075156Y1635118D02*
Y1637087D01*
G01X1076534Y1636634D02*
Y1635571D01*
G01X1078306Y1637087D02*
Y1635118D01*
G01X1078714Y1640118D02*
Y1637087D01*
G01Y1635118D02*
Y1632087D01*
G01X1075994Y1631831D02*
X1076534Y1631634D01*
G01X1075994Y1636831D02*
X1076534Y1636634D01*
G01X1008424Y1679449D02*
Y1708976D01*
G01X1006456Y1679449D02*
X1020380D01*
G01X1026968Y1694213D02*
G03I-7678J0D01*
G01X1026574D02*
G03I-7284J0D01*
G01X1032046Y1708976D02*
X1006456D01*
G01X1034508Y1650236D02*
X1033281Y1649528D01*
G01X1034508Y1645236D02*
X1033281Y1644528D01*
G01X1034508Y1640236D02*
X1033281Y1639528D01*
G01X1030511Y1650118D02*
X1029527Y1649134D01*
G01X1030511Y1649528D02*
X1029586Y1648602D01*
G01X1030511Y1645118D02*
X1029527Y1644134D01*
G01X1029586Y1643602D02*
X1030511Y1644528D01*
G01X1019290Y1652087D02*
Y1650118D01*
G01Y1647087D02*
Y1645118D01*
G01Y1642087D02*
Y1640118D01*
G01Y1650118D02*
Y1647087D01*
G01Y1645118D02*
Y1642087D01*
G01X1028484Y1640118D02*
Y1642087D01*
G01Y1645118D02*
Y1647087D01*
G01Y1650118D02*
Y1652087D01*
G01X1028727D02*
Y1650118D01*
G01Y1647087D02*
Y1645118D01*
G01Y1642087D02*
Y1640118D01*
G01X1029133Y1652087D02*
Y1650118D01*
G01Y1647087D02*
Y1645118D01*
G01Y1642087D02*
Y1640118D01*
G01X1030511Y1652677D02*
Y1649528D01*
G01Y1647677D02*
Y1644528D01*
G01Y1642677D02*
Y1639528D01*
G01D02*
X1048030D01*
G01X1079290Y1640118D02*
X1030511D01*
G01Y1642087D02*
X1079290D01*
G01X1030511Y1642677D02*
X1048030D01*
G01X1030314Y1642874D02*
X1029527D01*
G01X1030314Y1644331D02*
X1029527D01*
G01X1048030Y1644528D02*
X1030511D01*
G01X1079290Y1645118D02*
X1030511D01*
G01Y1647087D02*
X1079290D01*
G01X1048030Y1647677D02*
X1030511D01*
G01X1029527Y1647874D02*
X1030314D01*
G01Y1649331D02*
X1029527D01*
G01X1030511Y1649528D02*
X1048030D01*
G01X1079290Y1650118D02*
X1030511D01*
G01X1033281Y1642677D02*
X1034508Y1641969D01*
G01X1033281Y1647677D02*
X1034508Y1646969D01*
G01X1029527Y1643071D02*
X1030511Y1642087D01*
G01X1029586Y1643602D02*
X1030511Y1642677D01*
G01X1029527Y1648071D02*
X1030511Y1647087D01*
G01X1029586Y1648602D02*
X1030511Y1647677D01*
G01X1034508Y1670236D02*
X1033281Y1669528D01*
G01X1034508Y1665236D02*
X1033281Y1664528D01*
G01X1034508Y1660236D02*
X1033281Y1659528D01*
G01X1034508Y1655236D02*
X1033281Y1654528D01*
G01X1030511Y1670118D02*
X1029527Y1669134D01*
G01X1030511Y1669528D02*
X1029586Y1668602D01*
G01X1030511Y1665118D02*
X1029527Y1664134D01*
G01X1029586Y1663602D02*
X1030511Y1664528D01*
G01Y1660118D02*
X1029527Y1659134D01*
G01X1030511Y1659528D02*
X1029586Y1658602D01*
G01X1030511Y1655118D02*
X1029527Y1654134D01*
G01X1029586Y1653602D02*
X1030511Y1654528D01*
G01X1019290Y1672087D02*
Y1670118D01*
G01Y1667087D02*
Y1665118D01*
G01Y1662087D02*
Y1660118D01*
G01Y1657087D02*
Y1655118D01*
G01Y1670118D02*
Y1667087D01*
G01Y1665118D02*
Y1662087D01*
G01Y1660118D02*
Y1657087D01*
G01Y1655118D02*
Y1652087D01*
G01X1028484Y1655118D02*
Y1657087D01*
G01Y1660118D02*
Y1662087D01*
G01Y1665118D02*
Y1667087D01*
G01Y1670118D02*
Y1672087D01*
G01X1028727D02*
Y1670118D01*
G01Y1667087D02*
Y1665118D01*
G01Y1662087D02*
Y1660118D01*
G01Y1657087D02*
Y1655118D01*
G01X1029133Y1672087D02*
Y1670118D01*
G01Y1667087D02*
Y1665118D01*
G01Y1662087D02*
Y1660118D01*
G01Y1657087D02*
Y1655118D01*
G01X1030511Y1672677D02*
Y1669528D01*
G01Y1667677D02*
Y1664528D01*
G01Y1662677D02*
Y1659528D01*
G01Y1657677D02*
Y1654528D01*
G01Y1652087D02*
X1079290D01*
G01X1030511Y1652677D02*
X1048030D01*
G01X1030314Y1652874D02*
X1029527D01*
G01X1030314Y1654331D02*
X1029527D01*
G01X1048030Y1654528D02*
X1030511D01*
G01X1079290Y1655118D02*
X1030511D01*
G01Y1657087D02*
X1079290D01*
G01X1048030Y1657677D02*
X1030511D01*
G01X1029527Y1657874D02*
X1030314D01*
G01Y1659331D02*
X1029527D01*
G01X1048030Y1659528D02*
X1030511D01*
G01X1079290Y1660118D02*
X1030511D01*
G01Y1662087D02*
X1079290D01*
G01X1048030Y1662677D02*
X1030511D01*
G01X1029527Y1662874D02*
X1030314D01*
G01Y1664331D02*
X1029527D01*
G01X1048030Y1664528D02*
X1030511D01*
G01X1079290Y1665118D02*
X1030511D01*
G01Y1667087D02*
X1079290D01*
G01X1048030Y1667677D02*
X1030511D01*
G01X1029527Y1667874D02*
X1030314D01*
G01Y1669331D02*
X1029527D01*
G01X1030511Y1669528D02*
X1048030D01*
G01X1079290Y1670118D02*
X1030511D01*
G01X1033281Y1652677D02*
X1034508Y1651969D01*
G01X1033281Y1657677D02*
X1034508Y1656969D01*
G01X1033281Y1662677D02*
X1034508Y1661969D01*
G01X1033281Y1667677D02*
X1034508Y1666969D01*
G01X1029527Y1653071D02*
X1030511Y1652087D01*
G01X1029586Y1653602D02*
X1030511Y1652677D01*
G01X1029527Y1658071D02*
X1030511Y1657087D01*
G01X1029586Y1658602D02*
X1030511Y1657677D01*
G01Y1662087D02*
X1029527Y1663071D01*
G01X1029586Y1663602D02*
X1030511Y1662677D01*
G01X1029527Y1668071D02*
X1030511Y1667087D01*
G01X1029586Y1668602D02*
X1030511Y1667677D01*
G01X1034508Y1675236D02*
X1033281Y1674528D01*
G01X1029527Y1681417D02*
X1033464Y1685354D01*
G01X1029527Y1674134D02*
X1030511Y1675118D01*
G01Y1674528D02*
X1029586Y1673602D01*
G01X1019290Y1676496D02*
Y1675118D01*
G01D02*
Y1672087D01*
G01X1028484Y1675118D02*
Y1677087D01*
G01X1028727D02*
Y1675118D01*
G01X1029133Y1677087D02*
Y1675118D01*
G01X1029527Y1681811D02*
Y1679449D01*
G01X1030511Y1674528D02*
Y1677677D01*
G01X1033464Y1988189D02*
Y1685354D01*
G01X1030511Y1672087D02*
X1079290D01*
G01X1030511Y1672677D02*
X1048030D01*
G01X1030314Y1672874D02*
X1029527D01*
G01X1030314Y1674331D02*
X1029527D01*
G01X1048030Y1674528D02*
X1030511D01*
G01X1079290Y1675118D02*
X1030511D01*
G01Y1677087D02*
X1079290D01*
G01X1048030Y1677677D02*
X1030511D01*
G01X1029527Y1677874D02*
X1030314D01*
G01X1020380Y1679449D02*
X1034015D01*
G01X1029527Y1681417D02*
X1024212D01*
G01X1033281Y1672677D02*
X1034508Y1671969D01*
G01X1033281Y1677677D02*
X1034508Y1676969D01*
G01X1029527Y1673071D02*
X1030511Y1672087D01*
G01X1029586Y1673602D02*
X1030511Y1672677D01*
G01X1029527Y1678071D02*
X1030511Y1677087D01*
G01Y1677677D02*
X1029527Y1678661D01*
G01X1019326Y1677087D02*
G03X1019290Y1676496I4885J-594D01*
G01X1024212Y1681417D02*
G03X1019326Y1677087I0J-4921D01*
G01X1033480Y1708356D02*
G03X1032046Y1708976I-1434J-1348D01*
G01X1034015Y1707008D02*
G03X1033480Y1708356I-1968J-1D01*
G01X1041201Y1650295D02*
X1040145Y1649685D01*
G01X1041201Y1645295D02*
X1040145Y1644685D01*
G01X1041201Y1640295D02*
X1040145Y1639685D01*
G01X1035826Y1639606D02*
Y1639724D01*
G01Y1642480D02*
Y1642598D01*
G01Y1644606D02*
Y1644724D01*
G01Y1647480D02*
Y1647598D01*
G01Y1649606D02*
Y1649724D01*
G01X1043267Y1651831D02*
Y1650374D01*
G01Y1646831D02*
Y1645374D01*
G01Y1641831D02*
Y1640374D01*
G01X1044204Y1651831D02*
Y1650374D01*
G01Y1646831D02*
Y1645374D01*
G01Y1641831D02*
Y1640374D01*
G01X1044766Y1651831D02*
Y1650374D01*
G01Y1646831D02*
Y1645374D01*
G01Y1641831D02*
Y1640374D01*
G01X1048030Y1639528D02*
Y1642677D01*
G01Y1644528D02*
Y1647677D01*
G01Y1649528D02*
Y1652677D01*
G01X1049999Y1652087D02*
Y1650118D01*
G01Y1647087D02*
Y1645118D01*
G01Y1642087D02*
Y1640118D01*
G01X1039850Y1639606D02*
X1035826D01*
G01X1035235Y1640315D02*
X1034803D01*
G01X1041496Y1640374D02*
X1075994D01*
G01X1041496Y1641831D02*
X1075994D01*
G01X1034803Y1641890D02*
X1035235D01*
G01X1035826Y1642598D02*
X1039850D01*
G01Y1644606D02*
X1035826D01*
G01X1035235Y1645315D02*
X1034803D01*
G01X1041496Y1645374D02*
X1075994D01*
G01X1041496Y1646831D02*
X1075994D01*
G01X1034803Y1646890D02*
X1035235D01*
G01X1035826Y1647598D02*
X1039850D01*
G01Y1649606D02*
X1035826D01*
G01X1035235Y1650315D02*
X1034803D01*
G01X1041496Y1650374D02*
X1075994D01*
G01X1040145Y1642519D02*
X1041201Y1641910D01*
G01X1040145Y1647519D02*
X1041201Y1646910D01*
G01X1034803Y1640315D02*
G03X1034508Y1640236I0J-591D01*
G01X1034803Y1650315D02*
G03X1034508Y1650236I0J-591D01*
G01X1034803Y1645315D02*
G03X1034508Y1645236I0J-591D01*
G01Y1646969D02*
G03X1034803Y1646890I295J511D01*
G01X1034508Y1641969D02*
G03X1034803Y1641890I295J511D01*
G01X1035826Y1639724D02*
G03X1035235Y1640315I-591J0D01*
G01X1035826Y1649724D02*
G03X1035235Y1650315I-591J0D01*
G01X1035826Y1644724D02*
G03X1035235Y1645315I-591J0D01*
G01Y1646890D02*
G03X1035826Y1647480I0J591D01*
G01X1035235Y1641890D02*
G03X1035826Y1642480I0J591D01*
G01X1039850Y1649606D02*
G03X1040145Y1649685I0J591D01*
G01X1039850Y1644606D02*
G03X1040145Y1644685I0J591D01*
G01Y1647519D02*
G03X1039850Y1647598I-295J-511D01*
G01Y1639606D02*
G03X1040145Y1639685I0J591D01*
G01Y1642519D02*
G03X1039850Y1642598I-295J-511D01*
G01X1041496Y1650374D02*
G03X1041201Y1650295I0J-590D01*
G01X1041496Y1645374D02*
G03X1041201Y1645295I0J-590D01*
G01Y1646910D02*
G03X1041496Y1646831I295J511D01*
G01Y1640374D02*
G03X1041201Y1640295I0J-590D01*
G01Y1641910D02*
G03X1041496Y1641831I295J511D01*
G01X1041201Y1670295D02*
X1040145Y1669685D01*
G01X1041201Y1665295D02*
X1040145Y1664685D01*
G01X1041201Y1660295D02*
X1040145Y1659685D01*
G01X1041201Y1655295D02*
X1040145Y1654685D01*
G01X1035826Y1652480D02*
Y1652598D01*
G01Y1654606D02*
Y1654724D01*
G01Y1657480D02*
Y1657598D01*
G01Y1659606D02*
Y1659724D01*
G01Y1662480D02*
Y1662598D01*
G01Y1664606D02*
Y1664724D01*
G01Y1667480D02*
Y1667598D01*
G01Y1669606D02*
Y1669724D01*
G01X1043267Y1671831D02*
Y1670374D01*
G01Y1666831D02*
Y1665374D01*
G01Y1661831D02*
Y1660374D01*
G01Y1656831D02*
Y1655374D01*
G01X1044204Y1671831D02*
Y1670374D01*
G01Y1666831D02*
Y1665374D01*
G01Y1661831D02*
Y1660374D01*
G01Y1656831D02*
Y1655374D01*
G01X1044766Y1671831D02*
Y1670374D01*
G01Y1666831D02*
Y1665374D01*
G01Y1661831D02*
Y1660374D01*
G01Y1656831D02*
Y1655374D01*
G01X1048030Y1654528D02*
Y1657677D01*
G01Y1659528D02*
Y1662677D01*
G01Y1664528D02*
Y1667677D01*
G01Y1669528D02*
Y1672677D01*
G01X1049999Y1672087D02*
Y1670118D01*
G01Y1667087D02*
Y1665118D01*
G01Y1662087D02*
Y1660118D01*
G01Y1657087D02*
Y1655118D01*
G01X1041496Y1651831D02*
X1075994D01*
G01X1034803Y1651890D02*
X1035235D01*
G01X1035826Y1652598D02*
X1039850D01*
G01Y1654606D02*
X1035826D01*
G01X1035235Y1655315D02*
X1034803D01*
G01X1041496Y1655374D02*
X1075994D01*
G01X1041496Y1656831D02*
X1075994D01*
G01X1034803Y1656890D02*
X1035235D01*
G01X1035826Y1657598D02*
X1039850D01*
G01Y1659606D02*
X1035826D01*
G01X1035235Y1660315D02*
X1034803D01*
G01X1041496Y1660374D02*
X1075994D01*
G01X1041496Y1661831D02*
X1075994D01*
G01X1034803Y1661890D02*
X1035235D01*
G01X1035826Y1662598D02*
X1039850D01*
G01Y1664606D02*
X1035826D01*
G01X1035235Y1665315D02*
X1034803D01*
G01X1041496Y1665374D02*
X1075994D01*
G01X1041496Y1666831D02*
X1075994D01*
G01X1034803Y1666890D02*
X1035235D01*
G01X1035826Y1667598D02*
X1039850D01*
G01Y1669606D02*
X1035826D01*
G01X1035235Y1670315D02*
X1034803D01*
G01X1041496Y1670374D02*
X1075994D01*
G01X1040145Y1652519D02*
X1041201Y1651910D01*
G01X1040145Y1657519D02*
X1041201Y1656910D01*
G01X1040145Y1662519D02*
X1041201Y1661910D01*
G01X1040145Y1667519D02*
X1041201Y1666910D01*
G01X1034508Y1651969D02*
G03X1034803Y1651890I295J511D01*
G01X1035235D02*
G03X1035826Y1652480I0J591D01*
G01X1034803Y1665315D02*
G03X1034508Y1665236I0J-591D01*
G01X1034803Y1660315D02*
G03X1034508Y1660236I0J-591D01*
G01Y1661969D02*
G03X1034803Y1661890I295J511D01*
G01Y1655315D02*
G03X1034508Y1655236I0J-591D01*
G01Y1656969D02*
G03X1034803Y1656890I295J511D01*
G01Y1670315D02*
G03X1034508Y1670236I0J-591D01*
G01Y1666969D02*
G03X1034803Y1666890I295J511D01*
G01X1035826Y1664724D02*
G03X1035235Y1665315I-591J0D01*
G01X1035826Y1659724D02*
G03X1035235Y1660315I-591J0D01*
G01Y1661890D02*
G03X1035826Y1662480I0J591D01*
G01Y1654724D02*
G03X1035235Y1655315I-591J0D01*
G01Y1656890D02*
G03X1035826Y1657480I0J591D01*
G01Y1669724D02*
G03X1035235Y1670315I-591J0D01*
G01Y1666890D02*
G03X1035826Y1667480I0J591D01*
G01X1040145Y1652519D02*
G03X1039850Y1652598I-295J-511D01*
G01X1041201Y1651910D02*
G03X1041496Y1651831I295J511D01*
G01X1039850Y1664606D02*
G03X1040145Y1664685I0J591D01*
G01X1039850Y1659606D02*
G03X1040145Y1659685I0J591D01*
G01Y1662519D02*
G03X1039850Y1662598I-295J-511D01*
G01Y1654606D02*
G03X1040145Y1654685I0J591D01*
G01Y1657519D02*
G03X1039850Y1657598I-295J-511D01*
G01Y1669606D02*
G03X1040145Y1669685I0J591D01*
G01Y1667519D02*
G03X1039850Y1667598I-295J-511D01*
G01X1041496Y1665374D02*
G03X1041201Y1665295I0J-590D01*
G01X1041496Y1660374D02*
G03X1041201Y1660295I0J-590D01*
G01Y1661910D02*
G03X1041496Y1661831I295J511D01*
G01Y1655374D02*
G03X1041201Y1655295I0J-590D01*
G01Y1656910D02*
G03X1041496Y1656831I295J511D01*
G01Y1670374D02*
G03X1041201Y1670295I0J-590D01*
G01Y1666910D02*
G03X1041496Y1666831I295J511D01*
G01X1041201Y1675295D02*
X1040145Y1674685D01*
G01X1034015Y1679449D02*
Y1707008D01*
G01X1035826Y1672480D02*
Y1672598D01*
G01Y1674606D02*
Y1674724D01*
G01Y1677480D02*
Y1677598D01*
G01X1043267Y1676831D02*
Y1675374D01*
G01X1044204Y1676831D02*
Y1675374D01*
G01X1044766Y1676831D02*
Y1675374D01*
G01X1048030Y1674528D02*
Y1677677D01*
G01X1049999Y1677087D02*
Y1675118D01*
G01X1041496Y1671831D02*
X1075994D01*
G01X1034803Y1671890D02*
X1035235D01*
G01X1035826Y1672598D02*
X1039850D01*
G01Y1674606D02*
X1035826D01*
G01X1035235Y1675315D02*
X1034803D01*
G01X1041496Y1675374D02*
X1075994D01*
G01X1041496Y1676831D02*
X1075994D01*
G01X1034803Y1676890D02*
X1035235D01*
G01X1035826Y1677598D02*
X1039850D01*
G01X1074566Y1685433D02*
X1039920D01*
G01X1040145Y1672519D02*
X1041201Y1671910D01*
G01X1040145Y1677519D02*
X1041201Y1676910D01*
G01X1034508Y1671969D02*
G03X1034803Y1671890I295J511D01*
G01Y1675315D02*
G03X1034508Y1675236I0J-591D01*
G01Y1676969D02*
G03X1034803Y1676890I295J511D01*
G01X1035235Y1671890D02*
G03X1035826Y1672480I0J591D01*
G01Y1674724D02*
G03X1035235Y1675315I-591J0D01*
G01Y1676890D02*
G03X1035826Y1677480I0J591D01*
G01X1040145Y1672519D02*
G03X1039850Y1672598I-295J-511D01*
G01Y1674606D02*
G03X1040145Y1674685I0J591D01*
G01Y1677519D02*
G03X1039850Y1677598I-295J-511D01*
G01X1041201Y1671910D02*
G03X1041496Y1671831I295J511D01*
G01Y1675374D02*
G03X1041201Y1675295I0J-590D01*
G01Y1676910D02*
G03X1041496Y1676831I295J511D01*
G01X1079290Y1691339D02*
X1034015D01*
G01Y1693307D02*
X1079290D01*
G01X1054078Y1651831D02*
Y1650374D01*
G01Y1646831D02*
Y1645374D01*
G01Y1641831D02*
Y1640374D01*
G01X1054640Y1651831D02*
Y1650374D01*
G01Y1646831D02*
Y1645374D01*
G01Y1641831D02*
Y1640374D01*
G01X1068857Y1651831D02*
Y1650374D01*
G01Y1646831D02*
Y1645374D01*
G01Y1641831D02*
Y1640374D01*
G01X1069448Y1651831D02*
Y1650374D01*
G01Y1646831D02*
Y1645374D01*
G01Y1641831D02*
Y1640374D01*
G01X1071225Y1651831D02*
Y1650374D01*
G01Y1646831D02*
Y1645374D01*
G01Y1641831D02*
Y1640374D01*
G01X1071815Y1651831D02*
Y1650374D01*
G01Y1646831D02*
Y1645374D01*
G01Y1641831D02*
Y1640374D01*
G01X1072799Y1651831D02*
Y1650374D01*
G01Y1646831D02*
Y1645374D01*
G01Y1641831D02*
Y1640374D01*
G01X1054078Y1671831D02*
Y1670374D01*
G01Y1666831D02*
Y1665374D01*
G01Y1661831D02*
Y1660374D01*
G01Y1656831D02*
Y1655374D01*
G01X1054640Y1671831D02*
Y1670374D01*
G01Y1666831D02*
Y1665374D01*
G01Y1661831D02*
Y1660374D01*
G01Y1656831D02*
Y1655374D01*
G01X1068857Y1671831D02*
Y1670374D01*
G01Y1666831D02*
Y1665374D01*
G01Y1661831D02*
Y1660374D01*
G01Y1656831D02*
Y1655374D01*
G01X1069448Y1671831D02*
Y1670374D01*
G01Y1666831D02*
Y1665374D01*
G01Y1661831D02*
Y1660374D01*
G01Y1656831D02*
Y1655374D01*
G01X1071225Y1671831D02*
Y1670374D01*
G01Y1666831D02*
Y1665374D01*
G01Y1661831D02*
Y1660374D01*
G01Y1656831D02*
Y1655374D01*
G01X1071815Y1671831D02*
Y1670374D01*
G01Y1666831D02*
Y1665374D01*
G01Y1661831D02*
Y1660374D01*
G01Y1656831D02*
Y1655374D01*
G01X1072799Y1671831D02*
Y1670374D01*
G01Y1666831D02*
Y1665374D01*
G01Y1661831D02*
Y1660374D01*
G01Y1656831D02*
Y1655374D01*
G01X1054078Y1676831D02*
Y1675374D01*
G01X1054640Y1676831D02*
Y1675374D01*
G01X1068857Y1676831D02*
Y1675374D01*
G01X1069448Y1676831D02*
Y1675374D01*
G01X1071225Y1676831D02*
Y1675374D01*
G01X1071815Y1676831D02*
Y1675374D01*
G01X1072799Y1676831D02*
Y1675374D01*
G01X1079290Y1686220D02*
X1071416D01*
G01X1076534Y1650571D02*
X1075994Y1650374D01*
G01X1076534Y1645571D02*
X1075994Y1645374D01*
G01X1076534Y1640571D02*
X1075994Y1640374D01*
G01X1073779Y1640118D02*
Y1642087D01*
G01Y1645118D02*
Y1647087D01*
G01Y1650118D02*
Y1652087D01*
G01X1075156D02*
Y1650118D01*
G01Y1642087D02*
Y1640118D01*
G01Y1645118D02*
Y1647087D01*
G01X1076534Y1651634D02*
Y1650571D01*
G01Y1646634D02*
Y1645571D01*
G01Y1641634D02*
Y1640571D01*
G01X1078306Y1652087D02*
Y1650118D01*
G01Y1647087D02*
Y1645118D01*
G01Y1642087D02*
Y1640118D01*
G01X1078714Y1650118D02*
Y1647087D01*
G01Y1645118D02*
Y1642087D01*
G01X1075994Y1641831D02*
X1076534Y1641634D01*
G01X1075994Y1646831D02*
X1076534Y1646634D01*
G01Y1670571D02*
X1075994Y1670374D01*
G01X1076534Y1665571D02*
X1075994Y1665374D01*
G01X1076534Y1660571D02*
X1075994Y1660374D01*
G01X1076534Y1655571D02*
X1075994Y1655374D01*
G01X1073779Y1655118D02*
Y1657087D01*
G01Y1660118D02*
Y1662087D01*
G01Y1665118D02*
Y1667087D01*
G01Y1670118D02*
Y1672087D01*
G01X1075156D02*
Y1670118D01*
G01Y1667087D02*
Y1665118D01*
G01Y1662087D02*
Y1660118D01*
G01Y1657087D02*
Y1655118D01*
G01X1076534Y1671634D02*
Y1670571D01*
G01Y1666634D02*
Y1665571D01*
G01Y1661634D02*
Y1660571D01*
G01Y1656634D02*
Y1655571D01*
G01X1078306Y1672087D02*
Y1670118D01*
G01Y1667087D02*
Y1665118D01*
G01Y1662087D02*
Y1660118D01*
G01Y1655118D02*
Y1657087D01*
G01X1078714Y1670118D02*
Y1667087D01*
G01Y1665118D02*
Y1662087D01*
G01Y1660118D02*
Y1657087D01*
G01Y1655118D02*
Y1652087D01*
G01X1075994Y1651831D02*
X1076534Y1651634D01*
G01X1075994Y1656831D02*
X1076534Y1656634D01*
G01X1075994Y1661831D02*
X1076534Y1661634D01*
G01X1075994Y1666831D02*
X1076534Y1666634D01*
G01Y1675571D02*
X1075994Y1675374D01*
G01X1074566Y1685433D02*
X1079290Y1690157D01*
G01X1073779Y1675118D02*
Y1677087D01*
G01X1075156D02*
Y1675118D01*
G01X1076534Y1676634D02*
Y1675571D01*
G01X1078306Y1677087D02*
Y1675118D01*
G01X1078714Y1689581D02*
Y1677087D01*
G01Y1675118D02*
Y1672087D01*
G01X1075994Y1671831D02*
X1076534Y1671634D01*
G01X1075994Y1676831D02*
X1076534Y1676634D01*
G01X1041337Y1733129D02*
Y1716535D01*
G01X1065042D02*
X1041337D01*
G01X1056337D02*
X1097204D01*
G01X1080905Y1740652D02*
G03I-4292J0D01*
G01X1041337Y1739719D02*
Y1731535D01*
G01Y1959242D02*
Y1763311D01*
G01X1033463Y1763339D02*
G03X1041337I3937J0D01*
G01Y1739719D02*
G03X1033463I-3937J0D01*
G01Y1763339D02*
G03X1041337I3937J0D01*
G01Y1739719D02*
G03X1033463I-3937J0D01*
G01X1079105Y1957552D02*
G03I-4292J0D01*
G01X1041337Y1959242D02*
G03X1033463I-3937J0D01*
G01X1041337D02*
G03X1033463I-3937J0D01*
G01X1033464Y1988189D02*
G03X1029527Y1992126I-3937J0D01*
G01X1041337D02*
X1097204D01*
G01X1041337Y1982862D02*
Y1992126D01*
G01X1033463Y1982862D02*
G03X1041337I3937J0D01*
G01X1033463D02*
G03X1041337I3937J0D01*
G01X1094847Y-52755D02*
X1095845Y-53706D01*
X1096986Y-54086D01*
X1098127Y-53706D01*
X1099125Y-52565D01*
X1099838Y-50854D01*
X1100123Y-49143D01*
Y-47052D01*
X1099838Y-45341D01*
X1099125Y-43820D01*
X1098269Y-43059D01*
X1097271Y-42679D01*
X1096130Y-43059D01*
X1095275Y-43820D01*
X1094704Y-44960D01*
X1094419Y-46482D01*
X1094704Y-47812D01*
X1095417Y-49143D01*
X1096273Y-49904D01*
X1097271Y-50094D01*
X1098412Y-49714D01*
X1099267Y-48763D01*
X1100123Y-47052D01*
G01X1112204Y648419D02*
Y15000D01*
G01X1097204Y0D02*
G03X1112204Y15000I0J15000D01*
G01X1110804Y463385D02*
X1113604D01*
G01X1110804Y557871D02*
X1113604D01*
G01X1110804Y526375D02*
X1113604D01*
G01X1110804Y494880D02*
X1113604D01*
G01X1110804Y620861D02*
X1113604D01*
G01X1110804Y589366D02*
X1113604D01*
G01X1112204Y656293D02*
G03Y648419I0J-3937D01*
G01Y1378701D02*
Y656293D01*
G01Y1378701D02*
G03X1097204Y1393701I-15000J0D01*
G01Y1716535D02*
G03X1112204Y1731535I0J15000D01*
G01Y1977126D02*
Y1731535D01*
G01Y1935285D02*
Y2035027D01*
G01Y1977126D02*
G03X1097204Y1992126I-15000J0D01*
G01X1094847Y2125001D02*
X1095845Y2124050D01*
X1096986Y2123670D01*
X1098127Y2124050D01*
X1099125Y2125191D01*
X1099838Y2126902D01*
X1100123Y2128613D01*
Y2130704D01*
X1099838Y2132415D01*
X1099125Y2133936D01*
X1098269Y2134697D01*
X1097271Y2135077D01*
X1096130Y2134697D01*
X1095275Y2133936D01*
X1094704Y2132796D01*
X1094419Y2131274D01*
X1094704Y2129944D01*
X1095417Y2128613D01*
X1096273Y2127852D01*
X1097271Y2127662D01*
X1098412Y2128042D01*
X1099267Y2128993D01*
X1100123Y2130704D01*
G01X1206615Y-38936D02*
Y-57873D01*
G01Y2138820D02*
Y2119883D01*
G01X1314288Y-54086D02*
Y-42679D01*
X1312577Y-44960D01*
G01Y-54086D02*
X1315999D01*
G01X1325696Y-42679D02*
X1324555Y-43059D01*
X1323700Y-44010D01*
X1323129Y-45150D01*
X1322701Y-46672D01*
X1322559Y-48383D01*
X1322701Y-50094D01*
X1323129Y-51615D01*
X1323700Y-52755D01*
X1324555Y-53706D01*
X1325696Y-54086D01*
X1326837Y-53706D01*
X1327692Y-52755D01*
X1328263Y-51615D01*
X1328691Y-50094D01*
X1328833Y-48383D01*
X1328691Y-46672D01*
X1328263Y-45150D01*
X1327692Y-44010D01*
X1326837Y-43059D01*
X1325696Y-42679D01*
G01X1270445Y-38936D02*
X1660208D01*
G01X1314288Y2123670D02*
Y2135077D01*
X1312577Y2132796D01*
G01Y2123670D02*
X1315999D01*
G01X1325696Y2135077D02*
X1324555Y2134697D01*
X1323700Y2133746D01*
X1323129Y2132606D01*
X1322701Y2131084D01*
X1322559Y2129373D01*
X1322701Y2127662D01*
X1323129Y2126141D01*
X1323700Y2125001D01*
X1324555Y2124050D01*
X1325696Y2123670D01*
X1326837Y2124050D01*
X1327692Y2125001D01*
X1328263Y2126141D01*
X1328691Y2127662D01*
X1328833Y2129373D01*
X1328691Y2131084D01*
X1328263Y2132606D01*
X1327692Y2133746D01*
X1326837Y2134697D01*
X1325696Y2135077D01*
G01X1426283Y-38936D02*
Y-57873D01*
G01Y2138820D02*
Y2119883D01*
G01X1472059D02*
X1979933D01*
G01X1534715Y-54086D02*
Y-42679D01*
X1533004Y-44960D01*
G01Y-54086D02*
X1536426D01*
G01X1546123D02*
Y-42679D01*
X1544412Y-44960D01*
G01Y-54086D02*
X1547834D01*
G01X1532073Y72515D02*
X1530573Y73515D01*
X1528823Y74182D01*
X1526823D01*
X1524573Y73182D01*
X1522823Y71515D01*
X1521573Y69515D01*
X1520573Y66182D01*
X1520323Y63182D01*
X1520823Y60182D01*
X1521573Y58182D01*
X1523073Y56182D01*
X1524823Y54849D01*
X1526573Y54182D01*
X1528323D01*
X1530073Y54849D01*
X1531573Y55848D01*
X1532823Y57181D01*
G01X1543073Y54182D02*
Y67515D01*
G01Y64849D02*
X1544323Y66182D01*
X1545573Y67182D01*
X1547323Y67515D01*
X1548573Y67182D01*
X1550073Y66182D01*
G01X1562823Y63182D02*
X1570823D01*
X1570073Y65515D01*
X1568823Y66848D01*
X1567073Y67515D01*
X1565323Y67182D01*
X1563823Y66182D01*
X1562823Y63848D01*
X1562323Y61848D01*
Y59849D01*
X1562823Y57848D01*
X1564073Y55848D01*
X1565573Y54515D01*
X1567323Y54182D01*
X1569073Y54849D01*
X1570823Y56848D01*
G01X1591073Y54182D02*
Y67515D01*
G01Y65182D02*
X1590073Y66515D01*
X1588573Y67182D01*
X1586823Y67515D01*
X1585073Y66848D01*
X1583573Y65515D01*
X1582573Y63515D01*
X1582073Y60848D01*
X1582573Y58182D01*
X1583573Y56182D01*
X1585073Y54849D01*
X1586823Y54182D01*
X1588573Y54515D01*
X1590073Y55515D01*
X1591073Y56848D01*
G01X1606573Y74182D02*
Y54182D01*
G01X1603073Y67515D02*
X1610073D01*
G01X1622823Y63182D02*
X1630823D01*
X1630073Y65515D01*
X1628823Y66848D01*
X1627073Y67515D01*
X1625323Y67182D01*
X1623823Y66182D01*
X1622823Y63848D01*
X1622323Y61848D01*
Y59849D01*
X1622823Y57848D01*
X1624073Y55848D01*
X1625573Y54515D01*
X1627323Y54182D01*
X1629073Y54849D01*
X1630823Y56848D01*
G01X1651073Y74182D02*
Y54182D01*
G01Y57181D02*
X1650073Y55515D01*
X1648573Y54515D01*
X1646823Y54182D01*
X1644823Y54849D01*
X1643323Y56515D01*
X1642323Y58515D01*
X1642073Y60848D01*
X1642323Y63182D01*
X1643323Y65182D01*
X1644823Y66848D01*
X1646823Y67515D01*
X1648573Y67182D01*
X1649823Y66515D01*
X1651073Y65182D01*
G01X1504534Y45117D02*
Y90243D01*
G01Y45117D02*
Y-15051D01*
G01X2294239Y45117D02*
X1504534D01*
G01Y-15051D02*
X2256635D01*
G01X1517621Y123090D02*
X1523871Y103090D01*
X1530121Y123090D01*
G01X1540121Y112090D02*
X1548121D01*
X1547371Y114423D01*
X1546121Y115756D01*
X1544371Y116423D01*
X1542621Y116090D01*
X1541121Y115090D01*
X1540121Y112756D01*
X1539621Y110756D01*
Y108757D01*
X1540121Y106756D01*
X1541371Y104756D01*
X1542871Y103423D01*
X1544621Y103090D01*
X1546371Y103757D01*
X1548121Y105756D01*
G01X1560371Y103090D02*
Y116423D01*
G01Y113757D02*
X1561621Y115090D01*
X1562871Y116090D01*
X1564621Y116423D01*
X1565871Y116090D01*
X1567371Y115090D01*
G01X1580121Y105423D02*
X1581371Y104090D01*
X1583121Y103090D01*
X1584621D01*
X1586121Y103757D01*
X1587121Y104756D01*
X1587621Y106089D01*
X1587371Y108090D01*
X1586371Y109090D01*
X1581871Y111090D01*
X1580871Y113424D01*
X1581371Y115090D01*
X1582371Y116090D01*
X1583871Y116423D01*
X1585371Y116090D01*
X1586871Y115090D01*
G01X1603871Y116423D02*
Y103090D01*
G01Y121756D02*
X1603371Y122090D01*
Y122757D01*
X1603871Y123090D01*
X1604371Y122757D01*
Y122090D01*
X1603871Y121756D01*
G01X1623871Y103090D02*
X1622371Y103423D01*
X1620871Y104756D01*
X1619871Y107090D01*
X1619371Y109756D01*
X1619871Y112423D01*
X1620871Y114757D01*
X1622371Y116090D01*
X1623871Y116423D01*
X1625371Y116090D01*
X1626871Y114757D01*
X1627871Y112423D01*
X1628121Y109756D01*
X1627871Y107090D01*
X1626871Y104756D01*
X1625371Y103423D01*
X1623871Y103090D01*
G01X1639621D02*
Y116423D01*
G01Y113090D02*
X1640621Y114757D01*
X1642121Y116090D01*
X1644121Y116423D01*
X1645871Y116090D01*
X1647371Y114757D01*
X1648121Y112423D01*
Y103090D01*
G01X1521573Y147103D02*
Y167103D01*
X1527573D01*
X1529573Y166103D01*
X1531073Y163770D01*
X1531573Y161103D01*
X1531073Y158436D01*
X1529823Y156436D01*
X1527573Y155436D01*
X1521573D01*
G01X1552073Y165436D02*
X1550573Y166436D01*
X1548823Y167103D01*
X1546823D01*
X1544573Y166103D01*
X1542823Y164436D01*
X1541573Y162436D01*
X1540573Y159103D01*
X1540323Y156103D01*
X1540823Y153103D01*
X1541573Y151103D01*
X1543073Y149103D01*
X1544823Y147770D01*
X1546573Y147103D01*
X1548323D01*
X1550073Y147770D01*
X1551573Y148769D01*
X1552823Y150102D01*
G01X1568573Y157770D02*
X1569573Y158770D01*
X1570323Y160436D01*
X1570823Y162770D01*
X1570323Y164770D01*
X1569323Y166103D01*
X1567573Y167103D01*
X1560823D01*
Y147103D01*
X1569073D01*
X1570823Y148436D01*
X1571823Y150436D01*
X1572323Y152770D01*
X1571823Y155103D01*
X1570323Y157103D01*
X1568573Y157770D01*
X1560823D01*
G01X1600823Y147103D02*
Y167103D01*
X1612323Y147103D01*
Y167103D01*
G01X1626573Y147103D02*
X1625073Y147436D01*
X1623573Y148769D01*
X1622573Y151103D01*
X1622073Y153769D01*
X1622573Y156436D01*
X1623573Y158770D01*
X1625073Y160103D01*
X1626573Y160436D01*
X1628073Y160103D01*
X1629573Y158770D01*
X1630573Y156436D01*
X1630823Y153769D01*
X1630573Y151103D01*
X1629573Y148769D01*
X1628073Y147436D01*
X1626573Y147103D01*
G01X1646573Y146436D02*
X1646073Y146770D01*
Y147436D01*
X1646573Y147770D01*
X1647073Y147436D01*
Y146770D01*
X1646573Y146436D01*
G01X1504534Y135369D02*
Y240638D01*
G01Y135369D02*
X2294239D01*
G01X1504534Y90243D02*
Y135369D01*
G01Y90243D02*
X1880585D01*
G01X1530135Y191316D02*
Y218875D01*
X1539091Y195909D01*
X1548048Y218875D01*
Y191316D01*
G01X1566650D02*
X1564584Y191775D01*
X1562517Y193612D01*
X1561138Y196827D01*
X1560450Y200502D01*
X1561138Y204177D01*
X1562517Y207392D01*
X1564584Y209229D01*
X1566650Y209688D01*
X1568717Y209229D01*
X1570784Y207392D01*
X1572162Y204177D01*
X1572507Y200502D01*
X1572162Y196827D01*
X1570784Y193612D01*
X1568717Y191775D01*
X1566650Y191316D01*
G01X1600410Y218875D02*
Y191316D01*
G01Y195449D02*
X1599032Y193153D01*
X1596965Y191775D01*
X1594554Y191316D01*
X1591798Y192234D01*
X1589731Y194531D01*
X1588353Y197287D01*
X1588009Y200502D01*
X1588353Y203717D01*
X1589731Y206474D01*
X1591798Y208770D01*
X1594554Y209688D01*
X1596965Y209229D01*
X1598688Y208310D01*
X1600410Y206474D01*
G01X1616601Y203717D02*
X1627625D01*
X1626591Y206933D01*
X1624869Y208770D01*
X1622458Y209688D01*
X1620046Y209229D01*
X1617979Y207851D01*
X1616601Y204636D01*
X1615912Y201880D01*
Y199124D01*
X1616601Y196368D01*
X1618323Y193612D01*
X1620391Y191775D01*
X1622802Y191316D01*
X1625214Y192234D01*
X1627625Y194990D01*
G01X1649327Y191316D02*
Y218875D01*
G01X1504534Y180495D02*
X2294239D01*
G01X1504534Y240638D02*
X2294239D01*
G01X1534715Y2123670D02*
Y2135077D01*
X1533004Y2132796D01*
G01Y2123670D02*
X1536426D01*
G01X1546123D02*
Y2135077D01*
X1544412Y2132796D01*
G01Y2123670D02*
X1547834D01*
G01X1645006Y-38936D02*
Y-57873D01*
G01X1660208Y-38936D02*
X2310643D01*
G01X1585895Y27174D02*
X1591406Y-4322D01*
X1597706Y27174D01*
X1604005Y-4322D01*
X1609517Y27174D01*
G01X1629202Y16675D02*
Y-4322D01*
G01Y25074D02*
X1628414Y25599D01*
Y26649D01*
X1629202Y27174D01*
X1629990Y26649D01*
Y25599D01*
X1629202Y25074D01*
G01X1654793Y-648D02*
X1656761Y-2748D01*
X1659517Y-4322D01*
X1661879D01*
X1664242Y-3272D01*
X1665816Y-1698D01*
X1666603Y401D01*
X1666210Y3552D01*
X1664635Y5127D01*
X1657548Y8276D01*
X1655974Y11951D01*
X1656761Y14575D01*
X1658336Y16150D01*
X1660698Y16675D01*
X1663060Y16150D01*
X1665422Y14575D01*
G01X1692194Y27174D02*
Y-4322D01*
G01X1686682Y16675D02*
X1697706D01*
G01X1718178Y-4322D02*
Y16675D01*
G01Y12476D02*
X1720146Y14575D01*
X1722115Y16150D01*
X1724871Y16675D01*
X1726839Y16150D01*
X1729202Y14575D01*
G01X1755186Y-4322D02*
X1752824Y-3797D01*
X1750462Y-1698D01*
X1748886Y1977D01*
X1748099Y6176D01*
X1748886Y10376D01*
X1750462Y14051D01*
X1752824Y16150D01*
X1755186Y16675D01*
X1757548Y16150D01*
X1759910Y14051D01*
X1761485Y10376D01*
X1761879Y6176D01*
X1761485Y1977D01*
X1759910Y-1698D01*
X1757548Y-3797D01*
X1755186Y-4322D01*
G01X1779989D02*
Y16675D01*
G01Y11426D02*
X1781564Y14051D01*
X1783926Y16150D01*
X1787076Y16675D01*
X1789831Y16150D01*
X1792194Y14051D01*
X1793375Y10376D01*
Y-4322D01*
G01X1858335Y24549D02*
X1855973Y26124D01*
X1853218Y27174D01*
X1850068D01*
X1846524Y25599D01*
X1843769Y22974D01*
X1841800Y19825D01*
X1840225Y14575D01*
X1839831Y9851D01*
X1840619Y5127D01*
X1841800Y1977D01*
X1844162Y-1173D01*
X1846918Y-3272D01*
X1849674Y-4322D01*
X1852430D01*
X1855186Y-3272D01*
X1857548Y-1698D01*
X1859517Y401D01*
G01X1881170Y-4322D02*
X1878808Y-3797D01*
X1876446Y-1698D01*
X1874870Y1977D01*
X1874083Y6176D01*
X1874870Y10376D01*
X1876446Y14051D01*
X1878808Y16150D01*
X1881170Y16675D01*
X1883532Y16150D01*
X1885894Y14051D01*
X1887469Y10376D01*
X1887863Y6176D01*
X1887469Y1977D01*
X1885894Y-1698D01*
X1883532Y-3797D01*
X1881170Y-4322D01*
G01X1907154D02*
Y16675D01*
G01Y12476D02*
X1909122Y14575D01*
X1911091Y16150D01*
X1913847Y16675D01*
X1915815Y16150D01*
X1918178Y14575D01*
G01X1937075Y-14820D02*
Y16675D01*
G01Y11951D02*
X1939044Y14575D01*
X1941012Y16150D01*
X1944162Y16675D01*
X1946918Y16150D01*
X1949674Y13526D01*
X1950855Y9851D01*
X1951249Y6176D01*
X1950855Y2502D01*
X1949674Y-1173D01*
X1947311Y-3272D01*
X1944162Y-4322D01*
X1941406Y-3797D01*
X1938650Y-2223D01*
X1937075Y-123D01*
G01X1975658Y-4322D02*
X1973296Y-3797D01*
X1970934Y-1698D01*
X1969358Y1977D01*
X1968571Y6176D01*
X1969358Y10376D01*
X1970934Y14051D01*
X1973296Y16150D01*
X1975658Y16675D01*
X1978020Y16150D01*
X1980382Y14051D01*
X1981957Y10376D01*
X1982351Y6176D01*
X1981957Y1977D01*
X1980382Y-1698D01*
X1978020Y-3797D01*
X1975658Y-4322D01*
G01X2001642D02*
Y16675D01*
G01Y12476D02*
X2003610Y14575D01*
X2005579Y16150D01*
X2008335Y16675D01*
X2010303Y16150D01*
X2012666Y14575D01*
G01X2045737Y-4322D02*
Y16675D01*
G01Y13001D02*
X2044162Y15100D01*
X2041799Y16150D01*
X2039044Y16675D01*
X2036288Y15625D01*
X2033926Y13526D01*
X2032350Y10376D01*
X2031563Y6176D01*
X2032350Y1977D01*
X2033926Y-1173D01*
X2036288Y-3272D01*
X2039044Y-4322D01*
X2041799Y-3797D01*
X2044162Y-2223D01*
X2045737Y-123D01*
G01X2070146Y27174D02*
Y-4322D01*
G01X2064634Y16675D02*
X2075658D01*
G01X2101642D02*
Y-4322D01*
G01Y25074D02*
X2100854Y25599D01*
Y26649D01*
X2101642Y27174D01*
X2102430Y26649D01*
Y25599D01*
X2101642Y25074D01*
G01X2133138Y-4322D02*
X2130776Y-3797D01*
X2128414Y-1698D01*
X2126838Y1977D01*
X2126051Y6176D01*
X2126838Y10376D01*
X2128414Y14051D01*
X2130776Y16150D01*
X2133138Y16675D01*
X2135500Y16150D01*
X2137862Y14051D01*
X2139437Y10376D01*
X2139831Y6176D01*
X2139437Y1977D01*
X2137862Y-1698D01*
X2135500Y-3797D01*
X2133138Y-4322D01*
G01X2157941D02*
Y16675D01*
G01Y11426D02*
X2159516Y14051D01*
X2161878Y16150D01*
X2165028Y16675D01*
X2167783Y16150D01*
X2170146Y14051D01*
X2171327Y10376D01*
Y-4322D01*
G01X1645952Y2138820D02*
Y2119883D01*
G01X1752490Y-54086D02*
Y-42679D01*
X1750779Y-44960D01*
G01Y-54086D02*
X1754201D01*
G01X1761189Y-44580D02*
X1762044Y-43440D01*
X1763042Y-42869D01*
X1764183Y-42679D01*
X1765609Y-43059D01*
X1766607Y-44010D01*
X1766893Y-45150D01*
X1766750Y-46291D01*
X1766180Y-47242D01*
X1763328Y-49143D01*
X1762044Y-50474D01*
X1761189Y-52375D01*
X1760903Y-54086D01*
X1766893D01*
G01X1724027Y56157D02*
Y76157D01*
X1730277D01*
X1732277Y75157D01*
X1733527Y73824D01*
X1734027Y71157D01*
X1733527Y68490D01*
X1732027Y66824D01*
X1730277Y65823D01*
X1724027D01*
G01X1730277D02*
X1734027Y56157D01*
G01X1745277Y65157D02*
X1753277D01*
X1752527Y67490D01*
X1751277Y68823D01*
X1749527Y69490D01*
X1747777Y69157D01*
X1746277Y68157D01*
X1745277Y65823D01*
X1744777Y63823D01*
Y61824D01*
X1745277Y59823D01*
X1746527Y57823D01*
X1748027Y56490D01*
X1749777Y56157D01*
X1751527Y56824D01*
X1753277Y58823D01*
G01X1764527Y56157D02*
Y76157D01*
G01Y66157D02*
X1765777Y68157D01*
X1767277Y69157D01*
X1768777Y69490D01*
X1771027Y68823D01*
X1772527Y67490D01*
X1773527Y65157D01*
Y62490D01*
X1773027Y59823D01*
X1772027Y57823D01*
X1770277Y56490D01*
X1768777Y56157D01*
X1767277Y56490D01*
X1765777Y57490D01*
X1764527Y59156D01*
G01X1785277Y65157D02*
X1793277D01*
X1792527Y67490D01*
X1791277Y68823D01*
X1789527Y69490D01*
X1787777Y69157D01*
X1786277Y68157D01*
X1785277Y65823D01*
X1784777Y63823D01*
Y61824D01*
X1785277Y59823D01*
X1786527Y57823D01*
X1788027Y56490D01*
X1789777Y56157D01*
X1791527Y56824D01*
X1793277Y58823D01*
G01X1813027Y67824D02*
X1811277Y69157D01*
X1809777Y69490D01*
X1807777Y68823D01*
X1806277Y67490D01*
X1805277Y65157D01*
X1805027Y62823D01*
X1805277Y60490D01*
X1806277Y58490D01*
X1807777Y56824D01*
X1809777Y56157D01*
X1811527Y56824D01*
X1813027Y58157D01*
G01X1833027Y67824D02*
X1831277Y69157D01*
X1829777Y69490D01*
X1827777Y68823D01*
X1826277Y67490D01*
X1825277Y65157D01*
X1825027Y62823D01*
X1825277Y60490D01*
X1826277Y58490D01*
X1827777Y56824D01*
X1829777Y56157D01*
X1831527Y56824D01*
X1833027Y58157D01*
G01X1853527Y56157D02*
Y69490D01*
G01Y67157D02*
X1852527Y68490D01*
X1851027Y69157D01*
X1849277Y69490D01*
X1847527Y68823D01*
X1846027Y67490D01*
X1845027Y65490D01*
X1844527Y62823D01*
X1845027Y60157D01*
X1846027Y58157D01*
X1847527Y56824D01*
X1849277Y56157D01*
X1851027Y56490D01*
X1852527Y57490D01*
X1853527Y58823D01*
G01X1692559Y45117D02*
Y240638D01*
G01X1745054Y100529D02*
X1746304Y99196D01*
X1748054Y98196D01*
X1749554D01*
X1751054Y98863D01*
X1752054Y99862D01*
X1752554Y101195D01*
X1752304Y103196D01*
X1751304Y104196D01*
X1746804Y106196D01*
X1745804Y108530D01*
X1746304Y110196D01*
X1747304Y111196D01*
X1748804Y111529D01*
X1750304Y111196D01*
X1751804Y110196D01*
G01X1773304Y98196D02*
Y111529D01*
G01Y109196D02*
X1772304Y110529D01*
X1770804Y111196D01*
X1769054Y111529D01*
X1767304Y110862D01*
X1765804Y109529D01*
X1764804Y107529D01*
X1764304Y104862D01*
X1764804Y102196D01*
X1765804Y100196D01*
X1767304Y98863D01*
X1769054Y98196D01*
X1770804Y98529D01*
X1772304Y99529D01*
X1773304Y100862D01*
G01X1734774Y149077D02*
Y169077D01*
X1731774Y165077D01*
G01Y149077D02*
X1737774D01*
G01X1757774D02*
Y169077D01*
X1748524Y154744D01*
X1761024D01*
G01X1769274Y152076D02*
X1770774Y150410D01*
X1772524Y149410D01*
X1774774Y149077D01*
X1777024Y149744D01*
X1778774Y151077D01*
X1780024Y153410D01*
X1780274Y156077D01*
X1779774Y158743D01*
X1778524Y160410D01*
X1776774Y161743D01*
X1775024Y162077D01*
X1773274Y161743D01*
X1771024Y160410D01*
X1771774Y169077D01*
X1778524D01*
G01X1797774Y149077D02*
Y169077D01*
X1788524Y154744D01*
X1801024D01*
G01X1809274Y152076D02*
X1810774Y150410D01*
X1812524Y149410D01*
X1814774Y149077D01*
X1817024Y149744D01*
X1818774Y151077D01*
X1820024Y153410D01*
X1820274Y156077D01*
X1819774Y158743D01*
X1818524Y160410D01*
X1816774Y161743D01*
X1815024Y162077D01*
X1813274Y161743D01*
X1811024Y160410D01*
X1811774Y169077D01*
X1818524D01*
G01X1718223Y195023D02*
Y222582D01*
G01X1732692D02*
Y195023D01*
G01Y208802D02*
X1718223D01*
G01X1753016Y195023D02*
X1750950Y195482D01*
X1748883Y197319D01*
X1747504Y200534D01*
X1746816Y204209D01*
X1747504Y207884D01*
X1748883Y211099D01*
X1750950Y212936D01*
X1753016Y213395D01*
X1755083Y212936D01*
X1757150Y211099D01*
X1758528Y207884D01*
X1758873Y204209D01*
X1758528Y200534D01*
X1757150Y197319D01*
X1755083Y195482D01*
X1753016Y195023D01*
G01X1774719D02*
Y213395D01*
G01Y208802D02*
X1776097Y211099D01*
X1778164Y212936D01*
X1780920Y213395D01*
X1783331Y212936D01*
X1785398Y211099D01*
X1786432Y207884D01*
Y195023D01*
G01X1802967Y207424D02*
X1813991D01*
X1812957Y210640D01*
X1811235Y212477D01*
X1808824Y213395D01*
X1806412Y212936D01*
X1804345Y211558D01*
X1802967Y208343D01*
X1802278Y205587D01*
Y202831D01*
X1802967Y200075D01*
X1804689Y197319D01*
X1806757Y195482D01*
X1809168Y195023D01*
X1811580Y195941D01*
X1813991Y198697D01*
G01X1828459Y186755D02*
X1830526Y185837D01*
X1833282Y186755D01*
X1835004Y188592D01*
X1836383Y190889D01*
X1838449Y198238D01*
X1842928Y213395D01*
G01X1831904D02*
X1838449Y198238D01*
G01X1893567Y209721D02*
X1894945Y211099D01*
X1895979Y213395D01*
X1896668Y216611D01*
X1895979Y219367D01*
X1894601Y221204D01*
X1892189Y222582D01*
X1882888D01*
Y195023D01*
X1894257D01*
X1896668Y196860D01*
X1898046Y199616D01*
X1898735Y202831D01*
X1898046Y206046D01*
X1895979Y208802D01*
X1893567Y209721D01*
X1882888D01*
G01X1924571Y195023D02*
Y213395D01*
G01Y210181D02*
X1923193Y212017D01*
X1921126Y212936D01*
X1918715Y213395D01*
X1916304Y212477D01*
X1914237Y210640D01*
X1912858Y207884D01*
X1912170Y204209D01*
X1912858Y200534D01*
X1914237Y197778D01*
X1916304Y195941D01*
X1918715Y195023D01*
X1921126Y195482D01*
X1923193Y196860D01*
X1924571Y198697D01*
G01X1952130Y222582D02*
Y195023D01*
G01Y199156D02*
X1950752Y196860D01*
X1948685Y195482D01*
X1946274Y195023D01*
X1943518Y195941D01*
X1941451Y198238D01*
X1940073Y200994D01*
X1939729Y204209D01*
X1940073Y207424D01*
X1941451Y210181D01*
X1943518Y212477D01*
X1946274Y213395D01*
X1948685Y212936D01*
X1950408Y212017D01*
X1952130Y210181D01*
G01X1968666Y188133D02*
X1971077Y186296D01*
X1973833Y185837D01*
X1976244Y186296D01*
X1978311Y188592D01*
X1979689Y191808D01*
Y213395D01*
G01Y209721D02*
X1978311Y211558D01*
X1976244Y212936D01*
X1973833Y213395D01*
X1971077Y212477D01*
X1969355Y210640D01*
X1967976Y207424D01*
X1967288Y204209D01*
X1967632Y201453D01*
X1969010Y198238D01*
X1971077Y195941D01*
X1973833Y195023D01*
X1975900Y195482D01*
X1978311Y197319D01*
X1979689Y199156D01*
G01X1995880Y207424D02*
X2006904D01*
X2005870Y210640D01*
X2004148Y212477D01*
X2001737Y213395D01*
X1999325Y212936D01*
X1997258Y211558D01*
X1995880Y208343D01*
X1995191Y205587D01*
Y202831D01*
X1995880Y200075D01*
X1997602Y197319D01*
X1999670Y195482D01*
X2002081Y195023D01*
X2004493Y195941D01*
X2006904Y198697D01*
G01X2023784Y195023D02*
Y213395D01*
G01Y209721D02*
X2025506Y211558D01*
X2027229Y212936D01*
X2029640Y213395D01*
X2031362Y212936D01*
X2033429Y211558D01*
G01X2076146Y195023D02*
Y222582D01*
X2083035D01*
X2085791Y221204D01*
X2087858Y219367D01*
X2089581Y216611D01*
X2090959Y213395D01*
X2091303Y208802D01*
X2090959Y204209D01*
X2089581Y200994D01*
X2087858Y198238D01*
X2085791Y196401D01*
X2083035Y195023D01*
X2076146D01*
G01X2104394D02*
Y222582D01*
X2112661D01*
X2115417Y221204D01*
X2117484Y217989D01*
X2118173Y214314D01*
X2117484Y210640D01*
X2115762Y207884D01*
X2112661Y206505D01*
X2104394D01*
G01X2141598Y209721D02*
X2142976Y211099D01*
X2144010Y213395D01*
X2144699Y216611D01*
X2144010Y219367D01*
X2142632Y221204D01*
X2140220Y222582D01*
X2130919D01*
Y195023D01*
X2142288D01*
X2144699Y196860D01*
X2146077Y199616D01*
X2146766Y202831D01*
X2146077Y206046D01*
X2144010Y208802D01*
X2141598Y209721D01*
X2130919D01*
G01X2187071Y222582D02*
Y195023D01*
X2200850D01*
G01X2221519D02*
X2219453Y195482D01*
X2217386Y197319D01*
X2216007Y200534D01*
X2215319Y204209D01*
X2216007Y207884D01*
X2217386Y211099D01*
X2219453Y212936D01*
X2221519Y213395D01*
X2223586Y212936D01*
X2225653Y211099D01*
X2227031Y207884D01*
X2227376Y204209D01*
X2227031Y200534D01*
X2225653Y197319D01*
X2223586Y195482D01*
X2221519Y195023D01*
G01X2240466Y213395D02*
X2244600Y195023D01*
X2249078Y213395D01*
X2253557Y195023D01*
X2257691Y213395D01*
G01X2297307Y222582D02*
Y195023D01*
X2311086D01*
G01X2331755D02*
X2329689Y195482D01*
X2327622Y197319D01*
X2326243Y200534D01*
X2325555Y204209D01*
X2326243Y207884D01*
X2327622Y211099D01*
X2329689Y212936D01*
X2331755Y213395D01*
X2333822Y212936D01*
X2335889Y211099D01*
X2337267Y207884D01*
X2337612Y204209D01*
X2337267Y200534D01*
X2335889Y197319D01*
X2333822Y195482D01*
X2331755Y195023D01*
G01X2354147Y198238D02*
X2355869Y196401D01*
X2358281Y195023D01*
X2360348D01*
X2362415Y195941D01*
X2363793Y197319D01*
X2364482Y199156D01*
X2364137Y201913D01*
X2362760Y203291D01*
X2356558Y206046D01*
X2355181Y209262D01*
X2355869Y211558D01*
X2357248Y212936D01*
X2359314Y213395D01*
X2361381Y212936D01*
X2363448Y211558D01*
G01X2381706Y198238D02*
X2383428Y196401D01*
X2385840Y195023D01*
X2387907D01*
X2389974Y195941D01*
X2391352Y197319D01*
X2392041Y199156D01*
X2391696Y201913D01*
X2390319Y203291D01*
X2384117Y206046D01*
X2382740Y209262D01*
X2383428Y211558D01*
X2384807Y212936D01*
X2386873Y213395D01*
X2388940Y212936D01*
X2391007Y211558D01*
G01X1752490Y2123670D02*
Y2135077D01*
X1750779Y2132796D01*
G01Y2123670D02*
X1754201D01*
G01X1761189Y2133176D02*
X1762044Y2134316D01*
X1763042Y2134887D01*
X1764183Y2135077D01*
X1765609Y2134697D01*
X1766607Y2133746D01*
X1766893Y2132606D01*
X1766750Y2131465D01*
X1766180Y2130514D01*
X1763328Y2128613D01*
X1762044Y2127282D01*
X1761189Y2125381D01*
X1760903Y2123670D01*
X1766893D01*
G01X1865622Y-38936D02*
Y-57873D01*
G01X1881684Y135561D02*
Y45431D01*
G01X1897630Y122890D02*
Y102890D01*
G01X1891880Y122890D02*
X1903380D01*
G01X1913380Y102890D02*
Y122890D01*
G01Y113224D02*
X1914630Y114890D01*
X1915880Y115890D01*
X1917880Y116223D01*
X1919380Y115890D01*
X1921130Y114557D01*
X1921880Y112556D01*
Y102890D01*
G01X1937630Y116223D02*
Y102890D01*
G01Y121556D02*
X1937130Y121890D01*
Y122557D01*
X1937630Y122890D01*
X1938130Y122557D01*
Y121890D01*
X1937630Y121556D01*
G01X1961630Y114557D02*
X1959880Y115890D01*
X1958380Y116223D01*
X1956380Y115556D01*
X1954880Y114223D01*
X1953880Y111890D01*
X1953630Y109556D01*
X1953880Y107223D01*
X1954880Y105223D01*
X1956380Y103557D01*
X1958380Y102890D01*
X1960130Y103557D01*
X1961630Y104890D01*
G01X1973380Y102890D02*
Y122890D01*
G01X1981380Y116223D02*
X1973380Y108557D01*
G01X1976630Y111557D02*
X1981880Y102890D01*
G01X1993380D02*
Y116223D01*
G01Y112890D02*
X1994380Y114557D01*
X1995880Y115890D01*
X1997880Y116223D01*
X1999630Y115890D01*
X2001130Y114557D01*
X2001880Y112223D01*
Y102890D01*
G01X2013880Y111890D02*
X2021880D01*
X2021130Y114223D01*
X2019880Y115556D01*
X2018130Y116223D01*
X2016380Y115890D01*
X2014880Y114890D01*
X2013880Y112556D01*
X2013380Y110556D01*
Y108557D01*
X2013880Y106556D01*
X2015130Y104556D01*
X2016630Y103223D01*
X2018380Y102890D01*
X2020130Y103557D01*
X2021880Y105556D01*
G01X2033880Y105223D02*
X2035130Y103890D01*
X2036880Y102890D01*
X2038380D01*
X2039880Y103557D01*
X2040880Y104556D01*
X2041380Y105889D01*
X2041130Y107890D01*
X2040130Y108890D01*
X2035630Y110890D01*
X2034630Y113224D01*
X2035130Y114890D01*
X2036130Y115890D01*
X2037630Y116223D01*
X2039130Y115890D01*
X2040630Y114890D01*
G01X2053880Y105223D02*
X2055130Y103890D01*
X2056880Y102890D01*
X2058380D01*
X2059880Y103557D01*
X2060880Y104556D01*
X2061380Y105889D01*
X2061130Y107890D01*
X2060130Y108890D01*
X2055630Y110890D01*
X2054630Y113224D01*
X2055130Y114890D01*
X2056130Y115890D01*
X2057630Y116223D01*
X2059130Y115890D01*
X2060630Y114890D01*
G01X1880585Y90243D02*
X2294239D01*
G01X1865622Y2138820D02*
Y2119883D01*
G01X1972160Y-54086D02*
Y-42679D01*
X1970449Y-44960D01*
G01Y-54086D02*
X1973871D01*
G01X1980431Y-51805D02*
X1981286Y-53136D01*
X1982427Y-53896D01*
X1983711Y-54086D01*
X1984852Y-53896D01*
X1985992Y-52946D01*
X1986705Y-51805D01*
X1986848Y-50664D01*
X1986563Y-49333D01*
X1985564Y-48383D01*
X1984566Y-48002D01*
X1983283D01*
G01X1984566D02*
X1985422Y-47432D01*
X1986135Y-46482D01*
X1986420Y-45341D01*
X1986135Y-44200D01*
X1985422Y-43250D01*
X1984138Y-42679D01*
X1982855Y-42869D01*
X1981572Y-43630D01*
G01X1934704Y54182D02*
Y74182D01*
X1939704D01*
X1941704Y73182D01*
X1943204Y71849D01*
X1944454Y69849D01*
X1945454Y67515D01*
X1945704Y64182D01*
X1945454Y60848D01*
X1944454Y58515D01*
X1943204Y56515D01*
X1941704Y55182D01*
X1939704Y54182D01*
X1934704D01*
G01X1964704D02*
Y67515D01*
G01Y65182D02*
X1963704Y66515D01*
X1962204Y67182D01*
X1960454Y67515D01*
X1958704Y66848D01*
X1957204Y65515D01*
X1956204Y63515D01*
X1955704Y60848D01*
X1956204Y58182D01*
X1957204Y56182D01*
X1958704Y54849D01*
X1960454Y54182D01*
X1962204Y54515D01*
X1963704Y55515D01*
X1964704Y56848D01*
G01X1980204Y74182D02*
Y54182D01*
G01X1976704Y67515D02*
X1983704D01*
G01X1996454Y63182D02*
X2004454D01*
X2003704Y65515D01*
X2002454Y66848D01*
X2000704Y67515D01*
X1998954Y67182D01*
X1997454Y66182D01*
X1996454Y63848D01*
X1995954Y61848D01*
Y59849D01*
X1996454Y57848D01*
X1997704Y55848D01*
X1999204Y54515D01*
X2000954Y54182D01*
X2002704Y54849D01*
X2004454Y56848D01*
G01X1972160Y2123670D02*
Y2135077D01*
X1970449Y2132796D01*
G01Y2123670D02*
X1973871D01*
G01X1980431Y2125951D02*
X1981286Y2124620D01*
X1982427Y2123860D01*
X1983711Y2123670D01*
X1984852Y2123860D01*
X1985992Y2124810D01*
X1986705Y2125951D01*
X1986848Y2127092D01*
X1986563Y2128423D01*
X1985564Y2129373D01*
X1984566Y2129754D01*
X1983283D01*
G01X1984566D02*
X1985422Y2130324D01*
X1986135Y2131274D01*
X1986420Y2132415D01*
X1986135Y2133556D01*
X1985422Y2134506D01*
X1984138Y2135077D01*
X1982855Y2134887D01*
X1981572Y2134126D01*
G01X1979933Y2119883D02*
X2310641D01*
G01X2065282Y135561D02*
Y45431D01*
G01X2085291Y-38936D02*
Y-57873D01*
G01X2106829Y74884D02*
X2108329Y76883D01*
X2110079Y77884D01*
X2112079Y78217D01*
X2114579Y77550D01*
X2116329Y75884D01*
X2116829Y73884D01*
X2116579Y71883D01*
X2115579Y70217D01*
X2110579Y66884D01*
X2108329Y64550D01*
X2106829Y61216D01*
X2106329Y58217D01*
X2116829D01*
G01X2131579Y78217D02*
X2129579Y77550D01*
X2128079Y75884D01*
X2127079Y73884D01*
X2126329Y71217D01*
X2126079Y68217D01*
X2126329Y65217D01*
X2127079Y62550D01*
X2128079Y60550D01*
X2129579Y58884D01*
X2131579Y58217D01*
X2133579Y58884D01*
X2135079Y60550D01*
X2136079Y62550D01*
X2136829Y65217D01*
X2137079Y68217D01*
X2136829Y71217D01*
X2136079Y73884D01*
X2135079Y75884D01*
X2133579Y77550D01*
X2131579Y78217D01*
G01X2151579Y58217D02*
Y78217D01*
X2148579Y74217D01*
G01Y58217D02*
X2154579D01*
G01X2174579D02*
Y78217D01*
X2165329Y63884D01*
X2177829D01*
G01X2188329Y64883D02*
X2194829D01*
G01X2211579Y78217D02*
X2209579Y77550D01*
X2208079Y75884D01*
X2207079Y73884D01*
X2206329Y71217D01*
X2206079Y68217D01*
X2206329Y65217D01*
X2207079Y62550D01*
X2208079Y60550D01*
X2209579Y58884D01*
X2211579Y58217D01*
X2213579Y58884D01*
X2215079Y60550D01*
X2216079Y62550D01*
X2216829Y65217D01*
X2217079Y68217D01*
X2216829Y71217D01*
X2216079Y73884D01*
X2215079Y75884D01*
X2213579Y77550D01*
X2211579Y78217D01*
G01X2231579Y58217D02*
X2233329Y58550D01*
X2235329Y59550D01*
X2236579Y61216D01*
X2237079Y63550D01*
X2236579Y65883D01*
X2235079Y67883D01*
X2232829Y68884D01*
X2230329D01*
X2228829Y69550D01*
X2227579Y71217D01*
X2227079Y73550D01*
X2227829Y75884D01*
X2229579Y77550D01*
X2231579Y78217D01*
X2233579Y77550D01*
X2235329Y75884D01*
X2236079Y73550D01*
X2235579Y71217D01*
X2234329Y69550D01*
X2232829Y68884D01*
X2230329D01*
X2228079Y67883D01*
X2226579Y65883D01*
X2226079Y63550D01*
X2226579Y61216D01*
X2227829Y59550D01*
X2229829Y58550D01*
X2231579Y58217D01*
G01X2248329Y64883D02*
X2254829D01*
G01X2271579Y78217D02*
X2269579Y77550D01*
X2268079Y75884D01*
X2267079Y73884D01*
X2266329Y71217D01*
X2266079Y68217D01*
X2266329Y65217D01*
X2267079Y62550D01*
X2268079Y60550D01*
X2269579Y58884D01*
X2271579Y58217D01*
X2273579Y58884D01*
X2275079Y60550D01*
X2276079Y62550D01*
X2276829Y65217D01*
X2277079Y68217D01*
X2276829Y71217D01*
X2276079Y73884D01*
X2275079Y75884D01*
X2273579Y77550D01*
X2271579Y78217D01*
G01X2291579Y58217D02*
Y78217D01*
X2288579Y74217D01*
G01Y58217D02*
X2294579D01*
G01X2106829Y121531D02*
X2108329Y123530D01*
X2110079Y124531D01*
X2112079Y124864D01*
X2114579Y124197D01*
X2116329Y122531D01*
X2116829Y120531D01*
X2116579Y118530D01*
X2115579Y116864D01*
X2110579Y113531D01*
X2108329Y111197D01*
X2106829Y107863D01*
X2106329Y104864D01*
X2116829D01*
G01X2131579Y104197D02*
X2131079Y104531D01*
Y105197D01*
X2131579Y105531D01*
X2132079Y105197D01*
Y104531D01*
X2131579Y104197D01*
G01X2151579Y104864D02*
Y124864D01*
X2148579Y120864D01*
G01Y104864D02*
X2154579D01*
G01X2166829Y113197D02*
X2168579Y115531D01*
X2170079Y116864D01*
X2172079Y117530D01*
X2173829Y116864D01*
X2175079Y115531D01*
X2176079Y113531D01*
X2176329Y111197D01*
X2176079Y109197D01*
X2175079Y107197D01*
X2173579Y105531D01*
X2171829Y104864D01*
X2169829Y105531D01*
X2168079Y107530D01*
X2167079Y110531D01*
X2166829Y113864D01*
X2167329Y118197D01*
X2168079Y120531D01*
X2169329Y122864D01*
X2171079Y124531D01*
X2172829Y124864D01*
X2174579Y124197D01*
X2175829Y122531D01*
G01X2204079Y104864D02*
Y118197D01*
G01Y114530D02*
X2204829Y116197D01*
X2206079Y117530D01*
X2207829Y118197D01*
X2209579Y117530D01*
X2210829Y116197D01*
X2211579Y114530D01*
Y104864D01*
G01Y114530D02*
X2212329Y116197D01*
X2213579Y117530D01*
X2215329Y118197D01*
X2217079Y117530D01*
X2218329Y116197D01*
X2219079Y114197D01*
Y104864D01*
G01X2224079D02*
Y118197D01*
G01Y114530D02*
X2224829Y116197D01*
X2226079Y117530D01*
X2227829Y118197D01*
X2229579Y117530D01*
X2230829Y116197D01*
X2231579Y114530D01*
Y104864D01*
G01Y114530D02*
X2232329Y116197D01*
X2233579Y117530D01*
X2235329Y118197D01*
X2237079Y117530D01*
X2238329Y116197D01*
X2239079Y114197D01*
Y104864D01*
G01X2085291Y2138820D02*
Y2119883D01*
G01X2191830Y-54086D02*
Y-42679D01*
X2190119Y-44960D01*
G01Y-54086D02*
X2193541D01*
G01X2204949D02*
Y-42679D01*
X2199673Y-50854D01*
X2206803D01*
G01X2191830Y2123670D02*
Y2135077D01*
X2190119Y2132796D01*
G01Y2123670D02*
X2193541D01*
G01X2204949D02*
Y2135077D01*
X2199673Y2126902D01*
X2206803D01*
G01X2329578Y2138820D02*
Y-57873D01*
G01X2310641Y2119883D02*
Y-38936D01*
G01X2310643Y105749D02*
Y-38936D01*
G01X2317559Y65605D02*
X2318272Y64464D01*
X2319127Y63704D01*
X2320126Y63324D01*
X2321267Y63704D01*
X2322122Y64464D01*
X2322978Y65605D01*
X2323263Y67126D01*
Y74731D01*
G01X2294239Y-15051D02*
Y182267D01*
G01X2256635Y-15051D02*
X2294239D01*
G01X2310641Y176946D02*
X2329578D01*
G01X2294239Y182267D02*
Y240638D01*
G01X2318700Y290613D02*
X2322122D01*
G01X2320411D02*
Y279206D01*
G01X2318700D02*
X2322122D01*
G01X2310641Y392828D02*
X2329578D01*
G01X2317416Y494898D02*
Y506305D01*
G01X2323406D02*
Y494898D01*
G01Y500601D02*
X2317416D01*
G01X2310641Y608710D02*
X2329578D01*
G01X2321267Y716483D02*
X2324119D01*
Y713061D01*
X2323263Y711920D01*
X2322265Y711160D01*
X2320839Y710780D01*
X2319413Y711160D01*
X2318415Y711920D01*
X2317559Y713061D01*
X2316988Y714392D01*
X2316703Y715913D01*
Y717244D01*
X2316988Y718384D01*
X2317559Y719716D01*
X2318415Y720856D01*
X2319270Y721616D01*
X2320411Y722187D01*
X2321409D01*
X2322550Y721807D01*
X2323406Y721046D01*
G01X2310641Y824592D02*
X2329578D01*
G01X2317323Y926852D02*
Y938259D01*
X2322741D01*
G01X2320745Y932746D02*
X2317323D01*
G01X2310641Y1040474D02*
X2329578D01*
G01X2323263Y1142923D02*
X2317559D01*
Y1154330D01*
X2323263D01*
G01X2320981Y1148817D02*
X2317559D01*
G01X2310641Y1256355D02*
X2329578D01*
G01X2317274Y1358615D02*
Y1370022D01*
X2320126D01*
X2321267Y1369451D01*
X2322122Y1368691D01*
X2322835Y1367551D01*
X2323406Y1366219D01*
X2323548Y1364318D01*
X2323406Y1362417D01*
X2322835Y1361086D01*
X2322122Y1359946D01*
X2321267Y1359185D01*
X2320126Y1358615D01*
X2317274D01*
G01X2310641Y1472237D02*
X2329578D01*
G01X2323548Y1585143D02*
X2322693Y1585714D01*
X2321695Y1586094D01*
X2320554D01*
X2319270Y1585523D01*
X2318272Y1584573D01*
X2317559Y1583432D01*
X2316988Y1581531D01*
X2316846Y1579820D01*
X2317131Y1578109D01*
X2317559Y1576968D01*
X2318415Y1575827D01*
X2319413Y1575067D01*
X2320411Y1574687D01*
X2321409D01*
X2322407Y1575067D01*
X2323263Y1575637D01*
X2323976Y1576398D01*
G01X2310641Y1688119D02*
X2329578D01*
G01X2321552Y1796463D02*
X2322122Y1797033D01*
X2322550Y1797983D01*
X2322835Y1799315D01*
X2322550Y1800455D01*
X2321980Y1801215D01*
X2320981Y1801786D01*
X2317131D01*
Y1790379D01*
X2321837D01*
X2322835Y1791139D01*
X2323406Y1792280D01*
X2323691Y1793611D01*
X2323406Y1794942D01*
X2322550Y1796082D01*
X2321552Y1796463D01*
X2317131D01*
G01X2310452Y1904001D02*
X2329389D01*
G01X2316846Y2006261D02*
X2320411Y2017668D01*
X2323976Y2006261D01*
G01X2322693Y2010253D02*
X2318129D01*
G01X2310641Y2119883D02*
Y2025395D01*
M02*
